(kicad_pcb (version 20211014) (generator pcbnew)

  (general
    (thickness 1.6)
  )

  (paper "A4")
  (title_block
    (title "SA800U (Snapdragon 845) Baseboard")
    (date "2023-10-19")
    (rev "1.0.3")
    (company "Antmicro Ltd.")
    (comment 1 "www.antmicro.com")
  )

  (layers
    (0 "F.Cu" signal)
    (1 "In1.Cu" power)
    (2 "In2.Cu" signal)
    (3 "In3.Cu" signal)
    (4 "In4.Cu" power)
    (31 "B.Cu" signal)
    (32 "B.Adhes" user "B.Adhesive")
    (33 "F.Adhes" user "F.Adhesive")
    (34 "B.Paste" user)
    (35 "F.Paste" user)
    (36 "B.SilkS" user "B.Silkscreen")
    (37 "F.SilkS" user "F.Silkscreen")
    (38 "B.Mask" user)
    (39 "F.Mask" user)
    (40 "Dwgs.User" user "User.Drawings")
    (41 "Cmts.User" user "User.Comments")
    (42 "Eco1.User" user "User.Eco1")
    (43 "Eco2.User" user "User.Eco2")
    (44 "Edge.Cuts" user)
    (45 "Margin" user)
    (46 "B.CrtYd" user "B.Courtyard")
    (47 "F.CrtYd" user "F.Courtyard")
    (48 "B.Fab" user)
    (49 "F.Fab" user)
  )

  (setup
    (stackup
      (layer "F.SilkS" (type "Top Silk Screen"))
      (layer "F.Paste" (type "Top Solder Paste"))
      (layer "F.Mask" (type "Top Solder Mask") (thickness 0.01))
      (layer "F.Cu" (type "copper") (thickness 0.035))
      (layer "dielectric 1" (type "core") (thickness 0.274) (material "FR4") (epsilon_r 4.5) (loss_tangent 0.02))
      (layer "In1.Cu" (type "copper") (thickness 0.035))
      (layer "dielectric 2" (type "prepreg") (thickness 0.274) (material "FR4") (epsilon_r 4.5) (loss_tangent 0.02))
      (layer "In2.Cu" (type "copper") (thickness 0.035))
      (layer "dielectric 3" (type "core") (thickness 0.274) (material "FR4") (epsilon_r 4.5) (loss_tangent 0.02))
      (layer "In3.Cu" (type "copper") (thickness 0.035))
      (layer "dielectric 4" (type "prepreg") (thickness 0.274) (material "FR4") (epsilon_r 4.5) (loss_tangent 0.02))
      (layer "In4.Cu" (type "copper") (thickness 0.035))
      (layer "dielectric 5" (type "core") (thickness 0.274) (material "FR4") (epsilon_r 4.5) (loss_tangent 0.02))
      (layer "B.Cu" (type "copper") (thickness 0.035))
      (layer "B.Mask" (type "Bottom Solder Mask") (thickness 0.01))
      (layer "B.Paste" (type "Bottom Solder Paste"))
      (layer "B.SilkS" (type "Bottom Silk Screen"))
      (copper_finish "None")
      (dielectric_constraints yes)
    )
    (pad_to_mask_clearance 0)
    (aux_axis_origin 55 82)
    (pcbplotparams
      (layerselection 0x00010fc_ffffffff)
      (disableapertmacros false)
      (usegerberextensions false)
      (usegerberattributes true)
      (usegerberadvancedattributes true)
      (creategerberjobfile true)
      (svguseinch false)
      (svgprecision 6)
      (excludeedgelayer true)
      (plotframeref false)
      (viasonmask false)
      (mode 1)
      (useauxorigin false)
      (hpglpennumber 1)
      (hpglpenspeed 20)
      (hpglpendiameter 15.000000)
      (dxfpolygonmode true)
      (dxfimperialunits true)
      (dxfusepcbnewfont true)
      (psnegative false)
      (psa4output false)
      (plotreference true)
      (plotvalue true)
      (plotinvisibletext false)
      (sketchpadsonfab false)
      (subtractmaskfromsilk false)
      (outputformat 1)
      (mirror false)
      (drillshape 1)
      (scaleselection 1)
      (outputdirectory "")
    )
  )

  (net 0 "")
  (net 1 "GND")
  (net 2 "PAIR78")
  (net 3 "PAIR45")
  (net 4 "Earth")
  (net 5 "PAIR36")
  (net 6 "PAIR12")
  (net 7 "GNDD")
  (net 8 "PCIE1_RX_P")
  (net 9 "PCIE1_RX_N")
  (net 10 "EDP_AUX_N")
  (net 11 "EDP_AUX_P")
  (net 12 "CSI0_CLK_N")
  (net 13 "CSI0_CLK_P")
  (net 14 "CAM0_PWDN")
  (net 15 "CAM0_RST")
  (net 16 "CAM1_PWDN")
  (net 17 "CSI1_LN3_P")
  (net 18 "CSI1_LN3_N")
  (net 19 "CSI1_LN2_P")
  (net 20 "CSI1_LN2_N")
  (net 21 "CSI1_LN1_P")
  (net 22 "CSI1_LN1_N")
  (net 23 "CSI1_LN0_N")
  (net 24 "CSI1_LN0_P")
  (net 25 "CSI1_CLK_P")
  (net 26 "CSI1_CLK_N")
  (net 27 "CSI0_LN3_N")
  (net 28 "CSI0_LN3_P")
  (net 29 "CSI0_LN2_P")
  (net 30 "CSI0_LN2_N")
  (net 31 "CSI0_LN1_N")
  (net 32 "CSI0_LN1_P")
  (net 33 "CSI0_LN0_N")
  (net 34 "CSI0_LN0_P")
  (net 35 "LT9611_GPIO5")
  (net 36 "LT9611_RST")
  (net 37 "Net-(R2-Pad2)")
  (net 38 "Net-(R3-Pad2)")
  (net 39 "Net-(R4-Pad2)")
  (net 40 "I2C4_SDA")
  (net 41 "I2C4_SCL")
  (net 42 "CCI0_I2C_SCL")
  (net 43 "CCI0_I2C_SDA")
  (net 44 "CCI1_I2C_SCL")
  (net 45 "CCI1_I2C_SDA")
  (net 46 "PCIE1_REFCLK_N")
  (net 47 "PCIE1_REFCLK_P")
  (net 48 "PCIE1_TX_N")
  (net 49 "PCIE1_TX_P")
  (net 50 "DSI1_LN1_P")
  (net 51 "DSI1_LN0_N")
  (net 52 "DSI1_LN1_N")
  (net 53 "DSI1_LN2_N")
  (net 54 "DSI1_LN3_N")
  (net 55 "DSI1_CLK_N")
  (net 56 "DSI1_CLK_P")
  (net 57 "DSI1_LN2_P")
  (net 58 "DSI1_LN3_P")
  (net 59 "I2S1_WS")
  (net 60 "I2S1_MCLK")
  (net 61 "I2S1_SCK")
  (net 62 "I2S1_DATA0")
  (net 63 "Net-(C16-Pad1)")
  (net 64 "USB1_SS_TX0_P")
  (net 65 "USB1_SS_TX0_N")
  (net 66 "USB_VBUS")
  (net 67 "USB1_SS_RX1_N")
  (net 68 "USB1_SS_RX1_P")
  (net 69 "USB1_SS_RX0_P")
  (net 70 "USB1_SS_RX0_N")
  (net 71 "USB1_SS_TX1_N")
  (net 72 "USB1_SS_TX1_P")
  (net 73 "/PoE/VDD_POE")
  (net 74 "VDD")
  (net 75 "Net-(D16-Pad2)")
  (net 76 "/PoE/SMPS_CTRL")
  (net 77 "Net-(J1-Pad15)")
  (net 78 "Net-(J1-Pad17)")
  (net 79 "USB2C_HS_D_N")
  (net 80 "USB2C_HS_D_P")
  (net 81 "TP_I2C_SCL")
  (net 82 "TP_I2C_SDA")
  (net 83 "DSI0_LN1_N")
  (net 84 "DSI0_LN1_P")
  (net 85 "DSI0_CLK_P")
  (net 86 "DSI0_CLK_N")
  (net 87 "DSI0_LN0_N")
  (net 88 "DSI0_LN0_P")
  (net 89 "DSI0_LN3_P")
  (net 90 "DSI0_LN3_N")
  (net 91 "DSI0_LN2_N")
  (net 92 "DSI0_LN2_P")
  (net 93 "SBU_SW_OE")
  (net 94 "HOME_KEY")
  (net 95 "PWRKEY")
  (net 96 "VOL_UP")
  (net 97 "VOL_DOWN")
  (net 98 "SBU_SW_SEL")
  (net 99 "USB2_SINK")
  (net 100 "USB2_FAULT")
  (net 101 "USB2_EN")
  (net 102 "USB2_SS_TX_N")
  (net 103 "USB2_SS_TX_P")
  (net 104 "USB2_SS_RX_N")
  (net 105 "USB2_SS_RX_P")
  (net 106 "SD_LDO21A")
  (net 107 "/USB-PD/PD_VBUS")
  (net 108 "PCIE0_TX_P")
  (net 109 "/M2/C_PCIE0_TX0_P")
  (net 110 "PCIE0_TX_N")
  (net 111 "/M2/C_PCIE0_TX0_N")
  (net 112 "SD_DET")
  (net 113 "SD_DATA3")
  (net 114 "SD_DATA2")
  (net 115 "SD_CMD")
  (net 116 "SD_CLK")
  (net 117 "SD_DATA1")
  (net 118 "SD_DATA0")
  (net 119 "PCIE0_WAKE_N")
  (net 120 "PCIE0_CLKREQ_N")
  (net 121 "M2_ALERT")
  (net 122 "PCIE0_REFCLK_P")
  (net 123 "PCIE0_RX_P")
  (net 124 "PCIE0_RST_N")
  (net 125 "PCIE0_RX_N")
  (net 126 "PCIE0_REFCLK_N")
  (net 127 "1V8_DBG")
  (net 128 "Net-(R109-Pad2)")
  (net 129 "DBG_RXD")
  (net 130 "DBG_TXD")
  (net 131 "3V3_SYS")
  (net 132 "VREG_S4A_1V8")
  (net 133 "5V_SYS")
  (net 134 "1V8_SYS")
  (net 135 "/PoE/VSS_POE")
  (net 136 "5V_POE")
  (net 137 "3V8_SYS")
  (net 138 "1V2_SYS")
  (net 139 "LVS1A_1V8")
  (net 140 "/USB-PD/VREG_1V2")
  (net 141 "/USB-PD/VREG_2V7")
  (net 142 "PD_VDD")
  (net 143 "/USB-PD/PD_CC1")
  (net 144 "/USB-PD/PD_CC2")
  (net 145 "/PoE/DEN")
  (net 146 "/PoE/CLS")
  (net 147 "/PoE/CDB")
  (net 148 "/LCM/TP_I2C_SCL_3V3")
  (net 149 "/LCM/TP_I2C_SDA_3V3")
  (net 150 "I2C10_SCL")
  (net 151 "I2C10_SDA")
  (net 152 "/PSU/AUX_VDD")
  (net 153 "/PoE/TRIM")
  (net 154 "Net-(Q3-Pad1)")
  (net 155 "Net-(Q4-Pad1)")
  (net 156 "/PSU/BYPASS_EN")
  (net 157 "/PSU/VS1")
  (net 158 "/PSU/VS2")
  (net 159 "/PSU/VS3")
  (net 160 "Net-(R154-Pad2)")
  (net 161 "PCIE1_WAKE_N")
  (net 162 "PCIE1_CLKREQ_N")
  (net 163 "PCIE1_RST_N")
  (net 164 "/PSU/5V_DC_DC_ENABLE")
  (net 165 "STUSB4500_AB_SIDE")
  (net 166 "STUSB4500_GPIO")
  (net 167 "STUSB4500_ATTACH")
  (net 168 "STUSB4500_ALERT")
  (net 169 "/USB-PD/STUSB4500_PWR_OK2")
  (net 170 "/USB-PD/STUSB4500_PWR_OK3")
  (net 171 "Net-(R135-Pad2)")
  (net 172 "Net-(R139-Pad2)")
  (net 173 "Net-(R141-Pad2)")
  (net 174 "/PoE/APD")
  (net 175 "Net-(D29-Pad1)")
  (net 176 "DSI1_LN0_P")
  (net 177 "/Ethernet Controller/ETH_3V3")
  (net 178 "/Ethernet Controller/REG_1V0")
  (net 179 "/Ethernet Controller/PCIE1_RX_C_P")
  (net 180 "/Ethernet Controller/PCIE1_RX_C_N")
  (net 181 "/Ethernet Controller/ETH_1V0")
  (net 182 "/Ethernet Controller/XTAL1")
  (net 183 "/Ethernet Controller/XTAL2")
  (net 184 "/HDMI converter/LT9611_VCC33_IO")
  (net 185 "/HDMI converter/LT9611_VCC33_RX")
  (net 186 "/HDMI converter/LT9611_RST_N")
  (net 187 "/HDMI converter/LT9611_VCC33_TX")
  (net 188 "/HDMI converter/LT9611_VDD12")
  (net 189 "/HDMI converter/LT9611_VCC12_RX")
  (net 190 "/HDMI converter/XTALO")
  (net 191 "/HDMI converter/LT9611_VCC12_TX")
  (net 192 "/HDMI converter/XTALI")
  (net 193 "/HDMI converter/HDMI_TX2_P")
  (net 194 "/HDMI converter/HDMI_TX_D2_P")
  (net 195 "/HDMI converter/HDMI_TX2_N")
  (net 196 "/HDMI converter/HDMI_TX_D2_N")
  (net 197 "/HDMI converter/HDMI_TX_D1_P")
  (net 198 "/HDMI converter/HDMI_TX1_P")
  (net 199 "/HDMI converter/HDMI_TX_D1_N")
  (net 200 "/HDMI converter/HDMI_TX1_N")
  (net 201 "/HDMI converter/HDMI_TX0_P")
  (net 202 "/HDMI converter/HDMI_TX_D0_P")
  (net 203 "/HDMI converter/HDMI_TX0_N")
  (net 204 "/HDMI converter/HDMI_TX_D0_N")
  (net 205 "/HDMI converter/HDMI_TX_CLK_P")
  (net 206 "/HDMI converter/HDMI_CLK_P")
  (net 207 "/HDMI converter/HDMI_TX_CLK_N")
  (net 208 "/HDMI converter/HDMI_CLK_N")
  (net 209 "/HDMI converter/VCOM")
  (net 210 "/USB-C Interface /USB2_5V")
  (net 211 "/USB-C Interface /USB2C_TX1_C_N")
  (net 212 "/USB-C Interface /USB2C_TX1_N")
  (net 213 "/USB-C Interface /USB2C_RX2_C_P")
  (net 214 "/USB-C Interface /USB2C_RX2_P")
  (net 215 "/USB-C Interface /USB2C_TX1_C_P")
  (net 216 "/USB-C Interface /USB2C_TX1_P")
  (net 217 "/USB-C Interface /USB2C_RX2_C_N")
  (net 218 "/USB-C Interface /USB2C_RX2_N")
  (net 219 "/USB-C Interface /USB2C_RX1_N")
  (net 220 "/USB-C Interface /USB2C_RX1_C_N")
  (net 221 "/USB-C Interface /USB2C_TX2_P")
  (net 222 "/USB-C Interface /USB2C_TX2_C_P")
  (net 223 "/USB-C Interface /USB2C_RX1_P")
  (net 224 "/USB-C Interface /USB2C_RX1_C_P")
  (net 225 "/USB-C Interface /USB2C_TX2_N")
  (net 226 "/USB-C Interface /USB2C_TX2_C_N")
  (net 227 "/Other Interfaces/SD_VDD_R")
  (net 228 "/USB-C Interface /5V0_DBG")
  (net 229 "/USB-C Interface /DBG_USB_D_N")
  (net 230 "/USB-C Interface /DBG_USB_D_P")
  (net 231 "/Camera Interface/3V3_CAM")
  (net 232 "/HDMI converter/HDMI_SCL")
  (net 233 "/HDMI converter/HDMI_CEC")
  (net 234 "/HDMI converter/HDMI_DETECT")
  (net 235 "/HDMI converter/HDMI_SDA")
  (net 236 "/HDMI converter/HDMI_TX0_CONN_N")
  (net 237 "/HDMI converter/HDMI_CLK_CONN_P")
  (net 238 "/HDMI converter/HDMI_CLK_CONN_N")
  (net 239 "/HDMI converter/HDMI_TX0_CONN_P")
  (net 240 "/HDMI converter/HDMI_TX2_CONN_N")
  (net 241 "/HDMI converter/HDMI_TX1_CONN_P")
  (net 242 "/HDMI converter/HDMI_TX1_CONN_N")
  (net 243 "/HDMI converter/HDMI_TX2_CONN_P")
  (net 244 "/HDMI converter/5V_HDMI_FB_D")
  (net 245 "/HDMI converter/5V_HDMI")
  (net 246 "/Other Interfaces/SD_DET_R")
  (net 247 "/Other Interfaces/SD_DATA2_R")
  (net 248 "/Other Interfaces/SD_CMD_R")
  (net 249 "/Other Interfaces/SD_DATA3_R")
  (net 250 "/Other Interfaces/SD_CLK_R")
  (net 251 "/Other Interfaces/SD_DATA1_R")
  (net 252 "/Other Interfaces/SD_DATA0_R")
  (net 253 "/USB-C Interface /DBG_VBUS")
  (net 254 "/Ethernet Controller/LAN0_MDI0_N")
  (net 255 "/Ethernet Controller/LAN0_MDI0_P")
  (net 256 "/Ethernet Controller/LAN0_MDI1_N")
  (net 257 "/Ethernet Controller/LAN0_MDI1_P")
  (net 258 "/Ethernet Controller/LAN0_MDI2_N")
  (net 259 "/Ethernet Controller/LAN0_MDI2_P")
  (net 260 "/Ethernet Controller/LAN0_MDI3_N")
  (net 261 "/Ethernet Controller/LAN0_MDI3_P")
  (net 262 "/Ethernet Controller/ETH_LED0")
  (net 263 "/Ethernet Controller/ETH_LED2")
  (net 264 "/USB-C Interface /USB2_CC2")
  (net 265 "/USB-C Interface /USB2_CC1")
  (net 266 "/Camera Interface/CSI0_LN0_FFC_P")
  (net 267 "/Camera Interface/CSI0_LN0_FFC_N")
  (net 268 "/Camera Interface/CSI1_LN0_FFC_P")
  (net 269 "/Camera Interface/CSI1_LN0_FFC_N")
  (net 270 "/Camera Interface/CSI0_LN1_FFC_P")
  (net 271 "/Camera Interface/CSI0_LN1_FFC_N")
  (net 272 "/Camera Interface/CSI1_LN1_FFC_P")
  (net 273 "/Camera Interface/CSI1_LN1_FFC_N")
  (net 274 "/Camera Interface/CSI1_CLK_FFC_P")
  (net 275 "/Camera Interface/CSI1_CLK_FFC_N")
  (net 276 "/Camera Interface/CSI0_LN2_FFC_P")
  (net 277 "/Camera Interface/CSI0_LN2_FFC_N")
  (net 278 "/Camera Interface/CSI1_LN2_FFC_P")
  (net 279 "/Camera Interface/CSI1_LN2_FFC_N")
  (net 280 "/Camera Interface/CSI0_LN3_FFC_P")
  (net 281 "/Camera Interface/CSI0_LN3_FFC_N")
  (net 282 "/Camera Interface/CSI1_LN3_FFC_P")
  (net 283 "/Camera Interface/CSI1_LN3_FFC_N")
  (net 284 "/HDMI converter/LT9611_INTO_GPIO5")
  (net 285 "/HDMI converter/LT9611_CEC")
  (net 286 "/Ethernet Controller/ETH_ISOLATEB")
  (net 287 "/HDMI converter/LT9611_SCL")
  (net 288 "/HDMI converter/LT9611_SDA")
  (net 289 "/HDMI converter/I2C_ADDR")
  (net 290 "/USB-C Interface /USB2_CC_SELECT")
  (net 291 "/USB-C Interface /USB2_SINK_5V")
  (net 292 "/USB-C Interface /USB2_FAULT_5V")
  (net 293 "/Camera Interface/CCI1_I2C_SCL_3V3")
  (net 294 "/Camera Interface/CCI0_I2C_SCL_3V3")
  (net 295 "/Camera Interface/CCI1_I2C_SDA_3V3")
  (net 296 "/Camera Interface/CCI0_I2C_SDA_3V3")
  (net 297 "/HDMI converter/LT9611_I2S_D0_SPDIF")
  (net 298 "/HDMI converter/LT9611_I2S_WS")
  (net 299 "/HDMI converter/LT9611_I2S_SCLK")
  (net 300 "/HDMI converter/LT9611_I2S_MCLK")
  (net 301 "/USB-C Interface /USB2_EN_5V")
  (net 302 "/USB-C Interface /USB1C_TX0_C_P")
  (net 303 "/USB-C Interface /USB1C_TX0_C_N")
  (net 304 "/USB-C Interface /USB1C_RX1_C_N")
  (net 305 "/USB-C Interface /USB1C_RX1_C_P")
  (net 306 "/USB-C Interface /USB1C_TX1_C_N")
  (net 307 "/USB-C Interface /USB1C_TX1_C_P")
  (net 308 "/USB-C Interface /USB1C_RX0_C_P")
  (net 309 "/LCM/DSI_CLK_L_P")
  (net 310 "/LCM/DSI_CLK_L_N")
  (net 311 "/LCM/DSI_LN0_L_P")
  (net 312 "/LCM/DSI_LN0_L_N")
  (net 313 "/LCM/DSI_LN1_L_P")
  (net 314 "/LCM/DSI_LN1_L_N")
  (net 315 "/LCM/DSI_LN2_L_P")
  (net 316 "/LCM/DSI_LN2_L_N")
  (net 317 "/LCM/DSI_LN3_L_P")
  (net 318 "/LCM/DSI_LN3_L_N")
  (net 319 "3V3_SYS_EN")
  (net 320 "1V2_SYS_EN")
  (net 321 "USB1_D_P")
  (net 322 "USB1_D_N")
  (net 323 "/USB-C Interface /USB1C_RX0_C_N")
  (net 324 "/Camera Interface/CSI0_CLK_FFC_P")
  (net 325 "/Camera Interface/CSI0_CLK_FFC_N")
  (net 326 "USB_CC1")
  (net 327 "USB_CC2")
  (net 328 "/USB-C Interface /USB_SBU_NP_N")
  (net 329 "/USB-C Interface /USB_SBU_NP_P")
  (net 330 "/USB-C Interface /USB1_SBU_N")
  (net 331 "/USB-C Interface /USB1_SBU_P")
  (net 332 "/USB-PD/ALERT")
  (net 333 "/USB-PD/AB_SIDE")
  (net 334 "/USB-PD/GPIO")
  (net 335 "/USB-PD/ATTACH")
  (net 336 "/SoM/VRTC")
  (net 337 "/Other Interfaces/I2C10_SCL_3V3")
  (net 338 "/Other Interfaces/I2C10_SDA_3V3")
  (net 339 "/PSU/AUX_VALID")
  (net 340 "/PSU/POE_VALID")
  (net 341 "/PSU/USB_PD_VALID")
  (net 342 "Net-(D28-Pad2)")
  (net 343 "/SoM/VOL_DOWN_R")
  (net 344 "/SoM/HOME_KEY_R")
  (net 345 "/SoM/VOL_UP_R")
  (net 346 "/SoM/PWR_R")
  (net 347 "Net-(Q13-Pad3)")
  (net 348 "Net-(Q14-Pad3)")
  (net 349 "/SoM/BOOT")
  (net 350 "/SoM/USER_LED")
  (net 351 "USB_PD_DISABLE")
  (net 352 "Net-(C67-Pad1)")
  (net 353 "Net-(C108-Pad1)")
  (net 354 "/PSU/G1")
  (net 355 "/PSU/G2")
  (net 356 "Net-(C132-Pad1)")
  (net 357 "Net-(C132-Pad2)")
  (net 358 "Net-(C133-Pad1)")
  (net 359 "Net-(C133-Pad2)")
  (net 360 "Net-(C134-Pad2)")
  (net 361 "Net-(C134-Pad1)")
  (net 362 "Net-(C138-Pad1)")
  (net 363 "Net-(C138-Pad2)")
  (net 364 "Net-(C153-Pad1)")
  (net 365 "Net-(C155-Pad2)")
  (net 366 "Net-(D1-PadK)")
  (net 367 "/PSU/G3")
  (net 368 "unconnected-(D7-Pad1)")
  (net 369 "unconnected-(D7-Pad5)")
  (net 370 "unconnected-(D12-Pad4)")
  (net 371 "Net-(D14-Pad2)")
  (net 372 "Net-(D15-Pad2)")
  (net 373 "Net-(D21-Pad1)")
  (net 374 "Net-(D21-Pad2)")
  (net 375 "Net-(D24-Pad2)")
  (net 376 "Net-(D25-Pad2)")
  (net 377 "Net-(D26-Pad2)")
  (net 378 "Net-(D27-Pad1)")
  (net 379 "Net-(D29-Pad2)")
  (net 380 "Net-(D32-Pad1)")
  (net 381 "Net-(D36-Pad6)")
  (net 382 "Net-(D36-Pad5)")
  (net 383 "Net-(D36-Pad4)")
  (net 384 "Net-(IC2-Pad7)")
  (net 385 "Net-(Q5-Pad3)")
  (net 386 "Net-(Q6-Pad3)")
  (net 387 "Net-(Q7-Pad3)")
  (net 388 "Net-(Q8-Pad3)")
  (net 389 "Net-(Q10-Pad3)")
  (net 390 "Net-(Q15-Pad1)")
  (net 391 "Net-(Q17-Pad4)")
  (net 392 "Net-(R1-Pad2)")
  (net 393 "Net-(R11-Pad1)")
  (net 394 "Net-(R22-Pad1)")
  (net 395 "Net-(R27-Pad1)")
  (net 396 "Net-(R59-Pad1)")
  (net 397 "Net-(R69-Pad1)")
  (net 398 "Net-(R70-Pad1)")
  (net 399 "Net-(R105-Pad2)")
  (net 400 "Net-(R106-Pad2)")
  (net 401 "Net-(R108-Pad2)")
  (net 402 "Net-(R112-Pad2)")
  (net 403 "Net-(R113-Pad2)")
  (net 404 "Net-(R117-Pad1)")
  (net 405 "Net-(R123-Pad2)")
  (net 406 "Net-(R125-Pad2)")
  (net 407 "Net-(R127-Pad2)")
  (net 408 "Net-(R128-Pad2)")
  (net 409 "Net-(R131-Pad2)")
  (net 410 "Net-(R137-Pad2)")
  (net 411 "Net-(R155-Pad2)")
  (net 412 "unconnected-(D12-Pad5)")
  (net 413 "unconnected-(IC1-Pad4)")
  (net 414 "unconnected-(J2-Pad2)")
  (net 415 "Net-(TP42-Pad1)")
  (net 416 "Net-(TP43-Pad1)")
  (net 417 "Net-(R175-Pad2)")
  (net 418 "/SoM/USB_BOOT")
  (net 419 "/SoM/AUTO_ON_N")
  (net 420 "Net-(R176-Pad1)")
  (net 421 "Net-(R177-Pad1)")
  (net 422 "Net-(R178-Pad1)")
  (net 423 "Net-(R179-Pad1)")
  (net 424 "/SoM/VBAT_SOM")
  (net 425 "unconnected-(J4-PadB8)")
  (net 426 "unconnected-(J4-PadA8)")
  (net 427 "unconnected-(J5-PadB11)")
  (net 428 "unconnected-(J5-PadB10)")
  (net 429 "unconnected-(J5-PadB8)")
  (net 430 "unconnected-(J5-PadB5)")
  (net 431 "unconnected-(J5-PadB3)")
  (net 432 "unconnected-(J5-PadB2)")
  (net 433 "unconnected-(J5-PadA11)")
  (net 434 "unconnected-(J5-PadA10)")
  (net 435 "unconnected-(J5-PadA8)")
  (net 436 "unconnected-(J5-PadA5)")
  (net 437 "unconnected-(J5-PadA3)")
  (net 438 "unconnected-(J5-PadA2)")
  (net 439 "unconnected-(J7-Pad46)")
  (net 440 "unconnected-(J7-Pad45)")
  (net 441 "unconnected-(J7-Pad44)")
  (net 442 "unconnected-(J7-Pad43)")
  (net 443 "unconnected-(J7-Pad38)")
  (net 444 "unconnected-(J7-Pad37)")
  (net 445 "unconnected-(J7-Pad36)")
  (net 446 "unconnected-(J7-Pad35)")
  (net 447 "unconnected-(J7-Pad31)")
  (net 448 "unconnected-(J7-Pad17)")
  (net 449 "unconnected-(J7-Pad16)")
  (net 450 "unconnected-(J7-Pad14)")
  (net 451 "unconnected-(J7-Pad13)")
  (net 452 "unconnected-(J11-PadB11)")
  (net 453 "unconnected-(J11-PadB10)")
  (net 454 "unconnected-(J11-PadB8)")
  (net 455 "unconnected-(J11-PadB7)")
  (net 456 "unconnected-(J11-PadB6)")
  (net 457 "unconnected-(J11-PadB3)")
  (net 458 "unconnected-(J11-PadB2)")
  (net 459 "unconnected-(J11-PadA11)")
  (net 460 "unconnected-(J11-PadA10)")
  (net 461 "unconnected-(J11-PadA8)")
  (net 462 "unconnected-(J11-PadA7)")
  (net 463 "unconnected-(J11-PadA6)")
  (net 464 "unconnected-(J11-PadA3)")
  (net 465 "unconnected-(J11-PadA2)")
  (net 466 "/USB-PD/VS_DISCH")
  (net 467 "/USB-PD/EN_SINK")
  (net 468 "/USB-PD/DISCH")
  (net 469 "unconnected-(U1-Pad26)")
  (net 470 "unconnected-(U3-Pad64)")
  (net 471 "unconnected-(U3-Pad63)")
  (net 472 "unconnected-(U3-Pad62)")
  (net 473 "unconnected-(U3-Pad61)")
  (net 474 "unconnected-(U3-Pad60)")
  (net 475 "unconnected-(U3-Pad59)")
  (net 476 "unconnected-(U3-Pad58)")
  (net 477 "unconnected-(U3-Pad57)")
  (net 478 "unconnected-(U3-Pad33)")
  (net 479 "unconnected-(U3-Pad32)")
  (net 480 "unconnected-(U3-Pad22)")
  (net 481 "unconnected-(U3-Pad21)")
  (net 482 "unconnected-(U3-Pad20)")
  (net 483 "unconnected-(U3-Pad2)")
  (net 484 "unconnected-(U3-Pad1)")
  (net 485 "unconnected-(U5-Pad32)")
  (net 486 "unconnected-(U5-Pad31)")
  (net 487 "unconnected-(U5-Pad29)")
  (net 488 "unconnected-(U5-Pad28)")
  (net 489 "unconnected-(U5-Pad27)")
  (net 490 "unconnected-(U5-Pad25)")
  (net 491 "unconnected-(U5-Pad23)")
  (net 492 "unconnected-(U5-Pad22)")
  (net 493 "unconnected-(U5-Pad21)")
  (net 494 "unconnected-(U5-Pad18)")
  (net 495 "unconnected-(U5-Pad13)")
  (net 496 "unconnected-(U5-Pad12)")
  (net 497 "unconnected-(U5-Pad11)")
  (net 498 "unconnected-(U5-Pad10)")
  (net 499 "unconnected-(U5-Pad9)")
  (net 500 "unconnected-(U5-Pad8)")
  (net 501 "unconnected-(U5-Pad7)")
  (net 502 "unconnected-(U5-Pad6)")
  (net 503 "unconnected-(U5-Pad5)")
  (net 504 "unconnected-(U5-Pad3)")
  (net 505 "unconnected-(U8-Pad7)")
  (net 506 "unconnected-(U8-Pad5)")
  (net 507 "unconnected-(U11-Pad2_172)")
  (net 508 "unconnected-(U11-Pad2_171)")
  (net 509 "unconnected-(U11-Pad2_156)")
  (net 510 "unconnected-(U11-Pad2_154)")
  (net 511 "unconnected-(U11-Pad2_153)")
  (net 512 "unconnected-(U11-Pad2_152)")
  (net 513 "unconnected-(U11-Pad2_151)")
  (net 514 "LDO19A_3V0")
  (net 515 "unconnected-(U11-Pad2_149)")
  (net 516 "LVS2A_1V8")
  (net 517 "unconnected-(U11-Pad2_147)")
  (net 518 "unconnected-(U11-Pad2_146)")
  (net 519 "unconnected-(U11-Pad2_144)")
  (net 520 "unconnected-(U11-Pad2_142)")
  (net 521 "unconnected-(U11-Pad2_140)")
  (net 522 "unconnected-(U11-Pad2_138)")
  (net 523 "unconnected-(U11-Pad2_101)")
  (net 524 "unconnected-(U11-Pad2_99)")
  (net 525 "/SoM/ETH_3V3_EN")
  (net 526 "unconnected-(U11-Pad2_96)")
  (net 527 "/SoM/CAM3_TRIGGER_IN")
  (net 528 "unconnected-(U11-Pad2_94)")
  (net 529 "/SoM/CODEC_INT2")
  (net 530 "unconnected-(U11-Pad2_92)")
  (net 531 "/SoM/CODEC_INT1")
  (net 532 "unconnected-(U11-Pad2_90)")
  (net 533 "/SoM/CODEC_SPI_MISO")
  (net 534 "unconnected-(U11-Pad2_88)")
  (net 535 "unconnected-(U11-Pad2_86)")
  (net 536 "unconnected-(U11-Pad2_85)")
  (net 537 "unconnected-(U11-Pad2_84)")
  (net 538 "unconnected-(U11-Pad2_82)")
  (net 539 "unconnected-(U11-Pad2_78)")
  (net 540 "/SoM/I2S3_SCK")
  (net 541 "unconnected-(U11-Pad2_71)")
  (net 542 "/SoM/I2S3_DATA0")
  (net 543 "unconnected-(U11-Pad2_67)")
  (net 544 "unconnected-(U11-Pad2_65)")
  (net 545 "/SoM/I2S3_WS")
  (net 546 "unconnected-(U11-Pad2_62)")
  (net 547 "/SoM/I2S2_DATA1")
  (net 548 "unconnected-(U11-Pad2_60)")
  (net 549 "/SoM/I2S2_DATA0")
  (net 550 "unconnected-(U11-Pad2_58)")
  (net 551 "/SoM/I2S2_SCK")
  (net 552 "unconnected-(U11-Pad2_56)")
  (net 553 "/SoM/I2S2_WS")
  (net 554 "unconnected-(U11-Pad2_52)")
  (net 555 "/SoM/SLIMBUS_CLK")
  (net 556 "/SoM/TP_RST")
  (net 557 "/SoM/SLIMBUS_DATA1")
  (net 558 "/SoM/TP_INT")
  (net 559 "/SoM/SLIMBUS_DATA0")
  (net 560 "/SoM/WCD_CLK")
  (net 561 "/SoM/SSC_I2C1_SCL")
  (net 562 "/SoM/SSC_I2C1_SDA")
  (net 563 "unconnected-(U11-Pad1_172)")
  (net 564 "unconnected-(U11-Pad1_171)")
  (net 565 "unconnected-(U11-Pad1_154)")
  (net 566 "unconnected-(U11-Pad1_152)")
  (net 567 "unconnected-(U11-Pad1_150)")
  (net 568 "unconnected-(U11-Pad1_147)")
  (net 569 "unconnected-(U11-Pad1_145)")
  (net 570 "unconnected-(U11-Pad1_143)")
  (net 571 "unconnected-(U11-Pad1_141)")
  (net 572 "unconnected-(U11-Pad1_140)")
  (net 573 "/SoM/ACCL_INT")
  (net 574 "unconnected-(U11-Pad1_138)")
  (net 575 "/SoM/GYRO_INT")
  (net 576 "unconnected-(U11-Pad1_136)")
  (net 577 "/SoM/MAG_DRDY_INT")
  (net 578 "/SoM/MAG_INT")
  (net 579 "/SoM/CAM0_DVDD_EN")
  (net 580 "/SoM/CAM1_DVDD_EN")
  (net 581 "/SoM/CAM3_TRIGGER_OUT")
  (net 582 "/SoM/CAM3_RST")
  (net 583 "/SoM/PWR_OFF")
  (net 584 "unconnected-(U11-Pad1_122)")
  (net 585 "unconnected-(U11-Pad1_116)")
  (net 586 "unconnected-(U11-Pad1_112)")
  (net 587 "/SoM/RESET_USBHUB")
  (net 588 "/SoM/CAM3_VCC_EN")
  (net 589 "/SoM/LT6911_3V3_EN")
  (net 590 "unconnected-(U11-Pad1_104)")
  (net 591 "/SoM/CAM3_MCLK")
  (net 592 "/SoM/CAM0_AVDD_EN")
  (net 593 "unconnected-(U11-Pad1_99)")
  (net 594 "/SoM/CAM1_AVDD_EN")
  (net 595 "/SoM/CAM1_RST")
  (net 596 "/SoM/CAM1_MCLK")
  (net 597 "/SoM/HDMI1_INTO")
  (net 598 "/SoM/CAM0_MCLK")
  (net 599 "/SoM/LT6911_RST")
  (net 600 "/SoM/CAM1_AFVDD_EN")
  (net 601 "/SoM/CSI3_CLK_P")
  (net 602 "/SoM/CAM0_AFVDD_EN")
  (net 603 "/SoM/CSI3_CLK_N")
  (net 604 "unconnected-(U11-Pad1_84)")
  (net 605 "unconnected-(U11-Pad1_82)")
  (net 606 "/SoM/CSI3_LN0_N")
  (net 607 "/SoM/CSI3_LN0_P")
  (net 608 "/SoM/CSI2_LN3_N")
  (net 609 "/SoM/CSI2_LN3_P")
  (net 610 "/SoM/CSI3_LN1_P")
  (net 611 "/SoM/CSI3_LN1_N")
  (net 612 "/SoM/CSI2_LN2_N")
  (net 613 "/SoM/CSI2_LN2_P")
  (net 614 "/SoM/CSI2_LN0_P")
  (net 615 "/SoM/CSI2_LN0_N")
  (net 616 "/SoM/CSI2_LN1_N")
  (net 617 "/SoM/CSI2_LN1_P")
  (net 618 "/SoM/CSI2_CLK_N")
  (net 619 "/SoM/CSI2_CLK_P")
  (net 620 "/SoM/LCM_VDD_EN")
  (net 621 "unconnected-(U11-Pad1_39)")
  (net 622 "unconnected-(U11-Pad1_35)")
  (net 623 "unconnected-(U11-Pad1_33)")
  (net 624 "unconnected-(U11-Pad1_29)")
  (net 625 "unconnected-(U11-Pad1_27)")
  (net 626 "unconnected-(U15-Pad69)")
  (net 627 "unconnected-(U15-Pad68)")
  (net 628 "unconnected-(U15-Pad67)")
  (net 629 "unconnected-(U15-Pad58)")
  (net 630 "unconnected-(U15-Pad56)")
  (net 631 "unconnected-(U15-Pad48)")
  (net 632 "unconnected-(U15-Pad46)")
  (net 633 "unconnected-(U15-Pad38)")
  (net 634 "unconnected-(U15-Pad37)")
  (net 635 "unconnected-(U15-Pad36)")
  (net 636 "unconnected-(U15-Pad35)")
  (net 637 "unconnected-(U15-Pad34)")
  (net 638 "unconnected-(U15-Pad32)")
  (net 639 "unconnected-(U15-Pad31)")
  (net 640 "unconnected-(U15-Pad30)")
  (net 641 "unconnected-(U15-Pad29)")
  (net 642 "unconnected-(U15-Pad28)")
  (net 643 "unconnected-(U15-Pad26)")
  (net 644 "unconnected-(U15-Pad25)")
  (net 645 "unconnected-(U15-Pad24)")
  (net 646 "unconnected-(U15-Pad23)")
  (net 647 "unconnected-(U15-Pad22)")
  (net 648 "unconnected-(U15-Pad20)")
  (net 649 "unconnected-(U15-Pad19)")
  (net 650 "unconnected-(U15-Pad17)")
  (net 651 "unconnected-(U15-Pad13)")
  (net 652 "unconnected-(U15-Pad11)")
  (net 653 "unconnected-(U15-Pad8)")
  (net 654 "unconnected-(U15-Pad7)")
  (net 655 "unconnected-(U15-Pad6)")
  (net 656 "unconnected-(U15-Pad5)")
  (net 657 "unconnected-(U17-Pad23)")
  (net 658 "unconnected-(U17-Pad22)")
  (net 659 "unconnected-(U17-Pad11)")
  (net 660 "unconnected-(U23-Pad3)")
  (net 661 "unconnected-(J9-PadMP)")
  (net 662 "unconnected-(J6-Pad21)")
  (net 663 "unconnected-(J6-Pad22)")
  (net 664 "unconnected-(J7-PadSH1)")
  (net 665 "unconnected-(J7-PadSH2)")
  (net 666 "unconnected-(U18-Pad1)")
  (net 667 "unconnected-(U18-Pad2)")

  (footprint "sa800u-baseboard-hw-footprints:C_0402_1005Metric" (layer "F.Cu")
    (tedit 616D63CF)
    (at 106 92.4 -90)
    (descr "Capacitor SMD 0402")
    (tags "capacitor SMD 0402")
    (property "Author" "Antmicro")
    (property "Dielectric" "X5R")
    (property "License" "Apache-2.0")
    (property "MPN" "GRM155R61H104KE14D")
    (property "Manufacturer" "Murata")
    (property "Sheetfile" "ethernet-controller.kicad_sch")
    (property "Sheetname" "Ethernet Controller")
    (property "Val" "100n")
    (property "Voltage" "50V")
    (attr smd)
    (fp_text reference "C7" (at 2.32 -0.33 -90) (layer "F.SilkS")
      (effects (font (size 0.7 0.7) (thickness 0.15)) (justify left bottom))
    )
    (fp_text value "C_100n_0402" (at 0 1.4 -90) (layer "F.Fab")
      (effects (font (size 0.7 0.7) (thickness 0.15)) (justify left bottom))
    )
    (fp_text user "License: Apache-2.0" (at -0.932 5.17 -90) (layer "F.Fab") hide
      (effects (font (size 0.7 0.7) (thickness 0.15)) (justify left bottom))
    )
    (fp_text user "Author: Antmicro" (at -0.932 4.17 -90) (layer "F.Fab") hide
      (effects (font (size 0.7 0.7) (thickness 0.15)) (justify left bottom))
    )
    (fp_text user "${REFERENCE}" (at -0.932 3.168 -90) (layer "F.Fab") hide
      (effects (font (size 0.7 0.7) (thickness 0.15)) (justify left bottom))
    )
    (fp_rect (start -0.94 -0.47) (end 0.94 0.47) (layer "F.CrtYd") (width 0.05) (fill none))
    (fp_rect (start -0.499 -0.249) (end 0.499 0.249) (layer "F.Fab") (width 0.15) (fill none))
    (pad "1" smd roundrect (at -0.484 0 270) (size 0.59 0.64) (layers "F.Cu" "F.Paste" "F.Mask") (roundrect_rratio 0.25)
      (net 8 "PCIE1_RX_P") (pintype "passive"))
    (pad "2" smd roundrect (at 0.484 0 270) (size 0.59 0.64) (layers "F.Cu" "F.Paste" "F.Mask") (roundrect_rratio 0.25)
      (net 179 "/Ethernet Controller/PCIE1_RX_C_P") (pintype "passive"))
  )

  (footprint "sa800u-baseboard-hw-footprints:C_0402_1005Metric" (layer "F.Cu")
    (tedit 616D63CF)
    (at 105 92.4 -90)
    (descr "Capacitor SMD 0402")
    (tags "capacitor SMD 0402")
    (property "Author" "Antmicro")
    (property "Dielectric" "X5R")
    (property "License" "Apache-2.0")
    (property "MPN" "GRM155R61H104KE14D")
    (property "Manufacturer" "Murata")
    (property "Sheetfile" "ethernet-controller.kicad_sch")
    (property "Sheetname" "Ethernet Controller")
    (property "Val" "100n")
    (property "Voltage" "50V")
    (attr smd)
    (fp_text reference "C6" (at 2.32 -0.33 -90) (layer "F.SilkS")
      (effects (font (size 0.7 0.7) (thickness 0.15)) (justify left bottom))
    )
    (fp_text value "C_100n_0402" (at 0 1.4 -90) (layer "F.Fab")
      (effects (font (size 0.7 0.7) (thickness 0.15)) (justify left bottom))
    )
    (fp_text user "${REFERENCE}" (at -0.932 3.168 -90) (layer "F.Fab") hide
      (effects (font (size 0.7 0.7) (thickness 0.15)) (justify left bottom))
    )
    (fp_text user "License: Apache-2.0" (at -0.932 5.17 -90) (layer "F.Fab") hide
      (effects (font (size 0.7 0.7) (thickness 0.15)) (justify left bottom))
    )
    (fp_text user "Author: Antmicro" (at -0.932 4.17 -90) (layer "F.Fab") hide
      (effects (font (size 0.7 0.7) (thickness 0.15)) (justify left bottom))
    )
    (fp_rect (start -0.94 -0.47) (end 0.94 0.47) (layer "F.CrtYd") (width 0.05) (fill none))
    (fp_rect (start -0.499 -0.249) (end 0.499 0.249) (layer "F.Fab") (width 0.15) (fill none))
    (pad "1" smd roundrect (at -0.484 0 270) (size 0.59 0.64) (layers "F.Cu" "F.Paste" "F.Mask") (roundrect_rratio 0.25)
      (net 9 "PCIE1_RX_N") (pintype "passive"))
    (pad "2" smd roundrect (at 0.484 0 270) (size 0.59 0.64) (layers "F.Cu" "F.Paste" "F.Mask") (roundrect_rratio 0.25)
      (net 180 "/Ethernet Controller/PCIE1_RX_C_N") (pintype "passive"))
  )

  (footprint "sa800u-baseboard-hw-footprints:C_Elec_10x10.5mm" (layer "F.Cu")
    (tedit 5ED8C968)
    (at 62 124.7 180)
    (descr "SMD capacitor, aluminum electrolytic, 10x10.5mm")
    (tags "capacitor electrolytic")
    (property "Author" "Antmicro")
    (property "Dielectric" "")
    (property "License" "Apache-2.0")
    (property "MPN" "EEEHA2A470UP")
    (property "Manufacturer" "Panasonic")
    (property "Sheetfile" "poe.kicad_sch")
    (property "Sheetname" "PoE")
    (property "Val" "47u/100V")
    (property "Voltage" "")
    (attr smd)
    (fp_text reference "C146" (at 5.75 1.77 90) (layer "F.SilkS")
      (effects (font (size 0.7 0.7) (thickness 0.15)) (justify left bottom))
    )
    (fp_text value "C_47u_ELEC_100V" (at 0 6.299 180) (layer "F.Fab")
      (effects (font (size 0.7 0.7) (thickness 0.15)) (justify left bottom))
    )
    (fp_text user "Author: Antmicro" (at -6.85 9.499 180) (layer "F.Fab") hide
      (effects (font (size 0.7 0.7) (thickness 0.15)) (justify left bottom))
    )
    (fp_text user "License: Apache-2.0" (at -6.85 10.699 180) (layer "F.Fab") hide
      (effects (font (size 0.7 0.7) (thickness 0.15)) (justify left bottom))
    )
    (fp_text user "${REFERENCE}" (at -6.85 8.3 180) (layer "F.Fab") hide
      (effects (font (size 0.7 0.7) (thickness 0.15)) (justify left bottom))
    )
    (fp_line (start -5.361 4.295) (end -4.296 5.36) (layer "F.SilkS") (width 0.15))
    (fp_line (start -6.85 -2.76) (end -5.6 -2.76) (layer "F.SilkS") (width 0.15))
    (fp_line (start -5.361 -4.296) (end -4.296 -5.361) (layer "F.SilkS") (width 0.15))
    (fp_line (start -5.361 -4.296) (end -5.361 -1.51) (layer "F.SilkS") (width 0.15))
    (fp_line (start -4.296 5.36) (end 5.36 5.36) (layer "F.SilkS") (width 0.15))
    (fp_line (start -5.361 4.295) (end -5.361 1.509) (layer "F.SilkS") (width 0.15))
    (fp_line (start -4.296 -5.361) (end 5.36 -5.361) (layer "F.SilkS") (width 0.15))
    (fp_line (start 5.36 -5.361) (end 5.36 -1.51) (layer "F.SilkS") (width 0.15))
    (fp_line (start -6.225 -3.385) (end -6.225 -2.135) (layer "F.SilkS") (width 0.15))
    (fp_line (start 5.36 5.36) (end 5.36 1.509) (layer "F.SilkS") (width 0.15))
    (fp_line (start 6.65 -1.5) (end 6.65 1.49) (layer "F.CrtYd") (width 0.05))
    (fp_line (start -4.35 5.49) (end 5.49 5.49) (layer "F.CrtYd") (width 0.05))
    (fp_line (start -6.66 -1.5) (end -6.66 1.49) (layer "F.CrtYd") (width 0.05))
    (fp_line (start -5.5 -4.35) (end -4.35 -5.5) (layer "F.CrtYd") (width 0.05))
    (fp_line (start 5.49 -1.5) (end 6.65 -1.5) (layer "F.CrtYd") (width 0.05))
    (fp_line (start -5.5 1.49) (end -5.5 4.34) (layer "F.CrtYd") (width 0.05))
    (fp_line (start -5.5 -1.5) (end -6.66 -1.5) (layer "F.CrtYd") (width 0.05))
    (fp_line (start 5.49 1.49) (end 5.49 5.49) (layer "F.CrtYd") (width 0.05))
    (fp_line (start -5.5 4.34) (end -4.35 5.49) (layer "F.CrtYd") (width 0.05))
    (fp_line (start -6.66 1.49) (end -5.5 1.49) (layer "F.CrtYd") (width 0.05))
    (fp_line (start 5.49 -5.5) (end 5.49 -1.5) (layer "F.CrtYd") (width 0.05))
    (fp_line (start -4.35 -5.5) (end 5.49 -5.5) (layer "F.CrtYd") (width 0.05))
    (fp_line (start 6.65 1.49) (end 5.49 1.49) (layer "F.CrtYd") (width 0.05))
    (fp_line (start -5.5 -4.35) (end -5.5 -1.5) (layer "F.CrtYd") (width 0.05))
    (fp_line (start -5.25 -4.25) (end -4.25 -5.25) (layer "F.Fab") (width 0.15))
    (fp_line (start -4.25 -5.25) (end 5.249 -5.25) (layer "F.Fab") (width 0.15))
    (fp_line (start -5.25 -4.25) (end -5.25 4.249) (layer "F.Fab") (width 0.15))
    (fp_line (start -4.559 -1.7) (end -3.559 -1.7) (layer "F.Fab") (width 0.15))
    (fp_line (start -5.25 4.249) (end -4.25 5.249) (layer "F.Fab") (width 0.15))
    (fp_line (start 5.249 -5.25) (end 5.249 5.249) (layer "F.Fab") (width 0.15))
    (fp_line (start -4.059 -2.201) (end -4.059 -1.2) (layer "F.Fab") (width 0.15))
    (fp_line (start -4.25 5.249) (end 5.249 5.249) (layer "F.Fab") (width 0.15))
    (fp_circle (center 0 0) (end 4.999 0) (layer "F.Fab") (width 0.15) (fill none))
    (pad "1" smd roundrect (at -4.201 0 180) (size 4.4 2.5) (layers "F.Cu" "F.Paste" "F.Mask") (roundrect_rratio 0.1)
      (net 73 "/PoE/VDD_POE") (pintype "passive"))
    (pad "2" smd roundrect (at 4.2 0 180) (size 4.4 2.5) (layers "F.Cu" "F.Paste" "F.Mask") (roundrect_rratio 0.1)
      (net 7 "GNDD") (pintype "passive"))
  )

  (footprint "sa800u-baseboard-hw-footprints:R_0402_1005Metric" (layer "F.Cu")
    (tedit 5FD9C158)
    (at 140 142.5)
    (descr "Resistor SMD 0402")
    (tags "resistor SMD 0402")
    (property "Author" "Antmicro")
    (property "License" "Apache-2.0")
    (property "MPN" "CR0402-FX-2201GLF")
    (property "Manufacturer" "Bourns")
    (property "Sheetfile" "hdmi-converter.kicad_sch")
    (property "Sheetname" "HDMI converter")
    (property "Tolerance" "1%")
    (property "Val" "2k2")
    (attr smd)
    (fp_text reference "R28" (at -3.05 0.35) (layer "F.SilkS")
      (effects (font (size 0.7 0.7) (thickness 0.15)) (justify left bottom))
    )
    (fp_text value "R_2k2_0402" (at 0 1.4) (layer "F.Fab")
      (effects (font (size 0.7 0.7) (thickness 0.15)) (justify left bottom))
    )
    (fp_text user "${REFERENCE}" (at -0.95 3.168) (layer "F.Fab") hide
      (effects (font (size 0.7 0.7) (thickness 0.15)) (justify left bottom))
    )
    (fp_text user "Author: Antmicro" (at -0.95 4.169) (layer "F.Fab") hide
      (effects (font (size 0.7 0.7) (thickness 0.15)) (justify left bottom))
    )
    (fp_text user "License: Apache-2.0" (at -0.95 5.169) (layer "F.Fab") hide
      (effects (font (size 0.7 0.7) (thickness 0.15)) (justify left bottom))
    )
    (fp_rect (start -0.93 -0.47) (end 0.93 0.47) (layer "F.CrtYd") (width 0.05) (fill none))
    (fp_rect (start -0.5 -0.25) (end 0.5 0.25) (layer "F.Fab") (width 0.15) (fill none))
    (pad "1" smd roundrect (at -0.485 0) (size 0.59 0.64) (layers "F.Cu" "F.Paste" "F.Mask") (roundrect_rratio 0.25)
      (net 133 "5V_SYS") (pintype "passive"))
    (pad "2" smd roundrect (at 0.485 0) (size 0.59 0.64) (layers "F.Cu" "F.Paste" "F.Mask") (roundrect_rratio 0.25)
      (net 232 "/HDMI converter/HDMI_SCL") (pintype "passive"))
  )

  (footprint "sa800u-baseboard-hw-footprints:R_0402_1005Metric" (layer "F.Cu")
    (tedit 5FD9C158)
    (at 140 141.5)
    (descr "Resistor SMD 0402")
    (tags "resistor SMD 0402")
    (property "Author" "Antmicro")
    (property "License" "Apache-2.0")
    (property "MPN" "CR0402-FX-2201GLF")
    (property "Manufacturer" "Bourns")
    (property "Sheetfile" "hdmi-converter.kicad_sch")
    (property "Sheetname" "HDMI converter")
    (property "Tolerance" "1%")
    (property "Val" "2k2")
    (attr smd)
    (fp_text reference "R32" (at -3.05 0.35) (layer "F.SilkS")
      (effects (font (size 0.7 0.7) (thickness 0.15)) (justify left bottom))
    )
    (fp_text value "R_2k2_0402" (at 0 1.4) (layer "F.Fab")
      (effects (font (size 0.7 0.7) (thickness 0.15)) (justify left bottom))
    )
    (fp_text user "${REFERENCE}" (at -0.95 3.168) (layer "F.Fab") hide
      (effects (font (size 0.7 0.7) (thickness 0.15)) (justify left bottom))
    )
    (fp_text user "License: Apache-2.0" (at -0.95 5.169) (layer "F.Fab") hide
      (effects (font (size 0.7 0.7) (thickness 0.15)) (justify left bottom))
    )
    (fp_text user "Author: Antmicro" (at -0.95 4.169) (layer "F.Fab") hide
      (effects (font (size 0.7 0.7) (thickness 0.15)) (justify left bottom))
    )
    (fp_rect (start -0.93 -0.47) (end 0.93 0.47) (layer "F.CrtYd") (width 0.05) (fill none))
    (fp_rect (start -0.5 -0.25) (end 0.5 0.25) (layer "F.Fab") (width 0.15) (fill none))
    (pad "1" smd roundrect (at -0.485 0) (size 0.59 0.64) (layers "F.Cu" "F.Paste" "F.Mask") (roundrect_rratio 0.25)
      (net 133 "5V_SYS") (pintype "passive"))
    (pad "2" smd roundrect (at 0.485 0) (size 0.59 0.64) (layers "F.Cu" "F.Paste" "F.Mask") (roundrect_rratio 0.25)
      (net 235 "/HDMI converter/HDMI_SDA") (pintype "passive"))
  )

  (footprint "sa800u-baseboard-hw-footprints:SW_SPST_4.2x2.8" (layer "F.Cu")
    (tedit 5DF0C83F)
    (at 152 93.5)
    (descr "KMR211G")
    (tags "SPST Button Switch")
    (property "Author" "Antmicro")
    (property "License" "Apache-2.0")
    (property "MPN" "KMR211NGLFS")
    (property "Manufacturer" "C&K")
    (property "Sheetfile" "som.kicad_sch")
    (property "Sheetname" "SoM")
    (attr smd)
    (fp_text reference "S1" (at -3 -2.25) (layer "F.SilkS")
      (effects (font (size 0.7 0.7) (thickness 0.15)) (justify left bottom))
    )
    (fp_text value "SW_SPST_KMR211NGLFS" (at -3 3) (layer "F.Fab")
      (effects (font (size 0.7 0.7) (thickness 0.15)) (justify left bottom))
    )
    (fp_text user "${REFERENCE}" (at -3 4.25) (layer "F.Fab") hide
      (effects (font (size 0.7 0.7) (thickness 0.15)) (justify left bottom))
    )
    (fp_text user "Author: Antmicro" (at -3 5.5) (layer "F.Fab") hide
      (effects (font (size 0.7 0.7) (thickness 0.15)) (justify left bottom))
    )
    (fp_text user "License: Apache-2.0" (at -3 6.75) (layer "F.Fab") hide
      (effects (font (size 0.7 0.7) (thickness 0.15)) (justify left bottom))
    )
    (fp_line (start -2.101 -1.601) (end 2.1 -1.601) (layer "F.SilkS") (width 0.15))
    (fp_line (start 2.1 1.6) (end 2.1 1.499) (layer "F.SilkS") (width 0.15))
    (fp_line (start -2.101 -1.601) (end -2.101 -1.48) (layer "F.SilkS") (width 0.15))
    (fp_line (start 2.1 -1.601) (end 2.1 -1.48) (layer "F.SilkS") (width 0.15))
    (fp_line (start -2.101 1.58) (end -2.101 1.459) (layer "F.SilkS") (width 0.15))
    (fp_line (start -2.101 1.6) (end 2.1 1.6) (layer "F.SilkS") (width 0.15))
    (fp_rect (start -2.751 -1.75) (end 2.748 1.749) (layer "F.CrtYd") (width 0.05) (fill none))
    (fp_line (start -2.101 1.6) (end 2.1 1.6) (layer "F.Fab") (width 0.15))
    (fp_line (start 0.248 0.8) (end -0.25 0.8) (layer "F.Fab") (width 0.15))
    (fp_line (start -2.101 -1.601) (end -2.101 1.6) (layer "F.Fab") (width 0.15))
    (fp_line (start 2.1 1.6) (end 2.1 -1.601) (layer "F.Fab") (width 0.15))
    (fp_line (start 2.1 -1.601) (end -2.101 -1.601) (layer "F.Fab") (width 0.15))
    (fp_line (start -0.25 -0.802) (end 0.248 -0.802) (layer "F.Fab") (width 0.15))
    (fp_arc (start -0.25 0.8) (mid -1.051001 -0.001) (end -0.25 -0.802) (layer "F.Fab") (width 0.15))
    (fp_arc (start 0.248 -0.802) (mid 1.050001 -0.001) (end 0.248 0.8) (layer "F.Fab") (width 0.15))
    (pad "1" smd rect (at 2.048 -0.802) (size 0.9 1) (layers "F.Cu" "F.Paste" "F.Mask")
      (net 1 "GND") (pintype "passive"))
    (pad "2" smd rect (at 2.048 0.8) (size 0.9 1) (layers "F.Cu" "F.Paste" "F.Mask")
      (net 344 "/SoM/HOME_KEY_R") (pintype "passive"))
    (pad "3" smd rect (at -2.05 -0.802) (size 0.9 1) (layers "F.Cu" "F.Paste" "F.Mask")
      (net 1 "GND") (pintype "passive"))
    (pad "4" smd rect (at -2.05 0.8) (size 0.9 1) (layers "F.Cu" "F.Paste" "F.Mask")
      (net 344 "/SoM/HOME_KEY_R") (pintype "passive"))
  )

  (footprint "sa800u-baseboard-hw-footprints:SW_SPST_4.2x2.8" (layer "F.Cu")
    (tedit 5DF0C83F)
    (at 152 99.5)
    (descr "KMR211G")
    (tags "SPST Button Switch")
    (property "Author" "Antmicro")
    (property "License" "Apache-2.0")
    (property "MPN" "KMR211NGLFS")
    (property "Manufacturer" "C&K")
    (property "Sheetfile" "som.kicad_sch")
    (property "Sheetname" "SoM")
    (attr smd)
    (fp_text reference "S2" (at -2.44 -1.87) (layer "F.SilkS")
      (effects (font (size 0.7 0.7) (thickness 0.15)) (justify left bottom))
    )
    (fp_text value "SW_SPST_KMR211NGLFS" (at -3 3) (layer "F.Fab")
      (effects (font (size 0.7 0.7) (thickness 0.15)) (justify left bottom))
    )
    (fp_text user "${REFERENCE}" (at -3 4.25) (layer "F.Fab") hide
      (effects (font (size 0.7 0.7) (thickness 0.15)) (justify left bottom))
    )
    (fp_text user "Author: Antmicro" (at -3 5.5) (layer "F.Fab") hide
      (effects (font (size 0.7 0.7) (thickness 0.15)) (justify left bottom))
    )
    (fp_text user "License: Apache-2.0" (at -3 6.75) (layer "F.Fab") hide
      (effects (font (size 0.7 0.7) (thickness 0.15)) (justify left bottom))
    )
    (fp_line (start -2.101 -1.601) (end 2.1 -1.601) (layer "F.SilkS") (width 0.15))
    (fp_line (start -2.101 1.58) (end -2.101 1.459) (layer "F.SilkS") (width 0.15))
    (fp_line (start -2.101 -1.601) (end -2.101 -1.48) (layer "F.SilkS") (width 0.15))
    (fp_line (start 2.1 -1.601) (end 2.1 -1.48) (layer "F.SilkS") (width 0.15))
    (fp_line (start 2.1 1.6) (end 2.1 1.499) (layer "F.SilkS") (width 0.15))
    (fp_line (start -2.101 1.6) (end 2.1 1.6) (layer "F.SilkS") (width 0.15))
    (fp_rect (start -2.751 -1.75) (end 2.748 1.749) (layer "F.CrtYd") (width 0.05) (fill none))
    (fp_line (start 2.1 -1.601) (end -2.101 -1.601) (layer "F.Fab") (width 0.15))
    (fp_line (start -2.101 -1.601) (end -2.101 1.6) (layer "F.Fab") (width 0.15))
    (fp_line (start -0.25 -0.802) (end 0.248 -0.802) (layer "F.Fab") (width 0.15))
    (fp_line (start -2.101 1.6) (end 2.1 1.6) (layer "F.Fab") (width 0.15))
    (fp_line (start 2.1 1.6) (end 2.1 -1.601) (layer "F.Fab") (width 0.15))
    (fp_line (start 0.248 0.8) (end -0.25 0.8) (layer "F.Fab") (width 0.15))
    (fp_arc (start -0.25 0.8) (mid -1.051001 -0.001) (end -0.25 -0.802) (layer "F.Fab") (width 0.15))
    (fp_arc (start 0.248 -0.802) (mid 1.050001 -0.001) (end 0.248 0.8) (layer "F.Fab") (width 0.15))
    (pad "1" smd rect (at 2.048 -0.802) (size 0.9 1) (layers "F.Cu" "F.Paste" "F.Mask")
      (net 1 "GND") (pintype "passive"))
    (pad "2" smd rect (at 2.048 0.8) (size 0.9 1) (layers "F.Cu" "F.Paste" "F.Mask")
      (net 345 "/SoM/VOL_UP_R") (pintype "passive"))
    (pad "3" smd rect (at -2.05 -0.802) (size 0.9 1) (layers "F.Cu" "F.Paste" "F.Mask")
      (net 1 "GND") (pintype "passive"))
    (pad "4" smd rect (at -2.05 0.8) (size 0.9 1) (layers "F.Cu" "F.Paste" "F.Mask")
      (net 345 "/SoM/VOL_UP_R") (pintype "passive"))
  )

  (footprint "sa800u-baseboard-hw-footprints:SW_SPST_4.2x2.8" (layer "F.Cu")
    (tedit 5DF0C83F)
    (at 152 111.5)
    (descr "KMR211G")
    (tags "SPST Button Switch")
    (property "Author" "Antmicro")
    (property "License" "Apache-2.0")
    (property "MPN" "KMR211NGLFS")
    (property "Manufacturer" "C&K")
    (property "Sheetfile" "som.kicad_sch")
    (property "Sheetname" "SoM")
    (attr smd)
    (fp_text reference "S3" (at 1.41 2.66) (layer "F.SilkS")
      (effects (font (size 0.7 0.7) (thickness 0.15)) (justify left bottom))
    )
    (fp_text value "SW_SPST_KMR211NGLFS" (at -3 3) (layer "F.Fab")
      (effects (font (size 0.7 0.7) (thickness 0.15)) (justify left bottom))
    )
    (fp_text user "License: Apache-2.0" (at -3 6.75) (layer "F.Fab") hide
      (effects (font (size 0.7 0.7) (thickness 0.15)) (justify left bottom))
    )
    (fp_text user "${REFERENCE}" (at -3 4.25) (layer "F.Fab") hide
      (effects (font (size 0.7 0.7) (thickness 0.15)) (justify left bottom))
    )
    (fp_text user "Author: Antmicro" (at -3 5.5) (layer "F.Fab") hide
      (effects (font (size 0.7 0.7) (thickness 0.15)) (justify left bottom))
    )
    (fp_line (start -2.101 -1.601) (end 2.1 -1.601) (layer "F.SilkS") (width 0.15))
    (fp_line (start 2.1 1.6) (end 2.1 1.499) (layer "F.SilkS") (width 0.15))
    (fp_line (start -2.101 1.58) (end -2.101 1.459) (layer "F.SilkS") (width 0.15))
    (fp_line (start -2.101 1.6) (end 2.1 1.6) (layer "F.SilkS") (width 0.15))
    (fp_line (start 2.1 -1.601) (end 2.1 -1.48) (layer "F.SilkS") (width 0.15))
    (fp_line (start -2.101 -1.601) (end -2.101 -1.48) (layer "F.SilkS") (width 0.15))
    (fp_rect (start -2.751 -1.75) (end 2.748 1.749) (layer "F.CrtYd") (width 0.05) (fill none))
    (fp_line (start -0.25 -0.802) (end 0.248 -0.802) (layer "F.Fab") (width 0.15))
    (fp_line (start 2.1 -1.601) (end -2.101 -1.601) (layer "F.Fab") (width 0.15))
    (fp_line (start 2.1 1.6) (end 2.1 -1.601) (layer "F.Fab") (width 0.15))
    (fp_line (start -2.101 -1.601) (end -2.101 1.6) (layer "F.Fab") (width 0.15))
    (fp_line (start -2.101 1.6) (end 2.1 1.6) (layer "F.Fab") (width 0.15))
    (fp_line (start 0.248 0.8) (end -0.25 0.8) (layer "F.Fab") (width 0.15))
    (fp_arc (start -0.25 0.8) (mid -1.051001 -0.001) (end -0.25 -0.802) (layer "F.Fab") (width 0.15))
    (fp_arc (start 0.248 -0.802) (mid 1.050001 -0.001) (end 0.248 0.8) (layer "F.Fab") (width 0.15))
    (pad "1" smd rect (at 2.048 -0.802) (size 0.9 1) (layers "F.Cu" "F.Paste" "F.Mask")
      (net 1 "GND") (pintype "passive"))
    (pad "2" smd rect (at 2.048 0.8) (size 0.9 1) (layers "F.Cu" "F.Paste" "F.Mask")
      (net 346 "/SoM/PWR_R") (pintype "passive"))
    (pad "3" smd rect (at -2.05 -0.802) (size 0.9 1) (layers "F.Cu" "F.Paste" "F.Mask")
      (net 1 "GND") (pintype "passive"))
    (pad "4" smd rect (at -2.05 0.8) (size 0.9 1) (layers "F.Cu" "F.Paste" "F.Mask")
      (net 346 "/SoM/PWR_R") (pintype "passive"))
  )

  (footprint "sa800u-baseboard-hw-footprints:SW_SPST_4.2x2.8" (layer "F.Cu")
    (tedit 5DF0C83F)
    (at 152 105.5)
    (descr "KMR211G")
    (tags "SPST Button Switch")
    (property "Author" "Antmicro")
    (property "License" "Apache-2.0")
    (property "MPN" "KMR211NGLFS")
    (property "Manufacturer" "C&K")
    (property "Sheetfile" "som.kicad_sch")
    (property "Sheetname" "SoM")
    (attr smd)
    (fp_text reference "S4" (at -2.45 -1.91) (layer "F.SilkS")
      (effects (font (size 0.7 0.7) (thickness 0.15)) (justify left bottom))
    )
    (fp_text value "SW_SPST_KMR211NGLFS" (at -3 3) (layer "F.Fab")
      (effects (font (size 0.7 0.7) (thickness 0.15)) (justify left bottom))
    )
    (fp_text user "License: Apache-2.0" (at -3 6.75) (layer "F.Fab") hide
      (effects (font (size 0.7 0.7) (thickness 0.15)) (justify left bottom))
    )
    (fp_text user "${REFERENCE}" (at -3 4.25) (layer "F.Fab") hide
      (effects (font (size 0.7 0.7) (thickness 0.15)) (justify left bottom))
    )
    (fp_text user "Author: Antmicro" (at -3 5.5) (layer "F.Fab") hide
      (effects (font (size 0.7 0.7) (thickness 0.15)) (justify left bottom))
    )
    (fp_line (start -2.101 -1.601) (end -2.101 -1.48) (layer "F.SilkS") (width 0.15))
    (fp_line (start -2.101 -1.601) (end 2.1 -1.601) (layer "F.SilkS") (width 0.15))
    (fp_line (start -2.101 1.58) (end -2.101 1.459) (layer "F.SilkS") (width 0.15))
    (fp_line (start 2.1 -1.601) (end 2.1 -1.48) (layer "F.SilkS") (width 0.15))
    (fp_line (start 2.1 1.6) (end 2.1 1.499) (layer "F.SilkS") (width 0.15))
    (fp_line (start -2.101 1.6) (end 2.1 1.6) (layer "F.SilkS") (width 0.15))
    (fp_rect (start -2.751 -1.75) (end 2.748 1.749) (layer "F.CrtYd") (width 0.05) (fill none))
    (fp_line (start 2.1 -1.601) (end -2.101 -1.601) (layer "F.Fab") (width 0.15))
    (fp_line (start -2.101 -1.601) (end -2.101 1.6) (layer "F.Fab") (width 0.15))
    (fp_line (start 0.248 0.8) (end -0.25 0.8) (layer "F.Fab") (width 0.15))
    (fp_line (start -0.25 -0.802) (end 0.248 -0.802) (layer "F.Fab") (width 0.15))
    (fp_line (start -2.101 1.6) (end 2.1 1.6) (layer "F.Fab") (width 0.15))
    (fp_line (start 2.1 1.6) (end 2.1 -1.601) (layer "F.Fab") (width 0.15))
    (fp_arc (start 0.248 -0.802) (mid 1.050001 -0.001) (end 0.248 0.8) (layer "F.Fab") (width 0.15))
    (fp_arc (start -0.25 0.8) (mid -1.051001 -0.001) (end -0.25 -0.802) (layer "F.Fab") (width 0.15))
    (pad "1" smd rect (at 2.048 -0.802) (size 0.9 1) (layers "F.Cu" "F.Paste" "F.Mask")
      (net 1 "GND") (pintype "passive"))
    (pad "2" smd rect (at 2.048 0.8) (size 0.9 1) (layers "F.Cu" "F.Paste" "F.Mask")
      (net 343 "/SoM/VOL_DOWN_R") (pintype "passive"))
    (pad "3" smd rect (at -2.05 -0.802) (size 0.9 1) (layers "F.Cu" "F.Paste" "F.Mask")
      (net 1 "GND") (pintype "passive"))
    (pad "4" smd rect (at -2.05 0.8) (size 0.9 1) (layers "F.Cu" "F.Paste" "F.Mask")
      (net 343 "/SoM/VOL_DOWN_R") (pintype "passive"))
  )

  (footprint "sa800u-baseboard-hw-footprints:HDMI_Micro-D_Molex_46765-1x01" locked (layer "F.Cu")
    (tedit 615AA2CD)
    (at 144.251 149.001)
    (descr "HDMI, Micro, Type D, THT, 0.4mm pitch, 19 ckt, right angle (http://www.molex.com/pdm_docs/sd/467651301_sd.pdf)")
    (tags "hdmi micro type d right angle tht")
    (property "Author" "Antmicro")
    (property "License" "Apache-2.0")
    (property "MPN" "467651001")
    (property "Manufacturer" "Molex")
    (property "Sheetfile" "hdmi-converter.kicad_sch")
    (property "Sheetname" "HDMI converter")
    (attr smd)
    (fp_text reference "J2" (at 3.499 -3.501) (layer "F.SilkS")
      (effects (font (size 0.7 0.7) (thickness 0.15)) (justify left bottom))
    )
    (fp_text value "HDMI_Micro-D_46756-1001" (at -3.4 5) (layer "F.Fab")
      (effects (font (size 0.7 0.7) (thickness 0.15)) (justify left bottom))
    )
    (fp_text user "License: Apache-2.0" (at -3.4 9) (layer "F.Fab") hide
      (effects (font (size 0.7 0.7) (thickness 0.15)) (justify left bottom))
    )
    (fp_text user "${REFERENCE}" (at -3.4 6.4) (layer "F.Fab") hide
      (effects (font (size 0.7 0.7) (thickness 0.15)) (justify left bottom))
    )
    (fp_text user "Author: Antmicro" (at -3.4 7.6) (layer "F.Fab") hide
      (effects (font (size 0.7 0.7) (thickness 0.15)) (justify left bottom))
    )
    (fp_line (start 3.309 -3.86) (end 3.309 -3.551) (layer "F.SilkS") (width 0.15))
    (fp_line (start -3.31 -3.551) (end -3.31 -3.86) (layer "F.SilkS") (width 0.15))
    (fp_line (start -3.31 -3.86) (end -2.15 -3.86) (layer "F.SilkS") (width 0.15))
    (fp_line (start -3.31 -0.201) (end -3.31 -0.6) (layer "F.SilkS") (width 0.15))
    (fp_line (start -3.301 2.899) (end -3.301 2.499) (layer "F.SilkS") (width 0.15))
    (fp_line (start 3.309 2.499) (end 3.309 2.899) (layer "F.SilkS") (width 0.15))
    (fp_line (start 2.148 -3.86) (end 3.309 -3.86) (layer "F.SilkS") (width 0.15))
    (fp_line (start 3.309 -0.6) (end 3.309 -0.201) (layer "F.SilkS") (width 0.15))
    (fp_line (start 2.148 -3.86) (end 2.148 -4.061) (layer "F.SilkS") (width 0.15))
    (fp_rect (start -3.45 -4.101) (end 3.45 3.949) (layer "F.CrtYd") (width 0.05) (fill none))
    (fp_line (start 1.8 -3.301) (end 1.3 -3.801) (layer "B.Fab") (width 0.15))
    (fp_line (start 3.249 3.7) (end -3.25 3.7) (layer "F.Fab") (width 0.15))
    (fp_line (start -3.25 -3.801) (end 1.3 -3.801) (layer "F.Fab") (width 0.15))
    (fp_line (start 3.249 -3.801) (end 3.249 3.7) (layer "F.Fab") (width 0.15))
    (fp_line (start 2.298 -3.801) (end 3.249 -3.801) (layer "F.Fab") (width 0.15))
    (fp_line (start 1.8 -3.301) (end 2.298 -3.801) (layer "F.Fab") (width 0.15))
    (fp_line (start -3.25 3.7) (end -3.25 -3.801) (layer "F.Fab") (width 0.15))
    (pad "1" smd rect locked (at 1.8 -3.476) (size 0.23 0.85) (layers "F.Cu" "F.Paste" "F.Mask")
      (net 234 "/HDMI converter/HDMI_DETECT") (pinfunction "HPD/HEAC-") (pintype "passive"))
    (pad "2" smd rect locked (at 1.6 -2.25) (size 0.23 1) (layers "F.Cu" "F.Paste" "F.Mask")
      (net 414 "unconnected-(J2-Pad2)") (pinfunction "UTILITY/HEAC+") (pintype "passive+no_connect"))
    (pad "3" smd rect locked (at 1.398 -3.476) (size 0.23 0.85) (layers "F.Cu" "F.Paste" "F.Mask")
      (net 243 "/HDMI converter/HDMI_TX2_CONN_P") (pinfunction "D2+") (pintype "passive"))
    (pad "4" smd rect locked (at 1.199 -2.25) (size 0.23 1) (layers "F.Cu" "F.Paste" "F.Mask")
      (net 1 "GND") (pinfunction "D2S") (pintype "power_in"))
    (pad "5" smd rect locked (at 0.998 -3.476) (size 0.23 0.85) (layers "F.Cu" "F.Paste" "F.Mask")
      (net 240 "/HDMI converter/HDMI_TX2_CONN_N") (pinfunction "D2-") (pintype "passive"))
    (pad "6" smd rect locked (at 0.8 -2.25) (size 0.23 1) (layers "F.Cu" "F.Paste" "F.Mask")
      (net 241 "/HDMI converter/HDMI_TX1_CONN_P") (pinfunction "D1+") (pintype "passive"))
    (pad "7" smd rect locked (at 0.598 -3.476) (size 0.23 0.85) (layers "F.Cu" "F.Paste" "F.Mask")
      (net 1 "GND") (pinfunction "D1S") (pintype "power_in"))
    (pad "8" smd rect locked (at 0.4 -2.25) (size 0.23 1) (layers "F.Cu" "F.Paste" "F.Mask")
      (net 242 "/HDMI converter/HDMI_TX1_CONN_N") (pinfunction "D1-") (pintype "passive"))
    (pad "9" smd rect locked (at 0.2 -3.476) (size 0.23 0.85) (layers "F.Cu" "F.Paste" "F.Mask")
      (net 239 "/HDMI converter/HDMI_TX0_CONN_P") (pinfunction "D0+") (pintype "passive"))
    (pad "10" smd rect locked (at 0 -2.25) (size 0.23 1) (layers "F.Cu" "F.Paste" "F.Mask")
      (net 1 "GND") (pinfunction "D0S") (pintype "power_in"))
    (pad "11" smd rect locked (at -0.202 -3.476) (size 0.23 0.85) (layers "F.Cu" "F.Paste" "F.Mask")
      (net 236 "/HDMI converter/HDMI_TX0_CONN_N") (pinfunction "D0-") (pintype "passive"))
    (pad "12" smd rect locked (at -0.402 -2.25) (size 0.23 1) (layers "F.Cu" "F.Paste" "F.Mask")
      (net 237 "/HDMI converter/HDMI_CLK_CONN_P") (pinfunction "CK+") (pintype "passive"))
    (pad "13" smd rect locked (at -0.6 -3.476) (size 0.23 0.85) (layers "F.Cu" "F.Paste" "F.Mask")
      (net 1 "GND") (pinfunction "CKS") (pintype "power_in"))
    (pad "14" smd rect locked (at -0.802 -2.25) (size 0.23 1) (layers "F.Cu" "F.Paste" "F.Mask")
      (net 238 "/HDMI converter/HDMI_CLK_CONN_N") (pinfunction "CK-") (pintype "passive"))
    (pad "15" smd rect locked (at -1 -3.476) (size 0.23 0.85) (layers "F.Cu" "F.Paste" "F.Mask")
      (net 233 "/HDMI converter/HDMI_CEC") (pinfunction "CEC") (pintype "bidirectional"))
    (pad "16" smd rect locked (at -1.2 -2.25) (size 0.23 1) (layers "F.Cu" "F.Paste" "F.Mask")
      (net 1 "GND") (pinfunction "GND") (pintype "power_in"))
    (pad "17" smd rect locked (at -1.401 -3.476) (size 0.23 0.85) (layers "F.Cu" "F.Paste" "F.Mask")
      (net 232 "/HDMI converter/HDMI_SCL") (pinfunction "SCL") (pintype "passive"))
    (pad "18" smd rect locked (at -1.601 -2.25) (size 0.23 1) (layers "F.Cu" "F.Paste" "F.Mask")
      (net 235 "/HDMI converter/HDMI_SDA") (pinfunction "SDA") (pintype "bidirectional"))
    (pad "19" smd rect locked (at -1.801 -3.476) (size 0.23 0.85) (layers "F.Cu" "F.Paste" "F.Mask")
      (net 245 "/HDMI converter/5V_HDMI") (pinfunction "+5V") (pintype "power_in"))
    (pad "SH" thru_hole oval locked (at -3.101 1.3) (size 1.05 2.1) (drill oval 0.65 1.7) (layers *.Cu *.Mask)
      (net 1 "GND") (pinfunction "SH") (pintype "passive"))
    (pad "SH" thru_hole oval locked (at 3.1 -2.061) (size 1.05 2.1) (drill oval 0.65 1.7) (layers *.Cu *.Mask)
      (net 1 "GND") (pinfunction "SH") (pintype "passive"))
    (pad "SH" thru_hole oval locked (at -3.101 -2.061) (size 1.05 2.1) (drill oval 0.65 1.7) (layers *.Cu *.Mask)
      (net 1 "GND") (pinfunction "SH") (pintype "passive"))
    (pad "SH" thru_hole oval locked (at 3.1 1.3) (size 1.05 2.1) (drill oval 0.65 1.7) (layers *.Cu *.Mask)
      (net 1 "GND") (pinfunction "SH") (pintype "passive"))
  )

  (footprint "sa800u-baseboard-hw-footprints:C_0603_1608Metric" (layer "F.Cu")
    (tedit 5D5E94D2)
    (at 77.06 108.54)
    (descr "Capacitor SMD 0603")
    (tags "capacitor 0603")
    (property "Author" "Antmicro")
    (property "Dielectric" "")
    (property "License" "Apache-2.0")
    (property "MPN" "GRM188R60J226MEA0D")
    (property "Manufacturer" "Murata")
    (property "Sheetfile" "psu.kicad_sch")
    (property "Sheetname" "PSU")
    (property "Val" "22u")
    (property "Voltage" "")
    (attr smd)
    (fp_text reference "C129" (at -3.76 0.12) (layer "F.SilkS")
      (effects (font (size 0.7 0.7) (thickness 0.15)) (justify left bottom))
    )
    (fp_text value "C_22u_0603" (at 0 1.6) (layer "F.Fab")
      (effects (font (size 0.7 0.7) (thickness 0.15)) (justify left bottom))
    )
    (fp_text user "Author: Antmicro" (at -1.682 4.894) (layer "F.Fab") hide
      (effects (font (size 0.7 0.7) (thickness 0.15)) (justify left bottom))
    )
    (fp_text user "License: Apache-2.0" (at -1.682 5.895) (layer "F.Fab") hide
      (effects (font (size 0.7 0.7) (thickness 0.15)) (justify left bottom))
    )
    (fp_text user "${REFERENCE}" (at -1.682 3.895) (layer "F.Fab") hide
      (effects (font (size 0.7 0.7) (thickness 0.15)) (justify left bottom))
    )
    (fp_line (start -0.3 -0.3) (end 0.3 -0.3) (layer "F.SilkS") (width 0.15))
    (fp_line (start -0.3 0.3) (end 0.3 0.3) (layer "F.SilkS") (width 0.15))
    (fp_rect (start -1.24 -0.7) (end 1.24 0.7) (layer "F.CrtYd") (width 0.05) (fill none))
    (fp_rect (start -0.8 -0.4) (end 0.8 0.4) (layer "F.Fab") (width 0.15) (fill none))
    (pad "1" smd roundrect (at -0.7 0) (size 0.6 0.8) (layers "F.Cu" "F.Paste" "F.Mask") (roundrect_rratio 0.2)
      (net 74 "VDD") (pintype "passive"))
    (pad "2" smd roundrect (at 0.7 0) (size 0.6 0.8) (layers "F.Cu" "F.Paste" "F.Mask") (roundrect_rratio 0.2)
      (net 1 "GND") (pintype "passive"))
  )

  (footprint "sa800u-baseboard-hw-footprints:C_0603_1608Metric" (layer "F.Cu")
    (tedit 5D5E94D2)
    (at 82.29 91.37)
    (descr "Capacitor SMD 0603")
    (tags "capacitor 0603")
    (property "Author" "Antmicro")
    (property "Dielectric" "")
    (property "License" "Apache-2.0")
    (property "MPN" "GRM188R60J226MEA0D")
    (property "Manufacturer" "Murata")
    (property "Sheetfile" "psu.kicad_sch")
    (property "Sheetname" "PSU")
    (property "Val" "22u")
    (property "Voltage" "")
    (attr smd)
    (fp_text reference "C135" (at -1.41 -2.3) (layer "F.SilkS")
      (effects (font (size 0.7 0.7) (thickness 0.15)) (justify left bottom))
    )
    (fp_text value "C_22u_0603" (at 0 1.6) (layer "F.Fab")
      (effects (font (size 0.7 0.7) (thickness 0.15)) (justify left bottom))
    )
    (fp_text user "License: Apache-2.0" (at -1.682 5.895) (layer "F.Fab") hide
      (effects (font (size 0.7 0.7) (thickness 0.15)) (justify left bottom))
    )
    (fp_text user "Author: Antmicro" (at -1.682 4.894) (layer "F.Fab") hide
      (effects (font (size 0.7 0.7) (thickness 0.15)) (justify left bottom))
    )
    (fp_text user "${REFERENCE}" (at -1.682 3.895) (layer "F.Fab") hide
      (effects (font (size 0.7 0.7) (thickness 0.15)) (justify left bottom))
    )
    (fp_line (start -0.3 -0.3) (end 0.3 -0.3) (layer "F.SilkS") (width 0.15))
    (fp_line (start -0.3 0.3) (end 0.3 0.3) (layer "F.SilkS") (width 0.15))
    (fp_rect (start -1.24 -0.7) (end 1.24 0.7) (layer "F.CrtYd") (width 0.05) (fill none))
    (fp_rect (start -0.8 -0.4) (end 0.8 0.4) (layer "F.Fab") (width 0.15) (fill none))
    (pad "1" smd roundrect (at -0.7 0) (size 0.6 0.8) (layers "F.Cu" "F.Paste" "F.Mask") (roundrect_rratio 0.2)
      (net 137 "3V8_SYS") (pintype "passive"))
    (pad "2" smd roundrect (at 0.7 0) (size 0.6 0.8) (layers "F.Cu" "F.Paste" "F.Mask") (roundrect_rratio 0.2)
      (net 1 "GND") (pintype "passive"))
  )

  (footprint "sa800u-baseboard-hw-footprints:C_0603_1608Metric" (layer "F.Cu")
    (tedit 5D5E94D2)
    (at 82.02 109.35 90)
    (descr "Capacitor SMD 0603")
    (tags "capacitor 0603")
    (property "Author" "Antmicro")
    (property "Dielectric" "")
    (property "License" "Apache-2.0")
    (property "MPN" "GRM188R60J226MEA0D")
    (property "Manufacturer" "Murata")
    (property "Sheetfile" "psu.kicad_sch")
    (property "Sheetname" "PSU")
    (property "Val" "22u")
    (property "Voltage" "")
    (attr smd)
    (fp_text reference "C136" (at -3.93 0.41 90) (layer "F.SilkS")
      (effects (font (size 0.7 0.7) (thickness 0.15)) (justify left bottom))
    )
    (fp_text value "C_22u_0603" (at 0 1.6 90) (layer "F.Fab")
      (effects (font (size 0.7 0.7) (thickness 0.15)) (justify left bottom))
    )
    (fp_text user "Author: Antmicro" (at -1.682 4.894 90) (layer "F.Fab") hide
      (effects (font (size 0.7 0.7) (thickness 0.15)) (justify left bottom))
    )
    (fp_text user "${REFERENCE}" (at -1.682 3.895 90) (layer "F.Fab") hide
      (effects (font (size 0.7 0.7) (thickness 0.15)) (justify left bottom))
    )
    (fp_text user "License: Apache-2.0" (at -1.682 5.895 90) (layer "F.Fab") hide
      (effects (font (size 0.7 0.7) (thickness 0.15)) (justify left bottom))
    )
    (fp_line (start -0.3 -0.3) (end 0.3 -0.3) (layer "F.SilkS") (width 0.15))
    (fp_line (start -0.3 0.3) (end 0.3 0.3) (layer "F.SilkS") (width 0.15))
    (fp_rect (start -1.24 -0.7) (end 1.24 0.7) (layer "F.CrtYd") (width 0.05) (fill none))
    (fp_rect (start -0.8 -0.4) (end 0.8 0.4) (layer "F.Fab") (width 0.15) (fill none))
    (pad "1" smd roundrect (at -0.7 0 90) (size 0.6 0.8) (layers "F.Cu" "F.Paste" "F.Mask") (roundrect_rratio 0.2)
      (net 131 "3V3_SYS") (pintype "passive"))
    (pad "2" smd roundrect (at 0.7 0 90) (size 0.6 0.8) (layers "F.Cu" "F.Paste" "F.Mask") (roundrect_rratio 0.2)
      (net 1 "GND") (pintype "passive"))
  )

  (footprint "sa800u-baseboard-hw-footprints:C_0603_1608Metric" (layer "F.Cu")
    (tedit 5D5E94D2)
    (at 82.29 89.92)
    (descr "Capacitor SMD 0603")
    (tags "capacitor 0603")
    (property "Author" "Antmicro")
    (property "Dielectric" "")
    (property "License" "Apache-2.0")
    (property "MPN" "GRM188R60J226MEA0D")
    (property "Manufacturer" "Murata")
    (property "Sheetfile" "psu.kicad_sch")
    (property "Sheetname" "PSU")
    (property "Val" "22u")
    (property "Voltage" "")
    (attr smd)
    (fp_text reference "C141" (at -1.41 -2.3) (layer "F.SilkS")
      (effects (font (size 0.7 0.7) (thickness 0.15)) (justify left bottom))
    )
    (fp_text value "C_22u_0603" (at 0 1.6) (layer "F.Fab")
      (effects (font (size 0.7 0.7) (thickness 0.15)) (justify left bottom))
    )
    (fp_text user "${REFERENCE}" (at -1.682 3.895) (layer "F.Fab") hide
      (effects (font (size 0.7 0.7) (thickness 0.15)) (justify left bottom))
    )
    (fp_text user "License: Apache-2.0" (at -1.682 5.895) (layer "F.Fab") hide
      (effects (font (size 0.7 0.7) (thickness 0.15)) (justify left bottom))
    )
    (fp_text user "Author: Antmicro" (at -1.682 4.894) (layer "F.Fab") hide
      (effects (font (size 0.7 0.7) (thickness 0.15)) (justify left bottom))
    )
    (fp_line (start -0.3 0.3) (end 0.3 0.3) (layer "F.SilkS") (width 0.15))
    (fp_line (start -0.3 -0.3) (end 0.3 -0.3) (layer "F.SilkS") (width 0.15))
    (fp_rect (start -1.24 -0.7) (end 1.24 0.7) (layer "F.CrtYd") (width 0.05) (fill none))
    (fp_rect (start -0.8 -0.4) (end 0.8 0.4) (layer "F.Fab") (width 0.15) (fill none))
    (pad "1" smd roundrect (at -0.7 0) (size 0.6 0.8) (layers "F.Cu" "F.Paste" "F.Mask") (roundrect_rratio 0.2)
      (net 137 "3V8_SYS") (pintype "passive"))
    (pad "2" smd roundrect (at 0.7 0) (size 0.6 0.8) (layers "F.Cu" "F.Paste" "F.Mask") (roundrect_rratio 0.2)
      (net 1 "GND") (pintype "passive"))
  )

  (footprint "sa800u-baseboard-hw-footprints:C_0603_1608Metric" (layer "F.Cu")
    (tedit 5D5E94D2)
    (at 83.52 109.35 90)
    (descr "Capacitor SMD 0603")
    (tags "capacitor 0603")
    (property "Author" "Antmicro")
    (property "Dielectric" "")
    (property "License" "Apache-2.0")
    (property "MPN" "GRM188R60J226MEA0D")
    (property "Manufacturer" "Murata")
    (property "Sheetfile" "psu.kicad_sch")
    (property "Sheetname" "PSU")
    (property "Val" "22u")
    (property "Voltage" "")
    (attr smd)
    (fp_text reference "C139" (at -3.86 0.37 90) (layer "F.SilkS")
      (effects (font (size 0.7 0.7) (thickness 0.15)) (justify left bottom))
    )
    (fp_text value "C_22u_0603" (at 0 1.6 90) (layer "F.Fab")
      (effects (font (size 0.7 0.7) (thickness 0.15)) (justify left bottom))
    )
    (fp_text user "Author: Antmicro" (at -1.682 4.894 90) (layer "F.Fab") hide
      (effects (font (size 0.7 0.7) (thickness 0.15)) (justify left bottom))
    )
    (fp_text user "${REFERENCE}" (at -1.682 3.895 90) (layer "F.Fab") hide
      (effects (font (size 0.7 0.7) (thickness 0.15)) (justify left bottom))
    )
    (fp_text user "License: Apache-2.0" (at -1.682 5.895 90) (layer "F.Fab") hide
      (effects (font (size 0.7 0.7) (thickness 0.15)) (justify left bottom))
    )
    (fp_line (start -0.3 -0.3) (end 0.3 -0.3) (layer "F.SilkS") (width 0.15))
    (fp_line (start -0.3 0.3) (end 0.3 0.3) (layer "F.SilkS") (width 0.15))
    (fp_rect (start -1.24 -0.7) (end 1.24 0.7) (layer "F.CrtYd") (width 0.05) (fill none))
    (fp_rect (start -0.8 -0.4) (end 0.8 0.4) (layer "F.Fab") (width 0.15) (fill none))
    (pad "1" smd roundrect (at -0.7 0 90) (size 0.6 0.8) (layers "F.Cu" "F.Paste" "F.Mask") (roundrect_rratio 0.2)
      (net 131 "3V3_SYS") (pintype "passive"))
    (pad "2" smd roundrect (at 0.7 0 90) (size 0.6 0.8) (layers "F.Cu" "F.Paste" "F.Mask") (roundrect_rratio 0.2)
      (net 1 "GND") (pintype "passive"))
  )

  (footprint "sa800u-baseboard-hw-footprints:SOD-323" (layer "F.Cu")
    (tedit 617A46E7)
    (at 85.6 83.2)
    (property "Author" "Antmicro")
    (property "License" "Apache-2.0")
    (property "MPN" "STS321045B502")
    (property "Manufacturer" "Cooper Bussmann")
    (property "Sheetfile" "som.kicad_sch")
    (property "Sheetname" "SoM")
    (attr smd)
    (fp_text reference "D13" (at -3.43 1.73) (layer "F.SilkS")
      (effects (font (size 0.7 0.7) (thickness 0.15)) (justify left bottom))
    )
    (fp_text value "STS321045B502" (at 0 1.84) (layer "F.Fab")
      (effects (font (size 0.7 0.7) (thickness 0.15)) (justify left bottom))
    )
    (fp_text user "License: Apache-2.0" (at -1.75 6.24) (layer "F.Fab") hide
      (effects (font (size 0.7 0.7) (thickness 0.15)) (justify left bottom))
    )
    (fp_text user "${REFERENCE}" (at -1.75 3.838) (layer "F.Fab") hide
      (effects (font (size 0.7 0.7) (thickness 0.15)) (justify left bottom))
    )
    (fp_text user "Author: Antmicro" (at -1.75 5.038) (layer "F.Fab") hide
      (effects (font (size 0.7 0.7) (thickness 0.15)) (justify left bottom))
    )
    (fp_line (start 0.95 -0.737) (end 0.95 -0.5) (layer "F.SilkS") (width 0.15))
    (fp_line (start -0.95 -0.75) (end -0.95 -0.5005) (layer "F.SilkS") (width 0.15))
    (fp_line (start 0.9505 0.75) (end 0.6495 0.75) (layer "F.SilkS") (width 0.15))
    (fp_line (start 0.625 -0.737) (end 0.95 -0.737) (layer "F.SilkS") (width 0.15))
    (fp_line (start -0.577 0.75) (end -0.95 0.75) (layer "F.SilkS") (width 0.15))
    (fp_line (start 0.9505 0.5) (end 0.9505 0.75) (layer "F.SilkS") (width 0.15))
    (fp_line (start -0.577 -0.75) (end -0.95 -0.75) (layer "F.SilkS") (width 0.15))
    (fp_line (start -0.95 0.5) (end -0.95 0.75) (layer "F.SilkS") (width 0.15))
    (fp_line (start -0.6 -0.5) (end -0.6 0.498) (layer "F.SilkS") (width 0.15))
    (fp_rect (start -1.6 -0.9) (end 1.6 0.9) (layer "F.CrtYd") (width 0.05) (fill none))
    (fp_line (start -0.902 0.699) (end 0.9 0.699) (layer "F.Fab") (width 0.15))
    (fp_line (start 0.9 -0.701) (end -0.902 -0.701) (layer "F.Fab") (width 0.15))
    (fp_line (start 0.9 -0.701) (end 0.9 0.699) (layer "F.Fab") (width 0.15))
    (fp_line (start -0.902 0.699) (end -0.902 -0.701) (layer "F.Fab") (width 0.15))
    (pad "A" smd rect (at 1.124 0) (size 0.8 0.8) (layers "F.Cu" "F.Paste" "F.Mask")
      (net 424 "/SoM/VBAT_SOM") (pinfunction "1") (pintype "unspecified"))
    (pad "K" smd rect (at -1.125 0) (size 0.8 0.8) (layers "F.Cu" "F.Paste" "F.Mask")
      (net 1 "GND") (pinfunction "2") (pintype "unspecified"))
  )

  (footprint "sa800u-baseboard-hw-footprints:L_Coilcraft_XEL4030" (layer "F.Cu")
    (tedit 6215D867)
    (at 78.85 111.7)
    (property "Author" "Antmicro")
    (property "IMax" "")
    (property "ISat" "")
    (property "License" "Apache-2.0")
    (property "MPN" "XEL4030-222MEC")
    (property "Manufacturer" "Coilcraft")
    (property "MaxCur" "6.1A")
    (property "Sheetfile" "psu.kicad_sch")
    (property "Sheetname" "PSU")
    (property "Size" "4x4")
    (property "Val" "2u2/6.1A")
    (attr smd)
    (fp_text reference "L27" (at 0 -2.65) (layer "F.SilkS")
      (effects (font (size 0.7 0.7) (thickness 0.15)) (justify left bottom))
    )
    (fp_text value "L_2u2_6.1A_XEL4030" (at 0 3.35) (layer "F.Fab")
      (effects (font (size 0.7 0.7) (thickness 0.15)) (justify left bottom))
    )
    (fp_text user "Author: Antmicro" (at -2.15 5.996) (layer "F.Fab") hide
      (effects (font (size 0.7 0.7) (thickness 0.15)) (justify left bottom))
    )
    (fp_text user "License: Apache-2.0" (at -2.15 6.996) (layer "F.Fab") hide
      (effects (font (size 0.7 0.7) (thickness 0.15)) (justify left bottom))
    )
    (fp_text user "${REFERENCE}" (at -2.15 4.996) (layer "F.Fab") hide
      (effects (font (size 0.7 0.7) (thickness 0.15)) (justify left bottom))
    )
    (fp_line (start -1.8 2.2) (end 1.85 2.199) (layer "F.SilkS") (width 0.15))
    (fp_line (start -1.8 -2.2) (end 1.85 -2.201) (layer "F.SilkS") (width 0.15))
    (fp_rect (start -2.45 -2.45) (end 2.45 2.45) (layer "F.CrtYd") (width 0.05) (fill none))
    (fp_line (start -2 -2) (end 1.999 -2) (layer "F.Fab") (width 0.15))
    (fp_line (start -2 1.999) (end -2 -2) (layer "F.Fab") (width 0.15))
    (fp_line (start 1.999 1.999) (end -2 1.999) (layer "F.Fab") (width 0.15))
    (fp_line (start 1.999 -2) (end 1.999 1.999) (layer "F.Fab") (width 0.15))
    (pad "1" smd rect (at -1.186 0) (size 0.98 3.4) (layers "F.Cu" "F.Paste" "F.Mask")
      (net 359 "Net-(C133-Pad2)") (pintype "passive"))
    (pad "2" smd rect (at 1.185 0) (size 0.98 3.4) (layers "F.Cu" "F.Paste" "F.Mask")
      (net 131 "3V3_SYS") (pintype "passive"))
  )

  (footprint "sa800u-baseboard-hw-footprints:R_0402_1005Metric" (layer "F.Cu")
    (tedit 5FD9C158)
    (at 72.05 110.35 -90)
    (descr "Resistor SMD 0402")
    (tags "resistor SMD 0402")
    (property "Author" "Antmicro")
    (property "License" "Apache-2.0")
    (property "MPN" "CR0402-FX-3162GLF")
    (property "Manufacturer" "Bourns")
    (property "Sheetfile" "psu.kicad_sch")
    (property "Sheetname" "PSU")
    (property "Tolerance" "1%")
    (property "Val" "31k6")
    (attr smd)
    (fp_text reference "R137" (at 0.27 1.56 -90) (layer "F.SilkS")
      (effects (font (size 0.7 0.7) (thickness 0.15)) (justify left bottom))
    )
    (fp_text value "R_31k6_0402" (at 0 1.4 -90) (layer "F.Fab")
      (effects (font (size 0.7 0.7) (thickness 0.15)) (justify left bottom))
    )
    (fp_text user "Author: Antmicro" (at -0.95 4.169 -90) (layer "F.Fab") hide
      (effects (font (size 0.7 0.7) (thickness 0.15)) (justify left bottom))
    )
    (fp_text user "License: Apache-2.0" (at -0.95 5.169 -90) (layer "F.Fab") hide
      (effects (font (size 0.7 0.7) (thickness 0.15)) (justify left bottom))
    )
    (fp_text user "${REFERENCE}" (at -0.95 3.168 -90) (layer "F.Fab") hide
      (effects (font (size 0.7 0.7) (thickness 0.15)) (justify left bottom))
    )
    (fp_rect (start -0.93 -0.47) (end 0.93 0.47) (layer "F.CrtYd") (width 0.05) (fill none))
    (fp_rect (start -0.5 -0.25) (end 0.5 0.25) (layer "F.Fab") (width 0.15) (fill none))
    (pad "1" smd roundrect (at -0.485 0 270) (size 0.59 0.64) (layers "F.Cu" "F.Paste" "F.Mask") (roundrect_rratio 0.25)
      (net 131 "3V3_SYS") (pintype "passive"))
    (pad "2" smd roundrect (at 0.485 0 270) (size 0.59 0.64) (layers "F.Cu" "F.Paste" "F.Mask") (roundrect_rratio 0.25)
      (net 410 "Net-(R137-Pad2)") (pintype "passive"))
  )

  (footprint "sa800u-baseboard-hw-footprints:R_0402_1005Metric" (layer "F.Cu")
    (tedit 5FD9C158)
    (at 71.05 110.35 90)
    (descr "Resistor SMD 0402")
    (tags "resistor SMD 0402")
    (property "Author" "Antmicro")
    (property "License" "Apache-2.0")
    (property "MPN" "CR0402-FX-1002GLF")
    (property "Manufacturer" "Bourns")
    (property "Sheetfile" "psu.kicad_sch")
    (property "Sheetname" "PSU")
    (property "Tolerance" "1%")
    (property "Val" "10k")
    (attr smd)
    (fp_text reference "R138" (at -0.25 -1.53 90) (layer "F.SilkS")
      (effects (font (size 0.7 0.7) (thickness 0.15)) (justify left bottom))
    )
    (fp_text value "R_10k_0402" (at 0 1.4 90) (layer "F.Fab")
      (effects (font (size 0.7 0.7) (thickness 0.15)) (justify left bottom))
    )
    (fp_text user "License: Apache-2.0" (at -0.95 5.169 90) (layer "F.Fab") hide
      (effects (font (size 0.7 0.7) (thickness 0.15)) (justify left bottom))
    )
    (fp_text user "${REFERENCE}" (at -0.95 3.168 90) (layer "F.Fab") hide
      (effects (font (size 0.7 0.7) (thickness 0.15)) (justify left bottom))
    )
    (fp_text user "Author: Antmicro" (at -0.95 4.169 90) (layer "F.Fab") hide
      (effects (font (size 0.7 0.7) (thickness 0.15)) (justify left bottom))
    )
    (fp_rect (start -0.93 -0.47) (end 0.93 0.47) (layer "F.CrtYd") (width 0.05) (fill none))
    (fp_rect (start -0.5 -0.25) (end 0.5 0.25) (layer "F.Fab") (width 0.15) (fill none))
    (pad "1" smd roundrect (at -0.485 0 90) (size 0.59 0.64) (layers "F.Cu" "F.Paste" "F.Mask") (roundrect_rratio 0.25)
      (net 410 "Net-(R137-Pad2)") (pintype "passive"))
    (pad "2" smd roundrect (at 0.485 0 90) (size 0.59 0.64) (layers "F.Cu" "F.Paste" "F.Mask") (roundrect_rratio 0.25)
      (net 1 "GND") (pintype "passive"))
  )

  (footprint "sa800u-baseboard-hw-footprints:R_0402_1005Metric" (layer "F.Cu")
    (tedit 5FD9C158)
    (at 141.7 143.6 90)
    (descr "Resistor SMD 0402")
    (tags "resistor SMD 0402")
    (property "Author" "Antmicro")
    (property "License" "Apache-2.0")
    (property "MPN" "CR0402-FX-1002GLF")
    (property "Manufacturer" "Bourns")
    (property "Sheetfile" "hdmi-converter.kicad_sch")
    (property "Sheetname" "HDMI converter")
    (property "Tolerance" "1%")
    (property "Val" "10k")
    (attr smd)
    (fp_text reference "R41" (at -1.04 1.38 90) (layer "F.SilkS")
      (effects (font (size 0.7 0.7) (thickness 0.15)) (justify left bottom))
    )
    (fp_text value "R_10k_0402" (at 0 1.4 90) (layer "F.Fab")
      (effects (font (size 0.7 0.7) (thickness 0.15)) (justify left bottom))
    )
    (fp_text user "${REFERENCE}" (at -0.95 3.168 90) (layer "F.Fab") hide
      (effects (font (size 0.7 0.7) (thickness 0.15)) (justify left bottom))
    )
    (fp_text user "Author: Antmicro" (at -0.95 4.169 90) (layer "F.Fab") hide
      (effects (font (size 0.7 0.7) (thickness 0.15)) (justify left bottom))
    )
    (fp_text user "License: Apache-2.0" (at -0.95 5.169 90) (layer "F.Fab") hide
      (effects (font (size 0.7 0.7) (thickness 0.15)) (justify left bottom))
    )
    (fp_rect (start -0.93 -0.47) (end 0.93 0.47) (layer "F.CrtYd") (width 0.05) (fill none))
    (fp_rect (start -0.5 -0.25) (end 0.5 0.25) (layer "F.Fab") (width 0.15) (fill none))
    (pad "1" smd roundrect (at -0.485 0 90) (size 0.59 0.64) (layers "F.Cu" "F.Paste" "F.Mask") (roundrect_rratio 0.25)
      (net 245 "/HDMI converter/5V_HDMI") (pintype "passive"))
    (pad "2" smd roundrect (at 0.485 0 90) (size 0.59 0.64) (layers "F.Cu" "F.Paste" "F.Mask") (roundrect_rratio 0.25)
      (net 1 "GND") (pintype "passive"))
  )

  (footprint "sa800u-baseboard-hw-footprints:R_0402_1005Metric" (layer "F.Cu")
    (tedit 5FD9C158)
    (at 147.8 144)
    (descr "Resistor SMD 0402")
    (tags "resistor SMD 0402")
    (property "Author" "Antmicro")
    (property "License" "Apache-2.0")
    (property "MPN" "CR0402-FX-2002GLF")
    (property "Manufacturer" "Bourns")
    (property "Sheetfile" "hdmi-converter.kicad_sch")
    (property "Sheetname" "HDMI converter")
    (property "Tolerance" "1%")
    (property "Val" "20k")
    (attr smd)
    (fp_text reference "R43" (at 0.83 0.41) (layer "F.SilkS")
      (effects (font (size 0.7 0.7) (thickness 0.15)) (justify left bottom))
    )
    (fp_text value "R_20k_0402" (at 0 1.4) (layer "F.Fab")
      (effects (font (size 0.7 0.7) (thickness 0.15)) (justify left bottom))
    )
    (fp_text user "License: Apache-2.0" (at -0.95 5.169) (layer "F.Fab") hide
      (effects (font (size 0.7 0.7) (thickness 0.15)) (justify left bottom))
    )
    (fp_text user "Author: Antmicro" (at -0.95 4.169) (layer "F.Fab") hide
      (effects (font (size 0.7 0.7) (thickness 0.15)) (justify left bottom))
    )
    (fp_text user "${REFERENCE}" (at -0.95 3.168) (layer "F.Fab") hide
      (effects (font (size 0.7 0.7) (thickness 0.15)) (justify left bottom))
    )
    (fp_rect (start -0.93 -0.47) (end 0.93 0.47) (layer "F.CrtYd") (width 0.05) (fill none))
    (fp_rect (start -0.5 -0.25) (end 0.5 0.25) (layer "F.Fab") (width 0.15) (fill none))
    (pad "1" smd roundrect (at -0.485 0) (size 0.59 0.64) (layers "F.Cu" "F.Paste" "F.Mask") (roundrect_rratio 0.25)
      (net 234 "/HDMI converter/HDMI_DETECT") (pintype "passive"))
    (pad "2" smd roundrect (at 0.485 0) (size 0.59 0.64) (layers "F.Cu" "F.Paste" "F.Mask") (roundrect_rratio 0.25)
      (net 1 "GND") (pintype "passive"))
  )

  (footprint "sa800u-baseboard-hw-footprints:R_0402_1005Metric" (layer "F.Cu")
    (tedit 5FD9C158)
    (at 149.9 107.9 180)
    (descr "Resistor SMD 0402")
    (tags "resistor SMD 0402")
    (property "Author" "Antmicro")
    (property "License" "Apache-2.0")
    (property "MPN" "CR0402-FX-1001GLF")
    (property "Manufacturer" "Bourns")
    (property "Sheetfile" "som.kicad_sch")
    (property "Sheetname" "SoM")
    (property "Tolerance" "1%")
    (property "Val" "1k")
    (attr smd)
    (fp_text reference "R76" (at 1.03 -1.32 180) (layer "F.SilkS")
      (effects (font (size 0.7 0.7) (thickness 0.15)) (justify left bottom))
    )
    (fp_text value "R_1k_0402" (at 0 1.4 180) (layer "F.Fab")
      (effects (font (size 0.7 0.7) (thickness 0.15)) (justify left bottom))
    )
    (fp_text user "Author: Antmicro" (at -0.95 4.169 180) (layer "F.Fab") hide
      (effects (font (size 0.7 0.7) (thickness 0.15)) (justify left bottom))
    )
    (fp_text user "License: Apache-2.0" (at -0.95 5.169 180) (layer "F.Fab") hide
      (effects (font (size 0.7 0.7) (thickness 0.15)) (justify left bottom))
    )
    (fp_text user "${REFERENCE}" (at -0.95 3.168 180) (layer "F.Fab") hide
      (effects (font (size 0.7 0.7) (thickness 0.15)) (justify left bottom))
    )
    (fp_rect (start -0.93 -0.47) (end 0.93 0.47) (layer "F.CrtYd") (width 0.05) (fill none))
    (fp_rect (start -0.5 -0.25) (end 0.5 0.25) (layer "F.Fab") (width 0.15) (fill none))
    (pad "1" smd roundrect (at -0.485 0 180) (size 0.59 0.64) (layers "F.Cu" "F.Paste" "F.Mask") (roundrect_rratio 0.25)
      (net 343 "/SoM/VOL_DOWN_R") (pintype "passive"))
    (pad "2" smd roundrect (at 0.485 0 180) (size 0.59 0.64) (layers "F.Cu" "F.Paste" "F.Mask") (roundrect_rratio 0.25)
      (net 97 "VOL_DOWN") (pintype "passive"))
  )

  (footprint "sa800u-baseboard-hw-footprints:R_0402_1005Metric" (layer "F.Cu")
    (tedit 5FD9C158)
    (at 150.15 95.9 180)
    (descr "Resistor SMD 0402")
    (tags "resistor SMD 0402")
    (property "Author" "Antmicro")
    (property "License" "Apache-2.0")
    (property "MPN" "CR0402-FX-1001GLF")
    (property "Manufacturer" "Bourns")
    (property "Sheetfile" "som.kicad_sch")
    (property "Sheetname" "SoM")
    (property "Tolerance" "1%")
    (property "Val" "1k")
    (attr smd)
    (fp_text reference "R73" (at 2.96 -0.86 180) (layer "F.SilkS")
      (effects (font (size 0.7 0.7) (thickness 0.15)) (justify left bottom))
    )
    (fp_text value "R_1k_0402" (at 0 1.4 180) (layer "F.Fab")
      (effects (font (size 0.7 0.7) (thickness 0.15)) (justify left bottom))
    )
    (fp_text user "${REFERENCE}" (at -0.95 3.168 180) (layer "F.Fab") hide
      (effects (font (size 0.7 0.7) (thickness 0.15)) (justify left bottom))
    )
    (fp_text user "License: Apache-2.0" (at -0.95 5.169 180) (layer "F.Fab") hide
      (effects (font (size 0.7 0.7) (thickness 0.15)) (justify left bottom))
    )
    (fp_text user "Author: Antmicro" (at -0.95 4.169 180) (layer "F.Fab") hide
      (effects (font (size 0.7 0.7) (thickness 0.15)) (justify left bottom))
    )
    (fp_rect (start -0.93 -0.47) (end 0.93 0.47) (layer "F.CrtYd") (width 0.05) (fill none))
    (fp_rect (start -0.5 -0.25) (end 0.5 0.25) (layer "F.Fab") (width 0.15) (fill none))
    (pad "1" smd roundrect (at -0.485 0 180) (size 0.59 0.64) (layers "F.Cu" "F.Paste" "F.Mask") (roundrect_rratio 0.25)
      (net 344 "/SoM/HOME_KEY_R") (pintype "passive"))
    (pad "2" smd roundrect (at 0.485 0 180) (size 0.59 0.64) (layers "F.Cu" "F.Paste" "F.Mask") (roundrect_rratio 0.25)
      (net 94 "HOME_KEY") (pintype "passive"))
  )

  (footprint "sa800u-baseboard-hw-footprints:R_0402_1005Metric" (layer "F.Cu")
    (tedit 5FD9C158)
    (at 149.9 101.9 180)
    (descr "Resistor SMD 0402")
    (tags "resistor SMD 0402")
    (property "Author" "Antmicro")
    (property "License" "Apache-2.0")
    (property "MPN" "CR0402-FX-1001GLF")
    (property "Manufacturer" "Bourns")
    (property "Sheetfile" "som.kicad_sch")
    (property "Sheetname" "SoM")
    (property "Tolerance" "1%")
    (property "Val" "1k")
    (attr smd)
    (fp_text reference "R74" (at 3.06 -0.35 180) (layer "F.SilkS")
      (effects (font (size 0.7 0.7) (thickness 0.15)) (justify left bottom))
    )
    (fp_text value "R_1k_0402" (at 0 1.4 180) (layer "F.Fab")
      (effects (font (size 0.7 0.7) (thickness 0.15)) (justify left bottom))
    )
    (fp_text user "Author: Antmicro" (at -0.95 4.169 180) (layer "F.Fab") hide
      (effects (font (size 0.7 0.7) (thickness 0.15)) (justify left bottom))
    )
    (fp_text user "License: Apache-2.0" (at -0.95 5.169 180) (layer "F.Fab") hide
      (effects (font (size 0.7 0.7) (thickness 0.15)) (justify left bottom))
    )
    (fp_text user "${REFERENCE}" (at -0.95 3.168 180) (layer "F.Fab") hide
      (effects (font (size 0.7 0.7) (thickness 0.15)) (justify left bottom))
    )
    (fp_rect (start -0.93 -0.47) (end 0.93 0.47) (layer "F.CrtYd") (width 0.05) (fill none))
    (fp_rect (start -0.5 -0.25) (end 0.5 0.25) (layer "F.Fab") (width 0.15) (fill none))
    (pad "1" smd roundrect (at -0.485 0 180) (size 0.59 0.64) (layers "F.Cu" "F.Paste" "F.Mask") (roundrect_rratio 0.25)
      (net 345 "/SoM/VOL_UP_R") (pintype "passive"))
    (pad "2" smd roundrect (at 0.485 0 180) (size 0.59 0.64) (layers "F.Cu" "F.Paste" "F.Mask") (roundrect_rratio 0.25)
      (net 96 "VOL_UP") (pintype "passive"))
  )

  (footprint "sa800u-baseboard-hw-footprints:R_0402_1005Metric" (layer "F.Cu")
    (tedit 5FD9C158)
    (at 149.9 113.9 180)
    (descr "Resistor SMD 0402")
    (tags "resistor SMD 0402")
    (property "Author" "Antmicro")
    (property "License" "Apache-2.0")
    (property "MPN" "CR0402-FX-1001GLF")
    (property "Manufacturer" "Bourns")
    (property "Sheetfile" "som.kicad_sch")
    (property "Sheetname" "SoM")
    (property "Tolerance" "1%")
    (property "Val" "1k")
    (attr smd)
    (fp_text reference "R75" (at 1.15 -1.33 180) (layer "F.SilkS")
      (effects (font (size 0.7 0.7) (thickness 0.15)) (justify left bottom))
    )
    (fp_text value "R_1k_0402" (at 0 1.4 180) (layer "F.Fab")
      (effects (font (size 0.7 0.7) (thickness 0.15)) (justify left bottom))
    )
    (fp_text user "Author: Antmicro" (at -0.95 4.169 180) (layer "F.Fab") hide
      (effects (font (size 0.7 0.7) (thickness 0.15)) (justify left bottom))
    )
    (fp_text user "${REFERENCE}" (at -0.95 3.168 180) (layer "F.Fab") hide
      (effects (font (size 0.7 0.7) (thickness 0.15)) (justify left bottom))
    )
    (fp_text user "License: Apache-2.0" (at -0.95 5.169 180) (layer "F.Fab") hide
      (effects (font (size 0.7 0.7) (thickness 0.15)) (justify left bottom))
    )
    (fp_rect (start -0.93 -0.47) (end 0.93 0.47) (layer "F.CrtYd") (width 0.05) (fill none))
    (fp_rect (start -0.5 -0.25) (end 0.5 0.25) (layer "F.Fab") (width 0.15) (fill none))
    (pad "1" smd roundrect (at -0.485 0 180) (size 0.59 0.64) (layers "F.Cu" "F.Paste" "F.Mask") (roundrect_rratio 0.25)
      (net 346 "/SoM/PWR_R") (pintype "passive"))
    (pad "2" smd roundrect (at 0.485 0 180) (size 0.59 0.64) (layers "F.Cu" "F.Paste" "F.Mask") (roundrect_rratio 0.25)
      (net 95 "PWRKEY") (pintype "passive"))
  )

  (footprint "sa800u-baseboard-hw-footprints:R_0402_1005Metric" (layer "F.Cu")
    (tedit 5FD9C158)
    (at 71 119.6 90)
    (descr "Resistor SMD 0402")
    (tags "resistor SMD 0402")
    (property "Author" "Antmicro")
    (property "License" "Apache-2.0")
    (property "MPN" "CR0402-FX-2552GLF")
    (property "Manufacturer" "Bourns")
    (property "Sheetfile" "psu.kicad_sch")
    (property "Sheetname" "PSU")
    (property "Tolerance" "1%")
    (property "Val" "25k5")
    (attr smd)
    (fp_text reference "R129" (at -3.74 0.37 90) (layer "F.SilkS")
      (effects (font (size 0.7 0.7) (thickness 0.15)) (justify left bottom))
    )
    (fp_text value "R_25k5_0402" (at 0 1.4 90) (layer "F.Fab")
      (effects (font (size 0.7 0.7) (thickness 0.15)) (justify left bottom))
    )
    (fp_text user "Author: Antmicro" (at -0.95 4.169 90) (layer "F.Fab") hide
      (effects (font (size 0.7 0.7) (thickness 0.15)) (justify left bottom))
    )
    (fp_text user "${REFERENCE}" (at -0.95 3.168 90) (layer "F.Fab") hide
      (effects (font (size 0.7 0.7) (thickness 0.15)) (justify left bottom))
    )
    (fp_text user "License: Apache-2.0" (at -0.95 5.169 90) (layer "F.Fab") hide
      (effects (font (size 0.7 0.7) (thickness 0.15)) (justify left bottom))
    )
    (fp_rect (start -0.93 -0.47) (end 0.93 0.47) (layer "F.CrtYd") (width 0.05) (fill none))
    (fp_rect (start -0.5 -0.25) (end 0.5 0.25) (layer "F.Fab") (width 0.15) (fill none))
    (pad "1" smd roundrect (at -0.485 0 90) (size 0.59 0.64) (layers "F.Cu" "F.Paste" "F.Mask") (roundrect_rratio 0.25)
      (net 156 "/PSU/BYPASS_EN") (pintype "passive"))
    (pad "2" smd roundrect (at 0.485 0 90) (size 0.59 0.64) (layers "F.Cu" "F.Paste" "F.Mask") (roundrect_rratio 0.25)
      (net 164 "/PSU/5V_DC_DC_ENABLE") (pintype "passive"))
  )

  (footprint "sa800u-baseboard-hw-footprints:R_0402_1005Metric" (layer "F.Cu")
    (tedit 5FD9C158)
    (at 71.6 115.3 180)
    (descr "Resistor SMD 0402")
    (tags "resistor SMD 0402")
    (property "Author" "Antmicro")
    (property "License" "Apache-2.0")
    (property "MPN" "CR0402-FX-1002GLF")
    (property "Manufacturer" "Bourns")
    (property "Sheetfile" "psu.kicad_sch")
    (property "Sheetname" "PSU")
    (property "Tolerance" "1%")
    (property "Val" "10k")
    (attr smd)
    (fp_text reference "R130" (at -0.94 -4.74 180) (layer "F.SilkS")
      (effects (font (size 0.7 0.7) (thickness 0.15)) (justify left bottom))
    )
    (fp_text value "R_10k_0402" (at 0 1.4 180) (layer "F.Fab")
      (effects (font (size 0.7 0.7) (thickness 0.15)) (justify left bottom))
    )
    (fp_text user "License: Apache-2.0" (at -0.95 5.169 180) (layer "F.Fab") hide
      (effects (font (size 0.7 0.7) (thickness 0.15)) (justify left bottom))
    )
    (fp_text user "Author: Antmicro" (at -0.95 4.169 180) (layer "F.Fab") hide
      (effects (font (size 0.7 0.7) (thickness 0.15)) (justify left bottom))
    )
    (fp_text user "${REFERENCE}" (at -0.95 3.168 180) (layer "F.Fab") hide
      (effects (font (size 0.7 0.7) (thickness 0.15)) (justify left bottom))
    )
    (fp_rect (start -0.93 -0.47) (end 0.93 0.47) (layer "F.CrtYd") (width 0.05) (fill none))
    (fp_rect (start -0.5 -0.25) (end 0.5 0.25) (layer "F.Fab") (width 0.15) (fill none))
    (pad "1" smd roundrect (at -0.485 0 180) (size 0.59 0.64) (layers "F.Cu" "F.Paste" "F.Mask") (roundrect_rratio 0.25)
      (net 164 "/PSU/5V_DC_DC_ENABLE") (pintype "passive"))
    (pad "2" smd roundrect (at 0.485 0 180) (size 0.59 0.64) (layers "F.Cu" "F.Paste" "F.Mask") (roundrect_rratio 0.25)
      (net 1 "GND") (pintype "passive"))
  )

  (footprint "sa800u-baseboard-hw-footprints:R_0402_1005Metric" (layer "F.Cu")
    (tedit 5FD9C158)
    (at 71.6 116.3 180)
    (descr "Resistor SMD 0402")
    (tags "resistor SMD 0402")
    (property "Author" "Antmicro")
    (property "License" "Apache-2.0")
    (property "MPN" "CR0402-FX-1002GLF")
    (property "Manufacturer" "Bourns")
    (property "Sheetfile" "psu.kicad_sch")
    (property "Sheetname" "PSU")
    (property "Tolerance" "1%")
    (property "Val" "10k")
    (attr smd)
    (fp_text reference "R142" (at -0.94 -4.64 180) (layer "F.SilkS")
      (effects (font (size 0.7 0.7) (thickness 0.15)) (justify left bottom))
    )
    (fp_text value "R_10k_0402" (at 0 1.4 180) (layer "F.Fab")
      (effects (font (size 0.7 0.7) (thickness 0.15)) (justify left bottom))
    )
    (fp_text user "${REFERENCE}" (at -0.95 3.168 180) (layer "F.Fab") hide
      (effects (font (size 0.7 0.7) (thickness 0.15)) (justify left bottom))
    )
    (fp_text user "License: Apache-2.0" (at -0.95 5.169 180) (layer "F.Fab") hide
      (effects (font (size 0.7 0.7) (thickness 0.15)) (justify left bottom))
    )
    (fp_text user "Author: Antmicro" (at -0.95 4.169 180) (layer "F.Fab") hide
      (effects (font (size 0.7 0.7) (thickness 0.15)) (justify left bottom))
    )
    (fp_rect (start -0.93 -0.47) (end 0.93 0.47) (layer "F.CrtYd") (width 0.05) (fill none))
    (fp_rect (start -0.5 -0.25) (end 0.5 0.25) (layer "F.Fab") (width 0.15) (fill none))
    (pad "1" smd roundrect (at -0.485 0 180) (size 0.59 0.64) (layers "F.Cu" "F.Paste" "F.Mask") (roundrect_rratio 0.25)
      (net 173 "Net-(R141-Pad2)") (pintype "passive"))
    (pad "2" smd roundrect (at 0.485 0 180) (size 0.59 0.64) (layers "F.Cu" "F.Paste" "F.Mask") (roundrect_rratio 0.25)
      (net 1 "GND") (pintype "passive"))
  )

  (footprint "sa800u-baseboard-hw-footprints:AP62301WU-7-TSOT23-6" (layer "F.Cu")
    (tedit 6215EA50)
    (at 74.65 111.8 90)
    (property "Author" "Antmicro")
    (property "License" "Apache-2.0")
    (property "MPN" "AP62301WU-7")
    (property "Manufacturer" "Diodes Incorporated")
    (property "Sheetfile" "psu.kicad_sch")
    (property "Sheetname" "PSU")
    (attr smd)
    (fp_text reference "U20" (at -2.43 -0.33 180) (layer "F.SilkS")
      (effects (font (size 0.7 0.7) (thickness 0.15)) (justify left bottom))
    )
    (fp_text value "AP62301WU-7" (at -0.005 2.6 90) (layer "F.Fab")
      (effects (font (size 0.7 0.7) (thickness 0.15)) (justify left bottom))
    )
    (fp_text user "${REFERENCE}" (at -1.893 6.168 90) (layer "F.Fab") hide
      (effects (font (size 0.7 0.7) (thickness 0.15)) (justify left bottom))
    )
    (fp_text user "Author: Antmicro" (at -1.893 7.368 90) (layer "F.Fab") hide
      (effects (font (size 0.7 0.7) (thickness 0.15)) (justify left bottom))
    )
    (fp_text user "License: Apache-2.0" (at -1.893 4.967 90) (layer "F.Fab") hide
      (effects (font (size 0.7 0.7) (thickness 0.15)) (justify left bottom))
    )
    (fp_line (start 1.48 -0.72) (end 1.38 -0.72) (layer "F.SilkS") (width 0.15))
    (fp_line (start 1.479 0.73) (end 1.38 0.73) (layer "F.SilkS") (width 0.15))
    (fp_line (start 1.48 -0.72) (end 1.479 0.73) (layer "F.SilkS") (width 0.15))
    (fp_line (start -1.4805 0.725) (end -1.3905 0.725) (layer "F.SilkS") (width 0.15))
    (fp_line (start -1.4805 0.725) (end -1.4795 -0.725) (layer "F.SilkS") (width 0.15))
    (fp_line (start -1.4795 -0.725) (end -1.3905 -0.725) (layer "F.SilkS") (width 0.15))
    (fp_circle (center -1.499 1.236) (end -1.45 1.236) (layer "F.SilkS") (width 0.15) (fill solid))
    (fp_rect (start -1.65 -1.61) (end 1.65 1.61) (layer "F.CrtYd") (width 0.05) (fill none))
    (fp_line (start -1.102 0.916) (end 1.523 0.916) (layer "F.Fab") (width 0.15))
    (fp_line (start -1.527 0.491) (end -1.527 -0.833) (layer "F.Fab") (width 0.15))
    (fp_line (start 1.523 -0.833) (end 1.523 0.916) (layer "F.Fab") (width 0.15))
    (fp_line (start -1.527 0.491) (end -1.102 0.916) (layer "F.Fab") (width 0.15))
    (fp_line (start -1.527 -0.833) (end 1.523 -0.833) (layer "F.Fab") (width 0.15))
    (pad "1" smd rect (at -0.952 1.18 90) (size 0.7 0.8) (layers "F.Cu" "F.Paste" "F.Mask")
      (net 1 "GND") (pinfunction "GND") (pintype "power_in"))
    (pad "2" smd rect (at -0.001 1.18 90) (size 0.7 0.8) (layers "F.Cu" "F.Paste" "F.Mask")
      (net 359 "Net-(C133-Pad2)") (pinfunction "SW") (pintype "power_out"))
    (pad "3" smd rect (at 0.947 1.18 90) (size 0.7 0.8) (layers "F.Cu" "F.Paste" "F.Mask")
      (net 74 "VDD") (pinfunction "VIN") (pintype "power_in"))
    (pad "4" smd rect (at 0.947 -1.18 90) (size 0.7 0.8) (layers "F.Cu" "F.Paste" "F.Mask")
      (net 410 "Net-(R137-Pad2)") (pinfunction "FB") (pintype "input"))
    (pad "5" smd rect (at -0.001 -1.18 90) (size 0.7 0.8) (layers "F.Cu" "F.Paste" "F.Mask")
      (net 407 "Net-(R127-Pad2)") (pinfunction "EN") (pintype "input"))
    (pad "6" smd rect (at -0.952 -1.18 90) (size 0.7 0.8) (layers "F.Cu" "F.Paste" "F.Mask")
      (net 358 "Net-(C133-Pad1)") (pinfunction "BST") (pintype "output"))
  )

  (footprint "sa800u-baseboard-hw-footprints:C_0402_1005Metric" (layer "F.Cu")
    (tedit 616D63CF)
    (at 86.8 139.875 -90)
    (descr "Capacitor SMD 0402")
    (tags "capacitor SMD 0402")
    (property "Author" "Antmicro")
    (property "Dielectric" "")
    (property "License" "Apache-2.0")
    (property "MPN" "C1005X6S1A105K050BC")
    (property "Manufacturer" "TDK")
    (property "Sheetfile" "usb-pd.kicad_sch")
    (property "Sheetname" "USB-PD")
    (property "Val" "1u")
    (property "Voltage" "")
    (attr smd)
    (fp_text reference "C156" (at 2.595 -3.37 -90) (layer "F.SilkS")
      (effects (font (size 0.7 0.7) (thickness 0.15)) (justify left bottom))
    )
    (fp_text value "C_1u_0402" (at 0 1.4 -90) (layer "F.Fab")
      (effects (font (size 0.7 0.7) (thickness 0.15)) (justify left bottom))
    )
    (fp_text user "License: Apache-2.0" (at -0.932 5.17 -90) (layer "F.Fab") hide
      (effects (font (size 0.7 0.7) (thickness 0.15)) (justify left bottom))
    )
    (fp_text user "Author: Antmicro" (at -0.932 4.17 -90) (layer "F.Fab") hide
      (effects (font (size 0.7 0.7) (thickness 0.15)) (justify left bottom))
    )
    (fp_text user "${REFERENCE}" (at -0.932 3.168 -90) (layer "F.Fab") hide
      (effects (font (size 0.7 0.7) (thickness 0.15)) (justify left bottom))
    )
    (fp_rect (start -0.94 -0.47) (end 0.94 0.47) (layer "F.CrtYd") (width 0.05) (fill none))
    (fp_rect (start -0.499 -0.249) (end 0.499 0.249) (layer "F.Fab") (width 0.15) (fill none))
    (pad "1" smd roundrect (at -0.484 0 270) (size 0.59 0.64) (layers "F.Cu" "F.Paste" "F.Mask") (roundrect_rratio 0.25)
      (net 140 "/USB-PD/VREG_1V2") (pintype "passive"))
    (pad "2" smd roundrect (at 0.484 0 270) (size 0.59 0.64) (layers "F.Cu" "F.Paste" "F.Mask") (roundrect_rratio 0.25)
      (net 1 "GND") (pintype "passive"))
  )

  (footprint "sa800u-baseboard-hw-footprints:C_0402_1005Metric" (layer "F.Cu")
    (tedit 616D63CF)
    (at 88.8 139.875 -90)
    (descr "Capacitor SMD 0402")
    (tags "capacitor SMD 0402")
    (property "Author" "Antmicro")
    (property "Dielectric" "")
    (property "License" "Apache-2.0")
    (property "MPN" "C1005X6S1A105K050BC")
    (property "Manufacturer" "TDK")
    (property "Sheetfile" "usb-pd.kicad_sch")
    (property "Sheetname" "USB-PD")
    (property "Val" "1u")
    (property "Voltage" "")
    (attr smd)
    (fp_text reference "C157" (at 2.595 -3.37 -90) (layer "F.SilkS")
      (effects (font (size 0.7 0.7) (thickness 0.15)) (justify left bottom))
    )
    (fp_text value "C_1u_0402" (at 0 1.4 -90) (layer "F.Fab")
      (effects (font (size 0.7 0.7) (thickness 0.15)) (justify left bottom))
    )
    (fp_text user "Author: Antmicro" (at -0.932 4.17 -90) (layer "F.Fab") hide
      (effects (font (size 0.7 0.7) (thickness 0.15)) (justify left bottom))
    )
    (fp_text user "${REFERENCE}" (at -0.932 3.168 -90) (layer "F.Fab") hide
      (effects (font (size 0.7 0.7) (thickness 0.15)) (justify left bottom))
    )
    (fp_text user "License: Apache-2.0" (at -0.932 5.17 -90) (layer "F.Fab") hide
      (effects (font (size 0.7 0.7) (thickness 0.15)) (justify left bottom))
    )
    (fp_rect (start -0.94 -0.47) (end 0.94 0.47) (layer "F.CrtYd") (width 0.05) (fill none))
    (fp_rect (start -0.499 -0.249) (end 0.499 0.249) (layer "F.Fab") (width 0.15) (fill none))
    (pad "1" smd roundrect (at -0.484 0 270) (size 0.59 0.64) (layers "F.Cu" "F.Paste" "F.Mask") (roundrect_rratio 0.25)
      (net 107 "/USB-PD/PD_VBUS") (pintype "passive"))
    (pad "2" smd roundrect (at 0.484 0 270) (size 0.59 0.64) (layers "F.Cu" "F.Paste" "F.Mask") (roundrect_rratio 0.25)
      (net 1 "GND") (pintype "passive"))
  )

  (footprint "sa800u-baseboard-hw-footprints:C_0402_1005Metric" (layer "F.Cu")
    (tedit 616D63CF)
    (at 87.8 139.875 -90)
    (descr "Capacitor SMD 0402")
    (tags "capacitor SMD 0402")
    (property "Author" "Antmicro")
    (property "Dielectric" "")
    (property "License" "Apache-2.0")
    (property "MPN" "C1005X6S1A105K050BC")
    (property "Manufacturer" "TDK")
    (property "Sheetfile" "usb-pd.kicad_sch")
    (property "Sheetname" "USB-PD")
    (property "Val" "1u")
    (property "Voltage" "")
    (attr smd)
    (fp_text reference "C154" (at 2.595 -3.37 -90) (layer "F.SilkS")
      (effects (font (size 0.7 0.7) (thickness 0.15)) (justify left bottom))
    )
    (fp_text value "C_1u_0402" (at 0 1.4 -90) (layer "F.Fab")
      (effects (font (size 0.7 0.7) (thickness 0.15)) (justify left bottom))
    )
    (fp_text user "License: Apache-2.0" (at -0.932 5.17 -90) (layer "F.Fab") hide
      (effects (font (size 0.7 0.7) (thickness 0.15)) (justify left bottom))
    )
    (fp_text user "${REFERENCE}" (at -0.932 3.168 -90) (layer "F.Fab") hide
      (effects (font (size 0.7 0.7) (thickness 0.15)) (justify left bottom))
    )
    (fp_text user "Author: Antmicro" (at -0.932 4.17 -90) (layer "F.Fab") hide
      (effects (font (size 0.7 0.7) (thickness 0.15)) (justify left bottom))
    )
    (fp_rect (start -0.94 -0.47) (end 0.94 0.47) (layer "F.CrtYd") (width 0.05) (fill none))
    (fp_rect (start -0.499 -0.249) (end 0.499 0.249) (layer "F.Fab") (width 0.15) (fill none))
    (pad "1" smd roundrect (at -0.484 0 270) (size 0.59 0.64) (layers "F.Cu" "F.Paste" "F.Mask") (roundrect_rratio 0.25)
      (net 141 "/USB-PD/VREG_2V7") (pintype "passive"))
    (pad "2" smd roundrect (at 0.484 0 270) (size 0.59 0.64) (layers "F.Cu" "F.Paste" "F.Mask") (roundrect_rratio 0.25)
      (net 1 "GND") (pintype "passive"))
  )

  (footprint "sa800u-baseboard-hw-footprints:QFN-24-1EP_4x4mm_EP2.1x2.1mm" (layer "F.Cu")
    (tedit 5DC5F6A3)
    (at 87.05 136.275 180)
    (descr "QFN, 24 Pin")
    (tags "QFN NoLead")
    (property "Author" "Antmicro")
    (property "License" "Apache-2.0")
    (property "MPN" "STUSB4500QTR")
    (property "Manufacturer" "STMicroelectronics")
    (property "Sheetfile" "usb-pd.kicad_sch")
    (property "Sheetname" "USB-PD")
    (attr smd)
    (fp_text reference "U23" (at -2.31 -0.415 180) (layer "F.SilkS")
      (effects (font (size 0.7 0.7) (thickness 0.15)) (justify left bottom))
    )
    (fp_text value "STUSB4500_QFN" (at 0 3.4 180) (layer "F.Fab")
      (effects (font (size 0.7 0.7) (thickness 0.15)) (justify left bottom))
    )
    (fp_text user "${REFERENCE}" (at -2.503 5.4 180) (layer "F.Fab") hide
      (effects (font (size 0.7 0.7) (thickness 0.15)) (justify left bottom))
    )
    (fp_text user "Author: Antmicro" (at -2.503 7.8 180) (layer "F.Fab") hide
      (effects (font (size 0.7 0.7) (thickness 0.15)) (justify left bottom))
    )
    (fp_text user "License: Apache-2.0" (at -2.503 6.6 180) (layer "F.Fab") hide
      (effects (font (size 0.7 0.7) (thickness 0.15)) (justify left bottom))
    )
    (fp_line (start -2.11 -1.636) (end -2.11 -2.11) (layer "F.SilkS") (width 0.15))
    (fp_line (start -1.635 2.108) (end -2.11 2.108) (layer "F.SilkS") (width 0.15))
    (fp_line (start 2.108 2.108) (end 2.108 1.634) (layer "F.SilkS") (width 0.15))
    (fp_line (start 2.108 -2.11) (end 2.108 -1.635) (layer "F.SilkS") (width 0.15))
    (fp_line (start -2.11 2.108) (end -2.11 1.634) (layer "F.SilkS") (width 0.15))
    (fp_line (start 1.634 2.108) (end 2.108 2.108) (layer "F.SilkS") (width 0.15))
    (fp_line (start -1.635 -2.11) (end -2.11 -2.11) (layer "F.SilkS") (width 0.15))
    (fp_line (start 1.634 -2.11) (end 2.108 -2.11) (layer "F.SilkS") (width 0.15))
    (fp_circle (center -2.3 -2.3) (end -2.25 -2.3) (layer "F.SilkS") (width 0.15) (fill solid))
    (fp_rect (start -2.503 -2.503) (end 2.5 2.5) (layer "F.CrtYd") (width 0.05) (fill none))
    (fp_line (start 1.999 -2) (end 1.999 1.999) (layer "F.Fab") (width 0.15))
    (fp_line (start -2 -1) (end -1 -2) (layer "F.Fab") (width 0.15))
    (fp_line (start -1 -2) (end 1.999 -2) (layer "F.Fab") (width 0.15))
    (fp_line (start -2 1.999) (end -2 -1) (layer "F.Fab") (width 0.15))
    (fp_line (start 1.999 1.999) (end -2 1.999) (layer "F.Fab") (width 0.15))
    (pad "" smd roundrect (at -0.5 -0.5 180) (size 0.8 0.8) (layers "F.Paste") (roundrect_rratio 0.238095))
    (pad "" smd roundrect (at 0.5 0.5 180) (size 0.8 0.8) (layers "F.Paste") (roundrect_rratio 0.238095))
    (pad "" smd roundrect (at 0.5 -0.5 180) (size 0.8 0.8) (layers "F.Paste") (roundrect_rratio 0.238095))
    (pad "" smd roundrect (at -0.5 0.5 180) (size 0.8 0.8) (layers "F.Paste") (roundrect_rratio 0.238095))
    (pad "1" smd roundrect (at -1.938 -1.25 180) (size 0.825 0.25) (layers "F.Cu" "F.Paste" "F.Mask") (roundrect_rratio 0.25)
      (net 143 "/USB-PD/PD_CC1") (pinfunction "CC1DB") (pintype "bidirectional"))
    (pad "2" smd roundrect (at -1.938 -0.75 180) (size 0.825 0.25) (layers "F.Cu" "F.Paste" "F.Mask") (roundrect_rratio 0.25)
      (net 143 "/USB-PD/PD_CC1") (pinfunction "CC1") (pintype "bidirectional"))
    (pad "3" smd roundrect (at -1.938 -0.25 180) (size 0.825 0.25) (layers "F.Cu" "F.Paste" "F.Mask") (roundrect_rratio 0.25)
      (net 660 "unconnected-(U23-Pad3)") (pinfunction "NC") (pintype "no_connect"))
    (pad "4" smd roundrect (at -1.938 0.248 180) (size 0.825 0.25) (layers "F.Cu" "F.Paste" "F.Mask") (roundrect_rratio 0.25)
      (net 144 "/USB-PD/PD_CC2") (pinfunction "CC2") (pintype "bidirectional"))
    (pad "5" smd roundrect (at -1.938 0.748 180) (size 0.825 0.25) (layers "F.Cu" "F.Paste" "F.Mask") (roundrect_rratio 0.25)
      (net 144 "/USB-PD/PD_CC2") (pinfunction "CC2DB") (pintype "bidirectional"))
    (pad "6" smd roundrect (at -1.938 1.249 180) (size 0.825 0.25) (layers "F.Cu" "F.Paste" "F.Mask") (roundrect_rratio 0.25)
      (net 351 "USB_PD_DISABLE") (pinfunction "RESET") (pintype "input"))
    (pad "7" smd roundrect (at -1.25 1.937 180) (size 0.25 0.825) (layers "F.Cu" "F.Paste" "F.Mask") (roundrect_rratio 0.25)
      (net 150 "I2C10_SCL") (pinfunction "SCL") (pintype "input"))
    (pad "8" smd roundrect (at -0.75 1.937 180) (size 0.25 0.825) (layers "F.Cu" "F.Paste" "F.Mask") (roundrect_rratio 0.25)
      (net 151 "I2C10_SDA") (pinfunction "SDA") (pintype "bidirectional"))
    (pad "9" smd roundrect (at -0.25 1.937 180) (size 0.25 0.825) (layers "F.Cu" "F.Paste" "F.Mask") (roundrect_rratio 0.25)
      (net 468 "/USB-PD/DISCH") (pinfunction "DISCH") (pintype "bidirectional"))
    (pad "10" smd roundrect (at 0.248 1.937 180) (size 0.25 0.825) (layers "F.Cu" "F.Paste" "F.Mask") (roundrect_rratio 0.25)
      (net 1 "GND") (pinfunction "GND") (pintype "power_in"))
    (pad "11" smd roundrect (at 0.748 1.937 180) (size 0.25 0.825) (layers "F.Cu" "F.Paste" "F.Mask") (roundrect_rratio 0.25)
      (net 335 "/USB-PD/ATTACH") (pinfunction "ATTACH") (pintype "output"))
    (pad "12" smd roundrect (at 1.249 1.937 180) (size 0.25 0.825) (layers "F.Cu" "F.Paste" "F.Mask") (roundrect_rratio 0.25)
      (net 160 "Net-(R154-Pad2)") (pinfunction "ADDR0") (pintype "input"))
    (pad "13" smd roundrect (at 1.937 1.249 180) (size 0.825 0.25) (layers "F.Cu" "F.Paste" "F.Mask") (roundrect_rratio 0.25)
      (net 411 "Net-(R155-Pad2)") (pinfunction "ADDR1") (pintype "input"))
    (pad "14" smd roundrect (at 1.937 0.748 180) (size 0.825 0.25) (layers "F.Cu" "F.Paste" "F.Mask") (roundrect_rratio 0.25)
      (net 170 "/USB-PD/STUSB4500_PWR_OK3") (pinfunction "POWER_OK3") (pintype "output"))
    (pad "15" smd roundrect (at 1.937 0.248 180) (size 0.825 0.25) (layers "F.Cu" "F.Paste" "F.Mask") (roundrect_rratio 0.25)
      (net 334 "/USB-PD/GPIO") (pinfunction "GPIO") (pintype "output"))
    (pad "16" smd roundrect (at 1.937 -0.25 180) (size 0.825 0.25) (layers "F.Cu" "F.Paste" "F.Mask") (roundrect_rratio 0.25)
      (net 467 "/USB-PD/EN_SINK") (pinfunction "VBUS_EN_SNK") (pintype "output"))
    (pad "17" smd roundrect (at 1.937 -0.75 180) (size 0.825 0.25) (layers "F.Cu" "F.Paste" "F.Mask") (roundrect_rratio 0.25)
      (net 333 "/USB-PD/AB_SIDE") (pinfunction "A_B_SIDE") (pintype "output"))
    (pad "18" smd roundrect (at 1.937 -1.25 180) (size 0.825 0.25) (layers "F.Cu" "F.Paste" "F.Mask") (roundrect_rratio 0.25)
      (net 466 "/USB-PD/VS_DISCH") (pinfunction "VBUS_VS_DISCH") (pintype "input"))
    (pad "19" smd roundrect (at 1.249 -1.938 180) (size 0.25 0.825) (layers "F.Cu" "F.Paste" "F.Mask") (roundrect_rratio 0.25)
      (net 332 "/USB-PD/ALERT") (pinfunction "~{ALERT}") (pintype "output"))
    (pad "20" smd roundrect (at 0.748 -1.938 180) (size 0.25 0.825) (layers "F.Cu" "F.Paste" "F.Mask") (roundrect_rratio 0.25)
      (net 169 "/USB-PD/STUSB4500_PWR_OK2") (pinfunction "POWER_OK2") (pintype "output"))
    (pad "21" smd roundrect (at 0.248 -1.938 180) (size 0.25 0.825) (layers "F.Cu" "F.Paste" "F.Mask") (roundrect_rratio 0.25)
      (net 140 "/USB-PD/VREG_1V2") (pinfunction "VREG_1V2") (pintype "output"))
    (pad "22" smd roundrect (at -0.25 -1.938 180) (size 0.25 0.825) (layers "F.Cu" "F.Paste" "F.Mask") (roundrect_rratio 0.25)
      (net 1 "GND") (pinfunction "VSYS") (pintype "power_in"))
    (pad "23" smd roundrect (at -0.75 -1.938 180) (size 0.25 0.825) (layers "F.Cu" "F.Paste" "F.Mask") (roundrect_rratio 0.25)
      (net 141 "/USB-PD/VREG_2V7") (pinfunction "VREG_2V7") (pintype "output"))
    (pad "24" smd roundrect (at -1.25 -1.938 180) (size 0.25 0.825) (layers "F.Cu" "F.Paste" "F.Mask") (roundrect_rratio 0.25)
      (net 107 "/USB-PD/PD_VBUS") (pinfunction "VDD") (pintype "power_in"))
    (pad "25" smd rect (at 0 0 180) (size 2.1 2.1) (layers "F.Cu" "F.Mask")
      (net 1 "GND") (pinfunction "EP") (pintype "power_in"))
  )

  (footprint "sa800u-baseboard-hw-footprints:C_0402_1005Metric" (layer "F.Cu")
    (tedit 616D63CF)
    (at 119 108.8 180)
    (descr "Capacitor SMD 0402")
    (tags "capacitor SMD 0402")
    (property "Author" "Antmicro")
    (property "Dielectric" "X5R")
    (property "License" "Apache-2.0")
    (property "MPN" "GRM155R61H104KE14D")
    (property "Manufacturer" "Murata")
    (property "Sheetfile" "lcm.kicad_sch")
    (property "Sheetname" "LCM")
    (property "Val" "100n")
    (property "Voltage" "50V")
    (attr smd)
    (fp_text reference "C97" (at 3.02 -0.65 180) (layer "F.SilkS")
      (effects (font (size 0.7 0.7) (thickness 0.15)) (justify left bottom))
    )
    (fp_text value "C_100n_0402" (at 0 1.4 180) (layer "F.Fab")
      (effects (font (size 0.7 0.7) (thickness 0.15)) (justify left bottom))
    )
    (fp_text user "${REFERENCE}" (at -0.932 3.168 180) (layer "F.Fab") hide
      (effects (font (size 0.7 0.7) (thickness 0.15)) (justify left bottom))
    )
    (fp_text user "Author: Antmicro" (at -0.932 4.17 180) (layer "F.Fab") hide
      (effects (font (size 0.7 0.7) (thickness 0.15)) (justify left bottom))
    )
    (fp_text user "License: Apache-2.0" (at -0.932 5.17 180) (layer "F.Fab") hide
      (effects (font (size 0.7 0.7) (thickness 0.15)) (justify left bottom))
    )
    (fp_rect (start -0.94 -0.47) (end 0.94 0.47) (layer "F.CrtYd") (width 0.05) (fill none))
    (fp_rect (start -0.499 -0.249) (end 0.499 0.249) (layer "F.Fab") (width 0.15) (fill none))
    (pad "1" smd roundrect (at -0.484 0 180) (size 0.59 0.64) (layers "F.Cu" "F.Paste" "F.Mask") (roundrect_rratio 0.25)
      (net 139 "LVS1A_1V8") (pintype "passive"))
    (pad "2" smd roundrect (at 0.484 0 180) (size 0.59 0.64) (layers "F.Cu" "F.Paste" "F.Mask") (roundrect_rratio 0.25)
      (net 1 "GND") (pintype "passive"))
  )

  (footprint "sa800u-baseboard-hw-footprints:C_0402_1005Metric" (layer "F.Cu")
    (tedit 616D63CF)
    (at 122.8 108.8)
    (descr "Capacitor SMD 0402")
    (tags "capacitor SMD 0402")
    (property "Author" "Antmicro")
    (property "Dielectric" "X5R")
    (property "License" "Apache-2.0")
    (property "MPN" "GRM155R61H104KE14D")
    (property "Manufacturer" "Murata")
    (property "Sheetfile" "lcm.kicad_sch")
    (property "Sheetname" "LCM")
    (property "Val" "100n")
    (property "Voltage" "50V")
    (attr smd)
    (fp_text reference "C98" (at 0.791 0.39) (layer "F.SilkS")
      (effects (font (size 0.7 0.7) (thickness 0.15)) (justify left bottom))
    )
    (fp_text value "C_100n_0402" (at 0 1.4) (layer "F.Fab")
      (effects (font (size 0.7 0.7) (thickness 0.15)) (justify left bottom))
    )
    (fp_text user "Author: Antmicro" (at -0.932 4.17) (layer "F.Fab") hide
      (effects (font (size 0.7 0.7) (thickness 0.15)) (justify left bottom))
    )
    (fp_text user "${REFERENCE}" (at -0.932 3.168) (layer "F.Fab") hide
      (effects (font (size 0.7 0.7) (thickness 0.15)) (justify left bottom))
    )
    (fp_text user "License: Apache-2.0" (at -0.932 5.17) (layer "F.Fab") hide
      (effects (font (size 0.7 0.7) (thickness 0.15)) (justify left bottom))
    )
    (fp_rect (start -0.94 -0.47) (end 0.94 0.47) (layer "F.CrtYd") (width 0.05) (fill none))
    (fp_rect (start -0.499 -0.249) (end 0.499 0.249) (layer "F.Fab") (width 0.15) (fill none))
    (pad "1" smd roundrect (at -0.484 0) (size 0.59 0.64) (layers "F.Cu" "F.Paste" "F.Mask") (roundrect_rratio 0.25)
      (net 131 "3V3_SYS") (pintype "passive"))
    (pad "2" smd roundrect (at 0.484 0) (size 0.59 0.64) (layers "F.Cu" "F.Paste" "F.Mask") (roundrect_rratio 0.25)
      (net 1 "GND") (pintype "passive"))
  )

  (footprint "sa800u-baseboard-hw-footprints:D_SOD-323F" (layer "F.Cu")
    (tedit 60F16F6B)
    (at 138.8 145 -90)
    (property "Author" "Antmicro")
    (property "License" "Apache-2.0")
    (property "MPN" "1N4148WS")
    (property "Manufacturer" "ON Semiconductor")
    (property "Sheetfile" "hdmi-converter.kicad_sch")
    (property "Sheetname" "HDMI converter")
    (attr smd)
    (fp_text reference "D2" (at 0.56 -1.7 90) (layer "F.SilkS")
      (effects (font (size 0.7 0.7) (thickness 0.15)) (justify left bottom))
    )
    (fp_text value "1N4148WS" (at -1.7 1.9 -90) (layer "F.Fab")
      (effects (font (size 0.7 0.7) (thickness 0.15)) (justify left bottom))
    )
    (fp_text user "Author: Antmicro" (at -1.8 4.46 -90) (layer "F.Fab") hide
      (effects (font (size 0.7 0.7) (thickness 0.15)) (justify left bottom))
    )
    (fp_text user "${REFERENCE}" (at -1.8 3.2 -90) (layer "F.Fab") hide
      (effects (font (size 0.7 0.7) (thickness 0.15)) (justify left bottom))
    )
    (fp_text user "License: Apache-2.0" (at -1.8 5.8 -90) (layer "F.Fab") hide
      (effects (font (size 0.7 0.7) (thickness 0.15)) (justify left bottom))
    )
    (fp_line (start 0.973 0.748) (end 0.623 0.748) (layer "F.SilkS") (width 0.15))
    (fp_line (start 0.623 -0.75) (end 0.973 -0.75) (layer "F.SilkS") (width 0.15))
    (fp_line (start -0.975 -0.75) (end -0.975 -0.45) (layer "F.SilkS") (width 0.15))
    (fp_line (start -0.975 0.748) (end -0.975 0.45) (layer "F.SilkS") (width 0.15))
    (fp_line (start -0.625 -0.75) (end -0.975 -0.75) (layer "F.SilkS") (width 0.15))
    (fp_line (start 0.973 0.45) (end 0.973 0.748) (layer "F.SilkS") (width 0.15))
    (fp_line (start -0.625 0.748) (end -0.975 0.748) (layer "F.SilkS") (width 0.15))
    (fp_line (start -0.5 -0.426) (end -0.5 0.424) (layer "F.SilkS") (width 0.15))
    (fp_line (start 0.973 -0.75) (end 0.973 -0.45) (layer "F.SilkS") (width 0.15))
    (fp_rect (start -1.6 -0.827) (end 1.599 0.825) (layer "F.CrtYd") (width 0.05) (fill none))
    (fp_line (start -0.85 0.623) (end -0.85 -0.625) (layer "F.Fab") (width 0.15))
    (fp_line (start -0.85 0.623) (end 0.848 0.623) (layer "F.Fab") (width 0.15))
    (fp_line (start 0.848 -0.625) (end 0.848 0.623) (layer "F.Fab") (width 0.15))
    (fp_line (start -0.85 -0.625) (end 0.848 -0.625) (layer "F.Fab") (width 0.15))
    (pad "A" smd roundrect (at 1.05 0 270) (size 0.8 0.6) (layers "F.Cu" "F.Paste" "F.Mask") (roundrect_rratio 0.15)
      (net 244 "/HDMI converter/5V_HDMI_FB_D") (pinfunction "A") (pintype "passive"))
    (pad "K" smd roundrect (at -1.051 0 270) (size 0.8 0.6) (layers "F.Cu" "F.Paste" "F.Mask") (roundrect_rratio 0.15)
      (net 245 "/HDMI converter/5V_HDMI") (pinfunction "K") (pintype "passive"))
  )

  (footprint "sa800u-baseboard-hw-footprints:LED_0603_1608Metric_G" (layer "F.Cu")
    (tedit 60C2DD7B)
    (at 81.25 150.2 -90)
    (descr "LED SMD 0603 Green")
    (tags "LED SMD 0603 Green")
    (property "Author" "Antmicro")
    (property "License" "Apache-2.0")
    (property "MPN" "KP-1608ZGC")
    (property "Manufacturer" "Kingbright")
    (property "Sheetfile" "psu.kicad_sch")
    (property "Sheetname" "PSU")
    (attr smd)
    (fp_text reference "D24" (at 0.95 -1.46 -90) (layer "F.SilkS")
      (effects (font (size 0.7 0.7) (thickness 0.15)) (justify left bottom))
    )
    (fp_text value "KP-1608EC" (at 0 1.6 -90) (layer "F.Fab")
      (effects (font (size 0.7 0.7) (thickness 0.15)) (justify left bottom))
    )
    (fp_text user "Author: Antmicro" (at -1.31 4.769 -90) (layer "F.Fab") hide
      (effects (font (size 0.7 0.7) (thickness 0.15)) (justify left bottom))
    )
    (fp_text user "${REFERENCE}" (at -1.31 3.769 -90) (layer "F.Fab") hide
      (effects (font (size 0.7 0.7) (thickness 0.15)) (justify left bottom))
    )
    (fp_text user "License: Apache-2.0" (at -1.31 5.769 -90) (layer "F.Fab") hide
      (effects (font (size 0.7 0.7) (thickness 0.15)) (justify left bottom))
    )
    (fp_line (start -0.27 -0.35) (end 0.27 -0.35) (layer "F.SilkS") (width 0.15))
    (fp_line (start -0.106328 -0.200008) (end 0.093672 -0.000008) (layer "F.SilkS") (width 0.1))
    (fp_line (start 0.093672 -0.000008) (end 0.293672 -0.000008) (layer "F.SilkS") (width 0.1))
    (fp_line (start -0.106328 -0.200008) (end -0.106328 0.199992) (layer "F.SilkS") (width 0.1))
    (fp_line (start 1.25 0.32) (end 1.25 -0.32) (layer "F.SilkS") (width 0.15))
    (fp_line (start 0.093672 -0.200008) (end 0.093672 0.199992) (layer "F.SilkS") (width 0.1))
    (fp_line (start -0.106328 -0.000008) (end -0.29 0) (layer "F.SilkS") (width 0.1))
    (fp_line (start -0.27 0.351) (end 0.27 0.351) (layer "F.SilkS") (width 0.15))
    (fp_line (start 0.093672 -0.000008) (end -0.106328 0.199992) (layer "F.SilkS") (width 0.1))
    (fp_rect (start 1.26 0.65) (end -1.26 -0.65) (layer "F.CrtYd") (width 0.05) (fill none))
    (fp_line (start -0.599 0) (end -0.201 0) (layer "F.Fab") (width 0.15))
    (fp_line (start -0.201 -0.2) (end -0.201 0) (layer "F.Fab") (width 0.15))
    (fp_line (start -0.201 0.202) (end 0.101 0) (layer "F.Fab") (width 0.15))
    (fp_line (start 0.199 -0.2) (end 0.199 -0.1) (layer "F.Fab") (width 0.15))
    (fp_line (start 0.101 0) (end -0.201 -0.2) (layer "F.Fab") (width 0.15))
    (fp_line (start -0.201 0) (end -0.201 0.202) (layer "F.Fab") (width 0.15))
    (fp_line (start 0.199 0) (end 0.597 0) (layer "F.Fab") (width 0.15))
    (fp_line (start 0.199 0.202) (end 0.199 -0.1) (layer "F.Fab") (width 0.15))
    (fp_rect (start -0.848 -0.4) (end 0.85 0.402) (layer "F.Fab") (width 0.15) (fill none))
    (pad "1" smd rect (at -0.75 0 90) (size 0.8 0.8) (layers "F.Cu" "F.Paste" "F.Mask")
      (net 152 "/PSU/AUX_VDD") (pinfunction "1") (pintype "passive"))
    (pad "2" smd rect (at 0.75 0 90) (size 0.8 0.8) (layers "F.Cu" "F.Paste" "F.Mask")
      (net 375 "Net-(D24-Pad2)") (pinfunction "2") (pintype "passive"))
  )

  (footprint "sa800u-baseboard-hw-footprints:LED_0603_1608Metric_G" (layer "F.Cu")
    (tedit 60C2DD7B)
    (at 93.4 150.16 -90)
    (descr "LED SMD 0603 Green")
    (tags "LED SMD 0603 Green")
    (property "Author" "Antmicro")
    (property "License" "Apache-2.0")
    (property "MPN" "KP-1608ZGC")
    (property "Manufacturer" "Kingbright")
    (property "Sheetfile" "psu.kicad_sch")
    (property "Sheetname" "PSU")
    (attr smd)
    (fp_text reference "D25" (at 1.17 -2.07 -90) (layer "F.SilkS")
      (effects (font (size 0.7 0.7) (thickness 0.15)) (justify left bottom))
    )
    (fp_text value "KP-1608EC" (at 0 1.6 -90) (layer "F.Fab")
      (effects (font (size 0.7 0.7) (thickness 0.15)) (justify left bottom))
    )
    (fp_text user "Author: Antmicro" (at -1.31 4.769 -90) (layer "F.Fab") hide
      (effects (font (size 0.7 0.7) (thickness 0.15)) (justify left bottom))
    )
    (fp_text user "${REFERENCE}" (at -1.31 3.769 -90) (layer "F.Fab") hide
      (effects (font (size 0.7 0.7) (thickness 0.15)) (justify left bottom))
    )
    (fp_text user "License: Apache-2.0" (at -1.31 5.769 -90) (layer "F.Fab") hide
      (effects (font (size 0.7 0.7) (thickness 0.15)) (justify left bottom))
    )
    (fp_line (start 1.25 0.32) (end 1.25 -0.32) (layer "F.SilkS") (width 0.15))
    (fp_line (start -0.106328 -0.200008) (end 0.093672 -0.000008) (layer "F.SilkS") (width 0.1))
    (fp_line (start -0.27 -0.35) (end 0.27 -0.35) (layer "F.SilkS") (width 0.15))
    (fp_line (start -0.27 0.351) (end 0.27 0.351) (layer "F.SilkS") (width 0.15))
    (fp_line (start 0.093672 -0.200008) (end 0.093672 0.199992) (layer "F.SilkS") (width 0.1))
    (fp_line (start 0.093672 -0.000008) (end -0.106328 0.199992) (layer "F.SilkS") (width 0.1))
    (fp_line (start -0.106328 -0.200008) (end -0.106328 0.199992) (layer "F.SilkS") (width 0.1))
    (fp_line (start 0.093672 -0.000008) (end 0.293672 -0.000008) (layer "F.SilkS") (width 0.1))
    (fp_line (start -0.106328 -0.000008) (end -0.29 0) (layer "F.SilkS") (width 0.1))
    (fp_rect (start 1.26 0.65) (end -1.26 -0.65) (layer "F.CrtYd") (width 0.05) (fill none))
    (fp_line (start 0.199 0.202) (end 0.199 -0.1) (layer "F.Fab") (width 0.15))
    (fp_line (start 0.199 0) (end 0.597 0) (layer "F.Fab") (width 0.15))
    (fp_line (start 0.199 -0.2) (end 0.199 -0.1) (layer "F.Fab") (width 0.15))
    (fp_line (start -0.599 0) (end -0.201 0) (layer "F.Fab") (width 0.15))
    (fp_line (start -0.201 0.202) (end 0.101 0) (layer "F.Fab") (width 0.15))
    (fp_line (start 0.101 0) (end -0.201 -0.2) (layer "F.Fab") (width 0.15))
    (fp_line (start -0.201 0) (end -0.201 0.202) (layer "F.Fab") (width 0.15))
    (fp_line (start -0.201 -0.2) (end -0.201 0) (layer "F.Fab") (width 0.15))
    (fp_rect (start -0.848 -0.4) (end 0.85 0.402) (layer "F.Fab") (width 0.15) (fill none))
    (pad "1" smd rect (at -0.75 0 90) (size 0.8 0.8) (layers "F.Cu" "F.Paste" "F.Mask")
      (net 142 "PD_VDD") (pinfunction "1") (pintype "passive"))
    (pad "2" smd rect (at 0.75 0 90) (size 0.8 0.8) (layers "F.Cu" "F.Paste" "F.Mask")
      (net 376 "Net-(D25-Pad2)") (pinfunction "2") (pintype "passive"))
  )

  (footprint "sa800u-baseboard-hw-footprints:FB_0603_1608Metric" (layer "F.Cu")
    (tedit 618B9E9E)
    (at 137.1 145 -90)
    (property "Author" "Antmicro")
    (property "License" "Apache-2.0")
    (property "MPN" "BLM18SG121TN1D")
    (property "Manufacturer" "Murata")
    (property "Sheetfile" "hdmi-converter.kicad_sch")
    (property "Sheetname" "HDMI converter")
    (attr smd)
    (fp_text reference "FB2" (at 0.93 0.72 -90) (layer "F.SilkS")
      (effects (font (size 0.7 0.7) (thickness 0.15)) (justify left bottom))
    )
    (fp_text value "FB_120Z_3A_0603" (at 0 1.5 -90) (layer "F.Fab")
      (effects (font (size 0.7 0.7) (thickness 0.15)) (justify left bottom))
    )
    (fp_text user "License: Apache-2.0" (at -1.653 5.9 -90) (layer "F.Fab") hide
      (effects (font (size 0.7 0.7) (thickness 0.15)) (justify left bottom))
    )
    (fp_text user "Author: Antmicro" (at -1.653 3.162 -90) (layer "F.Fab") hide
      (effects (font (size 0.7 0.7) (thickness 0.15)) (justify left bottom))
    )
    (fp_text user "${REFERENCE}" (at -1.653 4.6 -90) (layer "F.Fab") hide
      (effects (font (size 0.7 0.7) (thickness 0.15)) (justify left bottom))
    )
    (fp_line (start -0.196 0.406) (end 0.193 0.406) (layer "F.SilkS") (width 0.15))
    (fp_line (start -0.196 -0.408) (end 0.193 -0.408) (layer "F.SilkS") (width 0.15))
    (fp_rect (start -1.3 -0.6) (end 1.3 0.6) (layer "F.CrtYd") (width 0.05) (fill none))
    (fp_line (start 0.8 -0.408) (end -0.803 -0.408) (layer "F.Fab") (width 0.15))
    (fp_line (start 0.8 0.406) (end -0.803 0.406) (layer "F.Fab") (width 0.15))
    (fp_line (start 0.8 -0.408) (end 0.8 0.406) (layer "F.Fab") (width 0.15))
    (fp_line (start -0.803 0.406) (end -0.803 -0.408) (layer "F.Fab") (width 0.15))
    (pad "1" smd roundrect (at -0.891 0 270) (size 0.762 1.09) (layers "F.Cu" "F.Paste" "F.Mask") (roundrect_rratio 0.15)
      (net 133 "5V_SYS") (pintype "passive"))
    (pad "2" smd roundrect (at 0.888 0 270) (size 0.762 1.09) (layers "F.Cu" "F.Paste" "F.Mask") (roundrect_rratio 0.15)
      (net 244 "/HDMI converter/5V_HDMI_FB_D") (pintype "passive"))
  )

  (footprint "sa800u-baseboard-hw-footprints:R_0402_1005Metric" (layer "F.Cu")
    (tedit 5FD9C158)
    (at 119 109.8 180)
    (descr "Resistor SMD 0402")
    (tags "resistor SMD 0402")
    (property "Author" "Antmicro")
    (property "License" "Apache-2.0")
    (property "MPN" "CR0402-FX-2001GLF")
    (property "Manufacturer" "Bourns")
    (property "Sheetfile" "lcm.kicad_sch")
    (property "Sheetname" "LCM")
    (property "Tolerance" "1%")
    (property "Val" "2k")
    (attr smd)
    (fp_text reference "R65" (at 1.04 -1.24 180) (layer "F.SilkS")
      (effects (font (size 0.7 0.7) (thickness 0.15)) (justify left bottom))
    )
    (fp_text value "R_2k_0402" (at 0 1.4 180) (layer "F.Fab")
      (effects (font (size 0.7 0.7) (thickness 0.15)) (justify left bottom))
    )
    (fp_text user "${REFERENCE}" (at -0.95 3.168 180) (layer "F.Fab") hide
      (effects (font (size 0.7 0.7) (thickness 0.15)) (justify left bottom))
    )
    (fp_text user "Author: Antmicro" (at -0.95 4.169 180) (layer "F.Fab") hide
      (effects (font (size 0.7 0.7) (thickness 0.15)) (justify left bottom))
    )
    (fp_text user "License: Apache-2.0" (at -0.95 5.169 180) (layer "F.Fab") hide
      (effects (font (size 0.7 0.7) (thickness 0.15)) (justify left bottom))
    )
    (fp_rect (start -0.93 -0.47) (end 0.93 0.47) (layer "F.CrtYd") (width 0.05) (fill none))
    (fp_rect (start -0.5 -0.25) (end 0.5 0.25) (layer "F.Fab") (width 0.15) (fill none))
    (pad "1" smd roundrect (at -0.485 0 180) (size 0.59 0.64) (layers "F.Cu" "F.Paste" "F.Mask") (roundrect_rratio 0.25)
      (net 82 "TP_I2C_SDA") (pintype "passive"))
    (pad "2" smd roundrect (at 0.485 0 180) (size 0.59 0.64) (layers "F.Cu" "F.Paste" "F.Mask") (roundrect_rratio 0.25)
      (net 139 "LVS1A_1V8") (pintype "passive"))
  )

  (footprint "sa800u-baseboard-hw-footprints:R_0402_1005Metric" (layer "F.Cu")
    (tedit 5FD9C158)
    (at 122.8 109.8)
    (descr "Resistor SMD 0402")
    (tags "resistor SMD 0402")
    (property "Author" "Antmicro")
    (property "License" "Apache-2.0")
    (property "MPN" "CR0402-FX-2001GLF")
    (property "Manufacturer" "Bourns")
    (property "Sheetfile" "lcm.kicad_sch")
    (property "Sheetname" "LCM")
    (property "Tolerance" "1%")
    (property "Val" "2k")
    (attr smd)
    (fp_text reference "R66" (at 0.79 0.39) (layer "F.SilkS")
      (effects (font (size 0.7 0.7) (thickness 0.15)) (justify left bottom))
    )
    (fp_text value "R_2k_0402" (at 0 1.4) (layer "F.Fab")
      (effects (font (size 0.7 0.7) (thickness 0.15)) (justify left bottom))
    )
    (fp_text user "${REFERENCE}" (at -0.95 3.168) (layer "F.Fab") hide
      (effects (font (size 0.7 0.7) (thickness 0.15)) (justify left bottom))
    )
    (fp_text user "License: Apache-2.0" (at -0.95 5.169) (layer "F.Fab") hide
      (effects (font (size 0.7 0.7) (thickness 0.15)) (justify left bottom))
    )
    (fp_text user "Author: Antmicro" (at -0.95 4.169) (layer "F.Fab") hide
      (effects (font (size 0.7 0.7) (thickness 0.15)) (justify left bottom))
    )
    (fp_rect (start -0.93 -0.47) (end 0.93 0.47) (layer "F.CrtYd") (width 0.05) (fill none))
    (fp_rect (start -0.5 -0.25) (end 0.5 0.25) (layer "F.Fab") (width 0.15) (fill none))
    (pad "1" smd roundrect (at -0.485 0) (size 0.59 0.64) (layers "F.Cu" "F.Paste" "F.Mask") (roundrect_rratio 0.25)
      (net 81 "TP_I2C_SCL") (pintype "passive"))
    (pad "2" smd roundrect (at 0.485 0) (size 0.59 0.64) (layers "F.Cu" "F.Paste" "F.Mask") (roundrect_rratio 0.25)
      (net 139 "LVS1A_1V8") (pintype "passive"))
  )

  (footprint "sa800u-baseboard-hw-footprints:R_0402_1005Metric" (layer "F.Cu")
    (tedit 5FD9C158)
    (at 122.8 107.8)
    (descr "Resistor SMD 0402")
    (tags "resistor SMD 0402")
    (property "Author" "Antmicro")
    (property "License" "Apache-2.0")
    (property "MPN" "CR0402-FX-2001GLF")
    (property "Manufacturer" "Bourns")
    (property "Sheetfile" "lcm.kicad_sch")
    (property "Sheetname" "LCM")
    (property "Tolerance" "1%")
    (property "Val" "2k")
    (attr smd)
    (fp_text reference "R67" (at 0.79 0.39) (layer "F.SilkS")
      (effects (font (size 0.7 0.7) (thickness 0.15)) (justify left bottom))
    )
    (fp_text value "R_2k_0402" (at 0 1.4) (layer "F.Fab")
      (effects (font (size 0.7 0.7) (thickness 0.15)) (justify left bottom))
    )
    (fp_text user "${REFERENCE}" (at -0.95 3.168) (layer "F.Fab") hide
      (effects (font (size 0.7 0.7) (thickness 0.15)) (justify left bottom))
    )
    (fp_text user "Author: Antmicro" (at -0.95 4.169) (layer "F.Fab") hide
      (effects (font (size 0.7 0.7) (thickness 0.15)) (justify left bottom))
    )
    (fp_text user "License: Apache-2.0" (at -0.95 5.169) (layer "F.Fab") hide
      (effects (font (size 0.7 0.7) (thickness 0.15)) (justify left bottom))
    )
    (fp_rect (start -0.93 -0.47) (end 0.93 0.47) (layer "F.CrtYd") (width 0.05) (fill none))
    (fp_rect (start -0.5 -0.25) (end 0.5 0.25) (layer "F.Fab") (width 0.15) (fill none))
    (pad "1" smd roundrect (at -0.485 0) (size 0.59 0.64) (layers "F.Cu" "F.Paste" "F.Mask") (roundrect_rratio 0.25)
      (net 148 "/LCM/TP_I2C_SCL_3V3") (pintype "passive"))
    (pad "2" smd roundrect (at 0.485 0) (size 0.59 0.64) (layers "F.Cu" "F.Paste" "F.Mask") (roundrect_rratio 0.25)
      (net 131 "3V3_SYS") (pintype "passive"))
  )

  (footprint "sa800u-baseboard-hw-footprints:R_0402_1005Metric" (layer "F.Cu")
    (tedit 5FD9C158)
    (at 83.4 132)
    (descr "Resistor SMD 0402")
    (tags "resistor SMD 0402")
    (property "Author" "Antmicro")
    (property "DNP" "DNP")
    (property "License" "Apache-2.0")
    (property "MPN" "CR0402-FX-1003GLF")
    (property "Manufacturer" "Bourns")
    (property "Sheetfile" "usb-pd.kicad_sch")
    (property "Sheetname" "USB-PD")
    (property "Tolerance" "1%")
    (property "Val" "100k")
    (attr exclude_from_pos_files)
    (fp_text reference "R154" (at -1.71 -2.53) (layer "F.SilkS")
      (effects (font (size 0.7 0.7) (thickness 0.15)) (justify left bottom))
    )
    (fp_text value "R_100k_0402" (at 0 1.4) (layer "F.Fab")
      (effects (font (size 0.7 0.7) (thickness 0.15)) (justify left bottom))
    )
    (fp_text user "License: Apache-2.0" (at -0.95 5.169) (layer "F.Fab") hide
      (effects (font (size 0.7 0.7) (thickness 0.15)) (justify left bottom))
    )
    (fp_text user "${REFERENCE}" (at -0.95 3.168) (layer "F.Fab") hide
      (effects (font (size 0.7 0.7) (thickness 0.15)) (justify left bottom))
    )
    (fp_text user "Author: Antmicro" (at -0.95 4.169) (layer "F.Fab") hide
      (effects (font (size 0.7 0.7) (thickness 0.15)) (justify left bottom))
    )
    (fp_rect (start -0.93 -0.47) (end 0.93 0.47) (layer "F.CrtYd") (width 0.05) (fill none))
    (fp_rect (start -0.5 -0.25) (end 0.5 0.25) (layer "F.Fab") (width 0.15) (fill none))
    (pad "1" smd roundrect (at -0.485 0) (size 0.59 0.64) (layers "F.Cu" "F.Paste" "F.Mask") (roundrect_rratio 0.25)
      (net 141 "/USB-PD/VREG_2V7") (pintype "passive"))
    (pad "2" smd roundrect (at 0.485 0) (size 0.59 0.64) (layers "F.Cu" "F.Paste" "F.Mask") (roundrect_rratio 0.25)
      (net 160 "Net-(R154-Pad2)") (pintype "passive"))
  )

  (footprint "sa800u-baseboard-hw-footprints:R_0402_1005Metric" (layer "F.Cu")
    (tedit 5FD9C158)
    (at 83.4 133)
    (descr "Resistor SMD 0402")
    (tags "resistor SMD 0402")
    (property "Author" "Antmicro")
    (property "DNP" "DNP")
    (property "License" "Apache-2.0")
    (property "MPN" "CR0402-FX-1003GLF")
    (property "Manufacturer" "Bourns")
    (property "Sheetfile" "usb-pd.kicad_sch")
    (property "Sheetname" "USB-PD")
    (property "Tolerance" "1%")
    (property "Val" "100k")
    (attr exclude_from_pos_files)
    (fp_text reference "R155" (at -1.71 -2.53) (layer "F.SilkS")
      (effects (font (size 0.7 0.7) (thickness 0.15)) (justify left bottom))
    )
    (fp_text value "R_100k_0402" (at 0 1.4) (layer "F.Fab")
      (effects (font (size 0.7 0.7) (thickness 0.15)) (justify left bottom))
    )
    (fp_text user "License: Apache-2.0" (at -0.95 5.169) (layer "F.Fab") hide
      (effects (font (size 0.7 0.7) (thickness 0.15)) (justify left bottom))
    )
    (fp_text user "${REFERENCE}" (at -0.95 3.168) (layer "F.Fab") hide
      (effects (font (size 0.7 0.7) (thickness 0.15)) (justify left bottom))
    )
    (fp_text user "Author: Antmicro" (at -0.95 4.169) (layer "F.Fab") hide
      (effects (font (size 0.7 0.7) (thickness 0.15)) (justify left bottom))
    )
    (fp_rect (start -0.93 -0.47) (end 0.93 0.47) (layer "F.CrtYd") (width 0.05) (fill none))
    (fp_rect (start -0.5 -0.25) (end 0.5 0.25) (layer "F.Fab") (width 0.15) (fill none))
    (pad "1" smd roundrect (at -0.485 0) (size 0.59 0.64) (layers "F.Cu" "F.Paste" "F.Mask") (roundrect_rratio 0.25)
      (net 141 "/USB-PD/VREG_2V7") (pintype "passive"))
    (pad "2" smd roundrect (at 0.485 0) (size 0.59 0.64) (layers "F.Cu" "F.Paste" "F.Mask") (roundrect_rratio 0.25)
      (net 411 "Net-(R155-Pad2)") (pintype "passive"))
  )

  (footprint "sa800u-baseboard-hw-footprints:R_0402_1005Metric" (layer "F.Cu")
    (tedit 5FD9C158)
    (at 84.9 132.4 90)
    (descr "Resistor SMD 0402")
    (tags "resistor SMD 0402")
    (property "Author" "Antmicro")
    (property "License" "Apache-2.0")
    (property "MPN" "CR0402-FX-1003GLF")
    (property "Manufacturer" "Bourns")
    (property "Sheetfile" "usb-pd.kicad_sch")
    (property "Sheetname" "USB-PD")
    (property "Tolerance" "1%")
    (property "Val" "100k")
    (attr smd)
    (fp_text reference "R156" (at 0.84 0.41 90) (layer "F.SilkS")
      (effects (font (size 0.7 0.7) (thickness 0.15)) (justify left bottom))
    )
    (fp_text value "R_100k_0402" (at 0 1.4 90) (layer "F.Fab")
      (effects (font (size 0.7 0.7) (thickness 0.15)) (justify left bottom))
    )
    (fp_text user "Author: Antmicro" (at -0.95 4.169 90) (layer "F.Fab") hide
      (effects (font (size 0.7 0.7) (thickness 0.15)) (justify left bottom))
    )
    (fp_text user "${REFERENCE}" (at -0.95 3.168 90) (layer "F.Fab") hide
      (effects (font (size 0.7 0.7) (thickness 0.15)) (justify left bottom))
    )
    (fp_text user "License: Apache-2.0" (at -0.95 5.169 90) (layer "F.Fab") hide
      (effects (font (size 0.7 0.7) (thickness 0.15)) (justify left bottom))
    )
    (fp_rect (start -0.93 -0.47) (end 0.93 0.47) (layer "F.CrtYd") (width 0.05) (fill none))
    (fp_rect (start -0.5 -0.25) (end 0.5 0.25) (layer "F.Fab") (width 0.15) (fill none))
    (pad "1" smd roundrect (at -0.485 0 90) (size 0.59 0.64) (layers "F.Cu" "F.Paste" "F.Mask") (roundrect_rratio 0.25)
      (net 160 "Net-(R154-Pad2)") (pintype "passive"))
    (pad "2" smd roundrect (at 0.485 0 90) (size 0.59 0.64) (layers "F.Cu" "F.Paste" "F.Mask") (roundrect_rratio 0.25)
      (net 1 "GND") (pintype "passive"))
  )

  (footprint "sa800u-baseboard-hw-footprints:R_0402_1005Metric" (layer "F.Cu")
    (tedit 5FD9C158)
    (at 83.4 134 180)
    (descr "Resistor SMD 0402")
    (tags "resistor SMD 0402")
    (property "Author" "Antmicro")
    (property "License" "Apache-2.0")
    (property "MPN" "CR0402-FX-1003GLF")
    (property "Manufacturer" "Bourns")
    (property "Sheetfile" "usb-pd.kicad_sch")
    (property "Sheetname" "USB-PD")
    (property "Tolerance" "1%")
    (property "Val" "100k")
    (attr smd)
    (fp_text reference "R157" (at 1.72 2.58 180) (layer "F.SilkS")
      (effects (font (size 0.7 0.7) (thickness 0.15)) (justify left bottom))
    )
    (fp_text value "R_100k_0402" (at 0 1.4 180) (layer "F.Fab")
      (effects (font (size 0.7 0.7) (thickness 0.15)) (justify left bottom))
    )
    (fp_text user "${REFERENCE}" (at -0.95 3.168 180) (layer "F.Fab") hide
      (effects (font (size 0.7 0.7) (thickness 0.15)) (justify left bottom))
    )
    (fp_text user "Author: Antmicro" (at -0.95 4.169 180) (layer "F.Fab") hide
      (effects (font (size 0.7 0.7) (thickness 0.15)) (justify left bottom))
    )
    (fp_text user "License: Apache-2.0" (at -0.95 5.169 180) (layer "F.Fab") hide
      (effects (font (size 0.7 0.7) (thickness 0.15)) (justify left bottom))
    )
    (fp_rect (start -0.93 -0.47) (end 0.93 0.47) (layer "F.CrtYd") (width 0.05) (fill none))
    (fp_rect (start -0.5 -0.25) (end 0.5 0.25) (layer "F.Fab") (width 0.15) (fill none))
    (pad "1" smd roundrect (at -0.485 0 180) (size 0.59 0.64) (layers "F.Cu" "F.Paste" "F.Mask") (roundrect_rratio 0.25)
      (net 411 "Net-(R155-Pad2)") (pintype "passive"))
    (pad "2" smd roundrect (at 0.485 0 180) (size 0.59 0.64) (layers "F.Cu" "F.Paste" "F.Mask") (roundrect_rratio 0.25)
      (net 1 "GND") (pintype "passive"))
  )

  (footprint "sa800u-baseboard-hw-footprints:R_0402_1005Metric" (layer "F.Cu")
    (tedit 5FD9C158)
    (at 71.55 111.85)
    (descr "Resistor SMD 0402")
    (tags "resistor SMD 0402")
    (property "Author" "Antmicro")
    (property "License" "Apache-2.0")
    (property "MPN" "CR0402-FX-1002GLF")
    (property "Manufacturer" "Bourns")
    (property "Sheetfile" "psu.kicad_sch")
    (property "Sheetname" "PSU")
    (property "Tolerance" "1%")
    (property "Val" "10k")
    (attr smd)
    (fp_text reference "R127" (at -1.59 1.3) (layer "F.SilkS")
      (effects (font (size 0.7 0.7) (thickness 0.15)) (justify left bottom))
    )
    (fp_text value "R_10k_0402" (at 0 1.4) (layer "F.Fab")
      (effects (font (size 0.7 0.7) (thickness 0.15)) (justify left bottom))
    )
    (fp_text user "Author: Antmicro" (at -0.95 4.169) (layer "F.Fab") hide
      (effects (font (size 0.7 0.7) (thickness 0.15)) (justify left bottom))
    )
    (fp_text user "License: Apache-2.0" (at -0.95 5.169) (layer "F.Fab") hide
      (effects (font (size 0.7 0.7) (thickness 0.15)) (justify left bottom))
    )
    (fp_text user "${REFERENCE}" (at -0.95 3.168) (layer "F.Fab") hide
      (effects (font (size 0.7 0.7) (thickness 0.15)) (justify left bottom))
    )
    (fp_rect (start -0.93 -0.47) (end 0.93 0.47) (layer "F.CrtYd") (width 0.05) (fill none))
    (fp_rect (start -0.5 -0.25) (end 0.5 0.25) (layer "F.Fab") (width 0.15) (fill none))
    (pad "1" smd roundrect (at -0.485 0) (size 0.59 0.64) (layers "F.Cu" "F.Paste" "F.Mask") (roundrect_rratio 0.25)
      (net 319 "3V3_SYS_EN") (pintype "passive"))
    (pad "2" smd roundrect (at 0.485 0) (size 0.59 0.64) (layers "F.Cu" "F.Paste" "F.Mask") (roundrect_rratio 0.25)
      (net 407 "Net-(R127-Pad2)") (pintype "passive"))
  )

  (footprint "sa800u-baseboard-hw-footprints:R_0402_1005Metric" (layer "F.Cu")
    (tedit 5FD9C158)
    (at 73.525 115.3 180)
    (descr "Resistor SMD 0402")
    (tags "resistor SMD 0402")
    (property "Author" "Antmicro")
    (property "DNP" "DNP")
    (property "License" "Apache-2.0")
    (property "MPN" "CR0402-FX-1002GLF")
    (property "Manufacturer" "Bourns")
    (property "Sheetfile" "psu.kicad_sch")
    (property "Sheetname" "PSU")
    (property "Tolerance" "1%")
    (property "Val" "10k")
    (attr exclude_from_pos_files)
    (fp_text reference "R134" (at -1.605 -5.86 180) (layer "F.SilkS")
      (effects (font (size 0.7 0.7) (thickness 0.15)) (justify left bottom))
    )
    (fp_text value "R_10k_0402" (at 0 1.4 180) (layer "F.Fab")
      (effects (font (size 0.7 0.7) (thickness 0.15)) (justify left bottom))
    )
    (fp_text user "Author: Antmicro" (at -0.95 4.169 180) (layer "F.Fab") hide
      (effects (font (size 0.7 0.7) (thickness 0.15)) (justify left bottom))
    )
    (fp_text user "${REFERENCE}" (at -0.95 3.168 180) (layer "F.Fab") hide
      (effects (font (size 0.7 0.7) (thickness 0.15)) (justify left bottom))
    )
    (fp_text user "License: Apache-2.0" (at -0.95 5.169 180) (layer "F.Fab") hide
      (effects (font (size 0.7 0.7) (thickness 0.15)) (justify left bottom))
    )
    (fp_rect (start -0.93 -0.47) (end 0.93 0.47) (layer "F.CrtYd") (width 0.05) (fill none))
    (fp_rect (start -0.5 -0.25) (end 0.5 0.25) (layer "F.Fab") (width 0.15) (fill none))
    (pad "1" smd roundrect (at -0.485 0 180) (size 0.59 0.64) (layers "F.Cu" "F.Paste" "F.Mask") (roundrect_rratio 0.25)
      (net 74 "VDD") (pintype "passive"))
    (pad "2" smd roundrect (at 0.485 0 180) (size 0.59 0.64) (layers "F.Cu" "F.Paste" "F.Mask") (roundrect_rratio 0.25)
      (net 164 "/PSU/5V_DC_DC_ENABLE") (pintype "passive"))
  )

  (footprint "sa800u-baseboard-hw-footprints:R_0402_1005Metric" (layer "F.Cu")
    (tedit 5FD9C158)
    (at 73.6 109.45 180)
    (descr "Resistor SMD 0402")
    (tags "resistor SMD 0402")
    (property "Author" "Antmicro")
    (property "DNP" "DNP")
    (property "License" "Apache-2.0")
    (property "MPN" "CR0402-FX-1002GLF")
    (property "Manufacturer" "Bourns")
    (property "Sheetfile" "psu.kicad_sch")
    (property "Sheetname" "PSU")
    (property "Tolerance" "1%")
    (property "Val" "10k")
    (attr exclude_from_pos_files)
    (fp_text reference "R132" (at 3.02 0.77 180) (layer "F.SilkS")
      (effects (font (size 0.7 0.7) (thickness 0.15)) (justify left bottom))
    )
    (fp_text value "R_10k_0402" (at 0 1.4 180) (layer "F.Fab")
      (effects (font (size 0.7 0.7) (thickness 0.15)) (justify left bottom))
    )
    (fp_text user "License: Apache-2.0" (at -0.95 5.169 180) (layer "F.Fab") hide
      (effects (font (size 0.7 0.7) (thickness 0.15)) (justify left bottom))
    )
    (fp_text user "Author: Antmicro" (at -0.95 4.169 180) (layer "F.Fab") hide
      (effects (font (size 0.7 0.7) (thickness 0.15)) (justify left bottom))
    )
    (fp_text user "${REFERENCE}" (at -0.95 3.168 180) (layer "F.Fab") hide
      (effects (font (size 0.7 0.7) (thickness 0.15)) (justify left bottom))
    )
    (fp_rect (start -0.93 -0.47) (end 0.93 0.47) (layer "F.CrtYd") (width 0.05) (fill none))
    (fp_rect (start -0.5 -0.25) (end 0.5 0.25) (layer "F.Fab") (width 0.15) (fill none))
    (pad "1" smd roundrect (at -0.485 0 180) (size 0.59 0.64) (layers "F.Cu" "F.Paste" "F.Mask") (roundrect_rratio 0.25)
      (net 74 "VDD") (pintype "passive"))
    (pad "2" smd roundrect (at 0.485 0 180) (size 0.59 0.64) (layers "F.Cu" "F.Paste" "F.Mask") (roundrect_rratio 0.25)
      (net 407 "Net-(R127-Pad2)") (pintype "passive"))
  )

  (footprint "sa800u-baseboard-hw-footprints:C_0402_1005Metric" (layer "F.Cu")
    (tedit 616D63CF)
    (at 145.2 96.9 180)
    (descr "Capacitor SMD 0402")
    (tags "capacitor SMD 0402")
    (property "Author" "Antmicro")
    (property "Dielectric" "X5R")
    (property "License" "Apache-2.0")
    (property "MPN" "GRM155R61H104KE14D")
    (property "Manufacturer" "Murata")
    (property "Sheetfile" "m2.kicad_sch")
    (property "Sheetname" "M2")
    (property "Val" "100n")
    (property "Voltage" "50V")
    (attr smd)
    (fp_text reference "C115" (at 3.74 -0.37 180) (layer "F.SilkS")
      (effects (font (size 0.7 0.7) (thickness 0.15)) (justify left bottom))
    )
    (fp_text value "C_100n_0402" (at 0 1.4 180) (layer "F.Fab")
      (effects (font (size 0.7 0.7) (thickness 0.15)) (justify left bottom))
    )
    (fp_text user "Author: Antmicro" (at -0.932 4.17 180) (layer "F.Fab") hide
      (effects (font (size 0.7 0.7) (thickness 0.15)) (justify left bottom))
    )
    (fp_text user "${REFERENCE}" (at -0.932 3.168 180) (layer "F.Fab") hide
      (effects (font (size 0.7 0.7) (thickness 0.15)) (justify left bottom))
    )
    (fp_text user "License: Apache-2.0" (at -0.932 5.17 180) (layer "F.Fab") hide
      (effects (font (size 0.7 0.7) (thickness 0.15)) (justify left bottom))
    )
    (fp_rect (start -0.94 -0.47) (end 0.94 0.47) (layer "F.CrtYd") (width 0.05) (fill none))
    (fp_rect (start -0.499 -0.249) (end 0.499 0.249) (layer "F.Fab") (width 0.15) (fill none))
    (pad "1" smd roundrect (at -0.484 0 180) (size 0.59 0.64) (layers "F.Cu" "F.Paste" "F.Mask") (roundrect_rratio 0.25)
      (net 109 "/M2/C_PCIE0_TX0_P") (pintype "passive"))
    (pad "2" smd roundrect (at 0.484 0 180) (size 0.59 0.64) (layers "F.Cu" "F.Paste" "F.Mask") (roundrect_rratio 0.25)
      (net 108 "PCIE0_TX_P") (pintype "passive"))
  )

  (footprint "sa800u-baseboard-hw-footprints:C_0805_2012Metric" (layer "F.Cu")
    (tedit 5FD9C126)
    (at 123.7 105.05)
    (descr "Capacitor SMD 0805")
    (tags "capacitor SMD 0805")
    (property "Author" "Antmicro")
    (property "DNP" "DNP")
    (property "Dielectric" "")
    (property "License" "Apache-2.0")
    (property "MPN" "0805X475K250CT")
    (property "Manufacturer" "Walsin")
    (property "Sheetfile" "camera-interface.kicad_sch")
    (property "Sheetname" "Camera Interface")
    (property "Val" "4u7")
    (property "Voltage" "")
    (attr exclude_from_pos_files)
    (fp_text reference "C105" (at 1.88 0.33) (layer "F.SilkS")
      (effects (font (size 0.7 0.7) (thickness 0.15)) (justify left bottom))
    )
    (fp_text value "C_4u7_0805" (at 0 1.947) (layer "F.Fab")
      (effects (font (size 0.7 0.7) (thickness 0.15)) (justify left bottom))
    )
    (fp_text user "${REFERENCE}" (at -1.9 3.947) (layer "F.Fab") hide
      (effects (font (size 0.7 0.7) (thickness 0.15)) (justify left bottom))
    )
    (fp_text user "License: Apache-2.0" (at -1.9 4.947) (layer "F.Fab") hide
      (effects (font (size 0.7 0.7) (thickness 0.15)) (justify left bottom))
    )
    (fp_text user "Author: Antmicro" (at -1.9 5.947) (layer "F.Fab") hide
      (effects (font (size 0.7 0.7) (thickness 0.15)) (justify left bottom))
    )
    (fp_line (start -0.3 0.8) (end 0.3 0.8) (layer "F.SilkS") (width 0.15))
    (fp_line (start -0.3 -0.8) (end 0.3 -0.8) (layer "F.SilkS") (width 0.15))
    (fp_rect (start -1.9 -0.93) (end 1.9 0.93) (layer "F.CrtYd") (width 0.05) (fill none))
    (fp_rect (start -0.95 -0.675) (end 0.95 0.675) (layer "F.Fab") (width 0.15) (fill none))
    (pad "1" smd rect (at -1.05 0) (size 1.2 1.2) (layers "F.Cu" "F.Paste" "F.Mask")
      (net 133 "5V_SYS") (pintype "passive"))
    (pad "2" smd rect (at 1.05 0) (size 1.2 1.2) (layers "F.Cu" "F.Paste" "F.Mask")
      (net 1 "GND") (pintype "passive"))
  )

  (footprint "sa800u-baseboard-hw-footprints:C_0805_2012Metric" (layer "F.Cu")
    (tedit 5FD9C126)
    (at 117.1 104.9 180)
    (descr "Capacitor SMD 0805")
    (tags "capacitor SMD 0805")
    (property "Author" "Antmicro")
    (property "DNP" "DNP")
    (property "Dielectric" "")
    (property "License" "Apache-2.0")
    (property "MPN" "0805X475K250CT")
    (property "Manufacturer" "Walsin")
    (property "Sheetfile" "camera-interface.kicad_sch")
    (property "Sheetname" "Camera Interface")
    (property "Val" "4u7")
    (property "Voltage" "")
    (attr exclude_from_pos_files)
    (fp_text reference "C108" (at 4.76 -0.43 180) (layer "F.SilkS")
      (effects (font (size 0.7 0.7) (thickness 0.15)) (justify left bottom))
    )
    (fp_text value "C_4u7_0805" (at 0 1.947 180) (layer "F.Fab")
      (effects (font (size 0.7 0.7) (thickness 0.15)) (justify left bottom))
    )
    (fp_text user "${REFERENCE}" (at -1.9 3.947 180) (layer "F.Fab") hide
      (effects (font (size 0.7 0.7) (thickness 0.15)) (justify left bottom))
    )
    (fp_text user "License: Apache-2.0" (at -1.9 4.947 180) (layer "F.Fab") hide
      (effects (font (size 0.7 0.7) (thickness 0.15)) (justify left bottom))
    )
    (fp_text user "Author: Antmicro" (at -1.9 5.947 180) (layer "F.Fab") hide
      (effects (font (size 0.7 0.7) (thickness 0.15)) (justify left bottom))
    )
    (fp_line (start -0.3 -0.8) (end 0.3 -0.8) (layer "F.SilkS") (width 0.15))
    (fp_line (start -0.3 0.8) (end 0.3 0.8) (layer "F.SilkS") (width 0.15))
    (fp_rect (start -1.9 -0.93) (end 1.9 0.93) (layer "F.CrtYd") (width 0.05) (fill none))
    (fp_rect (start -0.95 -0.675) (end 0.95 0.675) (layer "F.Fab") (width 0.15) (fill none))
    (pad "1" smd rect (at -1.05 0 180) (size 1.2 1.2) (layers "F.Cu" "F.Paste" "F.Mask")
      (net 353 "Net-(C108-Pad1)") (pintype "passive"))
    (pad "2" smd rect (at 1.05 0 180) (size 1.2 1.2) (layers "F.Cu" "F.Paste" "F.Mask")
      (net 1 "GND") (pintype "passive"))
  )

  (footprint "sa800u-baseboard-hw-footprints:R_0402_1005Metric" (layer "F.Cu")
    (tedit 5FD9C158)
    (at 137.2 103 180)
    (descr "Resistor SMD 0402")
    (tags "resistor SMD 0402")
    (property "Author" "Antmicro")
    (property "License" "Apache-2.0")
    (property "MPN" "CR0402-FX-1001GLF")
    (property "Manufacturer" "Bourns")
    (property "Sheetfile" "som.kicad_sch")
    (property "Sheetname" "SoM")
    (property "Tolerance" "1%")
    (property "Val" "1k")
    (attr smd)
    (fp_text reference "R69" (at -0.81 -0.4 180) (layer "F.SilkS")
      (effects (font (size 0.7 0.7) (thickness 0.15)) (justify left bottom))
    )
    (fp_text value "R_1k_0402" (at 0 1.4 180) (layer "F.Fab")
      (effects (font (size 0.7 0.7) (thickness 0.15)) (justify left bottom))
    )
    (fp_text user "Author: Antmicro" (at -0.95 4.169 180) (layer "F.Fab") hide
      (effects (font (size 0.7 0.7) (thickness 0.15)) (justify left bottom))
    )
    (fp_text user "License: Apache-2.0" (at -0.95 5.169 180) (layer "F.Fab") hide
      (effects (font (size 0.7 0.7) (thickness 0.15)) (justify left bottom))
    )
    (fp_text user "${REFERENCE}" (at -0.95 3.168 180) (layer "F.Fab") hide
      (effects (font (size 0.7 0.7) (thickness 0.15)) (justify left bottom))
    )
    (fp_rect (start -0.93 -0.47) (end 0.93 0.47) (layer "F.CrtYd") (width 0.05) (fill none))
    (fp_rect (start -0.5 -0.25) (end 0.5 0.25) (layer "F.Fab") (width 0.15) (fill none))
    (pad "1" smd roundrect (at -0.485 0 180) (size 0.59 0.64) (layers "F.Cu" "F.Paste" "F.Mask") (roundrect_rratio 0.25)
      (net 397 "Net-(R69-Pad1)") (pintype "passive"))
    (pad "2" smd roundrect (at 0.485 0 180) (size 0.59 0.64) (layers "F.Cu" "F.Paste" "F.Mask") (roundrect_rratio 0.25)
      (net 1 "GND") (pintype "passive"))
  )

  (footprint "sa800u-baseboard-hw-footprints:R_0603_1608Metric" (layer "F.Cu")
    (tedit 5D5D3E92)
    (at 117.6 93.5 180)
    (descr "Resistor SMD 0603")
    (tags "resistor SMD 0603")
    (property "Author" "Antmicro")
    (property "Current" "1A")
    (property "DNP" "DNP")
    (property "License" "Apache-2.0")
    (property "MPN" "CR0603-J/-000ELF")
    (property "Manufacturer" "Bourns")
    (property "Sheetfile" "camera-interface.kicad_sch")
    (property "Sheetname" "Camera Interface")
    (property "Tolerance" "")
    (property "Val" "0R")
    (attr exclude_from_pos_files)
    (fp_text reference "R85" (at 1.05 -1.38 180) (layer "F.SilkS")
      (effects (font (size 0.7 0.7) (thickness 0.15)) (justify left bottom))
    )
    (fp_text value "R_0R_0603" (at 0 1.6 180) (layer "F.Fab")
      (effects (font (size 0.7 0.7) (thickness 0.15)) (justify left bottom))
    )
    (fp_text user "License: Apache-2.0" (at -1.25 5.9 180) (layer "F.Fab") hide
      (effects (font (size 0.7 0.7) (thickness 0.15)) (justify left bottom))
    )
    (fp_text user "Author: Antmicro" (at -1.25 4.9 180) (layer "F.Fab") hide
      (effects (font (size 0.7 0.7) (thickness 0.15)) (justify left bottom))
    )
    (fp_text user "${REFERENCE}" (at -1.25 3.898 180) (layer "F.Fab") hide
      (effects (font (size 0.7 0.7) (thickness 0.15)) (justify left bottom))
    )
    (fp_line (start -0.3 -0.3) (end 0.3 -0.3) (layer "F.SilkS") (width 0.15))
    (fp_line (start -0.3 0.3) (end 0.3 0.3) (layer "F.SilkS") (width 0.15))
    (fp_rect (start -1.25 -0.7) (end 1.25 0.7) (layer "F.CrtYd") (width 0.05) (fill none))
    (fp_rect (start -0.8 -0.4) (end 0.8 0.4) (layer "F.Fab") (width 0.15) (fill none))
    (pad "1" smd roundrect (at -0.7 0 180) (size 0.6 0.8) (layers "F.Cu" "F.Paste" "F.Mask") (roundrect_rratio 0.2)
      (net 353 "Net-(C108-Pad1)") (pintype "passive"))
    (pad "2" smd roundrect (at 0.7 0 180) (size 0.6 0.8) (layers "F.Cu" "F.Paste" "F.Mask") (roundrect_rratio 0.2)
      (net 231 "/Camera Interface/3V3_CAM") (pintype "passive"))
  )

  (footprint "sa800u-baseboard-hw-footprints:SOT-223" (layer "F.Cu")
    (tedit 5D5D462E)
    (at 118.3 99.45)
    (property "Author" "Antmicro")
    (property "DNP" "DNP")
    (property "License" "Apache-2.0")
    (property "MPN" "AP2114H-3.3TRG1")
    (property "Manufacturer" "Diodes Incorporated")
    (property "Sheetfile" "camera-interface.kicad_sch")
    (property "Sheetname" "Camera Interface")
    (attr exclude_from_pos_files)
    (fp_text reference "U12" (at 1.99 -2.15) (layer "F.SilkS")
      (effects (font (size 0.7 0.7) (thickness 0.15)) (justify left bottom))
    )
    (fp_text value "AP2114H-3.3TRG1" (at 0 5.3) (layer "F.Fab")
      (effects (font (size 0.7 0.7) (thickness 0.15)) (justify left bottom))
    )
    (fp_text user "Author: Antmicro" (at -3.451 8.849) (layer "F.Fab") hide
      (effects (font (size 0.7 0.7) (thickness 0.15)) (justify left bottom))
    )
    (fp_text user "License: Apache-2.0" (at -3.451 10.048) (layer "F.Fab") hide
      (effects (font (size 0.7 0.7) (thickness 0.15)) (justify left bottom))
    )
    (fp_text user "${REFERENCE}" (at -3.451 7.65) (layer "F.Fab") hide
      (effects (font (size 0.7 0.7) (thickness 0.15)) (justify left bottom))
    )
    (fp_line (start 3.273 1.773) (end 2.825 1.773) (layer "F.SilkS") (width 0.15))
    (fp_line (start -3.275 1.449) (end -2.976 1.773) (layer "F.SilkS") (width 0.15))
    (fp_line (start -2.976 1.773) (end -2.976 1.969) (layer "F.SilkS") (width 0.15))
    (fp_line (start 2.898 -1.776) (end 3.273 -1.776) (layer "F.SilkS") (width 0.15))
    (fp_line (start -2.775 -1.776) (end -3.275 -1.776) (layer "F.SilkS") (width 0.15))
    (fp_line (start -3.275 0.973) (end -3.275 1.449) (layer "F.SilkS") (width 0.15))
    (fp_line (start 3.273 -1.776) (end 3.273 -1.476) (layer "F.SilkS") (width 0.15))
    (fp_line (start -3.275 -1.776) (end -3.275 -1.375) (layer "F.SilkS") (width 0.15))
    (fp_line (start 3.273 1.3) (end 3.273 1.773) (layer "F.SilkS") (width 0.15))
    (fp_circle (center -3.3 2.6) (end -3.25 2.6) (layer "F.SilkS") (width 0.15) (fill solid))
    (fp_line (start -2 -4.3) (end -2 -2) (layer "F.CrtYd") (width 0.05))
    (fp_line (start 3.5 -2) (end 3.5 4.3) (layer "F.CrtYd") (width 0.05))
    (fp_line (start -3.5 4.3) (end 3.5 4.3) (layer "F.CrtYd") (width 0.05))
    (fp_line (start -3.5 -2) (end -3.5 4.3) (layer "F.CrtYd") (width 0.05))
    (fp_line (start 3.5 -2) (end 2 -2) (layer "F.CrtYd") (width 0.05))
    (fp_line (start 2 -4.3) (end 2 -2) (layer "F.CrtYd") (width 0.05))
    (fp_line (start -2 -2) (end -3.5 -2) (layer "F.CrtYd") (width 0.05))
    (fp_line (start 2 -4.3) (end -2 -4.3) (layer "F.CrtYd") (width 0.05))
    (fp_line (start -3.15 1.35) (end -2.875 1.648) (layer "F.Fab") (width 0.15))
    (fp_line (start -3.15 -1.651) (end 3.148 -1.651) (layer "F.Fab") (width 0.15))
    (fp_line (start 3.148 1.648) (end -2.875 1.648) (layer "F.Fab") (width 0.15))
    (fp_line (start 3.148 -1.651) (end 3.148 1.648) (layer "F.Fab") (width 0.15))
    (fp_line (start -3.15 1.35) (end -3.15 -1.651) (layer "F.Fab") (width 0.15))
    (pad "1" smd rect (at -2.301 3.148) (size 1.5 2.2) (layers "F.Cu" "F.Paste" "F.Mask")
      (net 1 "GND") (pinfunction "GND") (pintype "power_in"))
    (pad "2" smd rect (at 0 3.148) (size 1.5 2.2) (layers "F.Cu" "F.Paste" "F.Mask")
      (net 353 "Net-(C108-Pad1)") (pinfunction "VOUT") (pintype "output"))
    (pad "3" smd rect (at 2.298 3.148) (size 1.5 2.2) (layers "F.Cu" "F.Paste" "F.Mask")
      (net 133 "5V_SYS") (pinfunction "IN") (pintype "input"))
    (pad "4" smd rect (at 0 -3.15) (size 3.8 2.2) (layers "F.Cu" "F.Paste" "F.Mask")
      (net 353 "Net-(C108-Pad1)") (pinfunction "VOUT") (pintype "passive"))
  )

  (footprint "sa800u-baseboard-hw-footprints:C_0402_1005Metric" (layer "F.Cu")
    (tedit 616D63CF)
    (at 145.2 95.9 180)
    (descr "Capacitor SMD 0402")
    (tags "capacitor SMD 0402")
    (property "Author" "Antmicro")
    (property "Dielectric" "X5R")
    (property "License" "Apache-2.0")
    (property "MPN" "GRM155R61H104KE14D")
    (property "Manufacturer" "Murata")
    (property "Sheetfile" "m2.kicad_sch")
    (property "Sheetname" "M2")
    (property "Val" "100n")
    (property "Voltage" "50V")
    (attr smd)
    (fp_text reference "C116" (at 3.74 -0.37 180) (layer "F.SilkS")
      (effects (font (size 0.7 0.7) (thickness 0.15)) (justify left bottom))
    )
    (fp_text value "C_100n_0402" (at 0 1.4 180) (layer "F.Fab")
      (effects (font (size 0.7 0.7) (thickness 0.15)) (justify left bottom))
    )
    (fp_text user "License: Apache-2.0" (at -0.932 5.17 180) (layer "F.Fab") hide
      (effects (font (size 0.7 0.7) (thickness 0.15)) (justify left bottom))
    )
    (fp_text user "${REFERENCE}" (at -0.932 3.168 180) (layer "F.Fab") hide
      (effects (font (size 0.7 0.7) (thickness 0.15)) (justify left bottom))
    )
    (fp_text user "Author: Antmicro" (at -0.932 4.17 180) (layer "F.Fab") hide
      (effects (font (size 0.7 0.7) (thickness 0.15)) (justify left bottom))
    )
    (fp_rect (start -0.94 -0.47) (end 0.94 0.47) (layer "F.CrtYd") (width 0.05) (fill none))
    (fp_rect (start -0.499 -0.249) (end 0.499 0.249) (layer "F.Fab") (width 0.15) (fill none))
    (pad "1" smd roundrect (at -0.484 0 180) (size 0.59 0.64) (layers "F.Cu" "F.Paste" "F.Mask") (roundrect_rratio 0.25)
      (net 111 "/M2/C_PCIE0_TX0_N") (pintype "passive"))
    (pad "2" smd roundrect (at 0.484 0 180) (size 0.59 0.64) (layers "F.Cu" "F.Paste" "F.Mask") (roundrect_rratio 0.25)
      (net 110 "PCIE0_TX_N") (pintype "passive"))
  )

  (footprint "sa800u-baseboard-hw-footprints:R_0402_1005Metric" (layer "F.Cu")
    (tedit 5FD9C158)
    (at 144.95 94.4)
    (descr "Resistor SMD 0402")
    (tags "resistor SMD 0402")
    (property "Author" "Antmicro")
    (property "License" "Apache-2.0")
    (property "MPN" "CR0402-FX-2200GLF")
    (property "Manufacturer" "Bourns")
    (property "Sheetfile" "m2.kicad_sch")
    (property "Sheetname" "M2")
    (property "Tolerance" "1%")
    (property "Val" "220R")
    (attr smd)
    (fp_text reference "R92" (at -3.04 0.36) (layer "F.SilkS")
      (effects (font (size 0.7 0.7) (thickness 0.15)) (justify left bottom))
    )
    (fp_text value "R_220R_0402" (at 0 1.4) (layer "F.Fab")
      (effects (font (size 0.7 0.7) (thickness 0.15)) (justify left bottom))
    )
    (fp_text user "Author: Antmicro" (at -0.95 4.169) (layer "F.Fab") hide
      (effects (font (size 0.7 0.7) (thickness 0.15)) (justify left bottom))
    )
    (fp_text user "${REFERENCE}" (at -0.95 3.168) (layer "F.Fab") hide
      (effects (font (size 0.7 0.7) (thickness 0.15)) (justify left bottom))
    )
    (fp_text user "License: Apache-2.0" (at -0.95 5.169) (layer "F.Fab") hide
      (effects (font (size 0.7 0.7) (thickness 0.15)) (justify left bottom))
    )
    (fp_rect (start -0.93 -0.47) (end 0.93 0.47) (layer "F.CrtYd") (width 0.05) (fill none))
    (fp_rect (start -0.5 -0.25) (end 0.5 0.25) (layer "F.Fab") (width 0.15) (fill none))
    (pad "1" smd roundrect (at -0.485 0) (size 0.59 0.64) (layers "F.Cu" "F.Paste" "F.Mask") (roundrect_rratio 0.25)
      (net 131 "3V3_SYS") (pintype "passive"))
    (pad "2" smd roundrect (at 0.485 0) (size 0.59 0.64) (layers "F.Cu" "F.Paste" "F.Mask") (roundrect_rratio 0.25)
      (net 373 "Net-(D21-Pad1)") (pintype "passive"))
  )

  (footprint "sa800u-baseboard-hw-footprints:Receptacle_SA800U-WF" locked (layer "F.Cu")
    (tedit 6215E1EF)
    (at 112.47 100.96)
    (property "Author" "Antmicro")
    (property "License" "Apache-2.0")
    (property "MPN" "FX10A-168S-SV")
    (property "Manufacturer" "Hirose Electric")
    (property "Sheetfile" "som.kicad_sch")
    (property "Sheetname" "SoM")
    (attr smd)
    (fp_text reference "U11" (at 0.005 -19.31) (layer "F.SilkS")
      (effects (font (size 0.7 0.7) (thickness 0.15)) (justify left bottom))
    )
    (fp_text value "Receptacle_SA800U-WF" (at 0 20.4) (layer "F.Fab")
      (effects (font (size 0.7 0.7) (thickness 0.15)) (justify left bottom))
    )
    (fp_text user "${REFERENCE}-J1" (at 0 -14.6) (layer "F.Fab") hide
      (effects (font (size 0.7 0.7) (thickness 0.15)) (justify left bottom))
    )
    (fp_text user "${REFERENCE}-J2" (at 0 14.4) (layer "F.Fab") hide
      (effects (font (size 0.7 0.7) (thickness 0.15)) (justify left bottom))
    )
    (fp_text user "License: Apache-2.0" (at -28.99 23) (layer "F.Fab") hide
      (effects (font (size 0.7 0.7) (thickness 0.15)) (justify left bottom))
    )
    (fp_text user "Author: Antmicro" (at -28.99 21.824) (layer "F.Fab") hide
      (effects (font (size 0.7 0.7) (thickness 0.15)) (justify left bottom))
    )
    (fp_text user "${REFERENCE}" (at -28.99 24.199) (layer "F.Fab") hide
      (effects (font (size 0.7 0.7) (thickness 0.15)) (justify left bottom))
    )
    (fp_text user "FX10A-168S-SV(21)" (at 0 -13.6) (layer "F.Fab") hide
      (effects (font (size 0.7 0.7) (thickness 0.15)) (justify left bottom))
    )
    (fp_text user "FX10A-168S-SV(21)" (at 0 15.4) (layer "F.Fab") hide
      (effects (font (size 0.7 0.7) (thickness 0.15)) (justify left bottom))
    )
    (fp_line (start -25.82 16.444) (end -25.82 18.454) (layer "F.SilkS") (width 0.15))
    (fp_line (start -22.229 10.592) (end -25.82 10.592) (layer "F.SilkS") (width 0.15))
    (fp_line (start 25.839 -10.546) (end 25.839 -12.557) (layer "F.SilkS") (width 0.15))
    (fp_line (start -23.819 -10.546) (end -20.229 -10.546) (layer "F.SilkS") (width 0.15))
    (fp_line (start -25.82 10.592) (end -25.82 12.592) (layer "F.SilkS") (width 0.15))
    (fp_line (start 20.251 18.454) (end 23.839 18.454) (layer "F.SilkS") (width 0.15))
    (fp_line (start -23.819 -18.406) (end -23.819 -16.407) (layer "F.SilkS") (width 0.15))
    (fp_line (start 22.251 -10.546) (end 25.839 -10.546) (layer "F.SilkS") (width 0.15))
    (fp_line (start -25.82 18.454) (end -22.229 18.454) (layer "F.SilkS") (width 0.15))
    (fp_line (start -20.229 -18.406) (end -23.819 -18.406) (layer "F.SilkS") (width 0.15))
    (fp_line (start 23.839 18.454) (end 23.839 16.444) (layer "F.SilkS") (width 0.15))
    (fp_line (start -23.819 -12.557) (end -23.819 -10.546) (layer "F.SilkS") (width 0.15))
    (fp_line (start 25.839 -16.407) (end 25.839 -18.406) (layer "F.SilkS") (width 0.15))
    (fp_line (start 23.839 12.592) (end 23.839 10.592) (layer "F.SilkS") (width 0.15))
    (fp_line (start 20.248 10.592) (end 23.839 10.592) (layer "F.SilkS") (width 0.15))
    (fp_rect (start -26.1 10.3) (end 24.1 18.7) (layer "F.CrtYd") (width 0.05) (fill none))
    (fp_rect (start -24.1 -18.677) (end 26.1 -10.277) (layer "F.CrtYd") (width 0.05) (fill none))
    (fp_line (start 25.711 -10.676) (end 25.711 -18.276) (layer "F.Fab") (width 0.15))
    (fp_line (start -25.691 10.723) (end -25.691 18.323) (layer "F.Fab") (width 0.15))
    (fp_line (start -23.689 -18.276) (end -23.689 -10.676) (layer "F.Fab") (width 0.15))
    (fp_line (start 25.711 -18.276) (end -23.689 -18.276) (layer "F.Fab") (width 0.15))
    (fp_line (start -25.691 18.323) (end 23.711 18.323) (layer "F.Fab") (width 0.15))
    (fp_line (start 23.711 10.723) (end -25.691 10.723) (layer "F.Fab") (width 0.15))
    (fp_line (start -23.689 -10.676) (end 25.711 -10.676) (layer "F.Fab") (width 0.15))
    (fp_line (start 23.711 18.323) (end 23.711 10.723) (layer "F.Fab") (width 0.15))
    (pad "" np_thru_hole circle locked (at -26.538 -14.477) (size 4 4) (drill 2) (layers *.Cu *.Mask))
    (pad "" np_thru_hole circle locked (at 23.211 -14.477 270) (size 1.25 1.25) (drill 1.25) (layers *.Cu *.Mask))
    (pad "" np_thru_hole circle locked (at -28.538 14.524) (size 4 4) (drill 2) (layers *.Cu *.Mask))
    (pad "" np_thru_hole circle locked (at -21.189 -14.477 270) (size 1.25 1.25) (drill 1.25) (layers *.Mask "F.Cu"))
    (pad "" np_thru_hole circle locked (at 21.211 14.524 270) (size 1.25 1.25) (drill 1.25) (layers *.Cu *.Mask))
    (pad "" np_thru_hole circle locked (at 26.56 14.724) (size 4 4) (drill 2) (layers *.Cu *.Mask))
    (pad "" np_thru_hole circle locked (at -23.189 14.524 270) (size 1.25 1.25) (drill 1.25) (layers *.Cu *.Mask))
    (pad "" np_thru_hole circle locked (at 28.56 -14.477) (size 4 4) (drill 2) (layers *.Cu *.Mask))
    (pad "1_1" smd rect locked (at 21.76 -11.426 180) (size 0.33 1.6) (layers "F.Cu" "F.Paste" "F.Mask")
      (net 124 "PCIE0_RST_N") (pinfunction "PCIE0_RST_N") (pintype "output"))
    (pad "1_2" smd rect locked (at 21.76 -17.526 180) (size 0.33 1.6) (layers "F.Cu" "F.Paste" "F.Mask")
      (net 1 "GND") (pinfunction "GND") (pintype "passive"))
    (pad "1_3" smd rect locked (at 21.26 -11.426 180) (size 0.33 1.6) (layers "F.Cu" "F.Paste" "F.Mask")
      (net 119 "PCIE0_WAKE_N") (pinfunction "PCIE0_WAKE_N") (pintype "input"))
    (pad "1_4" smd rect locked (at 21.26 -17.526 180) (size 0.33 1.6) (layers "F.Cu" "F.Paste" "F.Mask")
      (net 28 "CSI0_LN3_P") (pinfunction "CSI0_LN3_P") (pintype "input"))
    (pad "1_5" smd rect locked (at 20.76 -11.426 180) (size 0.33 1.6) (layers "F.Cu" "F.Paste" "F.Mask")
      (net 120 "PCIE0_CLKREQ_N") (pinfunction "PCIE0_CLKREQ_N") (pintype "input"))
    (pad "1_6" smd rect locked (at 20.76 -17.526 180) (size 0.33 1.6) (layers "F.Cu" "F.Paste" "F.Mask")
      (net 27 "CSI0_LN3_N") (pinfunction "CSI0_LN3_N") (pintype "input"))
    (pad "1_7" smd rect locked (at 20.26 -11.426 180) (size 0.33 1.6) (layers "F.Cu" "F.Paste" "F.Mask")
      (net 1 "GND") (pinfunction "GND") (pintype "passive"))
    (pad "1_8" smd rect locked (at 20.26 -17.526 180) (size 0.33 1.6) (layers "F.Cu" "F.Paste" "F.Mask")
      (net 1 "GND") (pinfunction "GND") (pintype "passive"))
    (pad "1_9" smd rect locked (at 19.76 -11.426 180) (size 0.33 1.6) (layers "F.Cu" "F.Paste" "F.Mask")
      (net 110 "PCIE0_TX_N") (pinfunction "PCIE0_TX_M") (pintype "output"))
    (pad "1_10" smd rect locked (at 19.76 -17.526 180) (size 0.33 1.6) (layers "F.Cu" "F.Paste" "F.Mask")
      (net 30 "CSI0_LN2_N") (pinfunction "CSI0_LN2_N") (pintype "input"))
    (pad "1_11" smd rect locked (at 19.26 -11.426 180) (size 0.33 1.6) (layers "F.Cu" "F.Paste" "F.Mask")
      (net 108 "PCIE0_TX_P") (pinfunction "PCIE0_TX_P") (pintype "output"))
    (pad "1_12" smd rect locked (at 19.26 -17.526 180) (size 0.33 1.6) (layers "F.Cu" "F.Paste" "F.Mask")
      (net 29 "CSI0_LN2_P") (pinfunction "CSI0_LN2_P") (pintype "input"))
    (pad "1_13" smd rect locked (at 18.76 -11.426 180) (size 0.33 1.6) (layers "F.Cu" "F.Paste" "F.Mask")
      (net 1 "GND") (pinfunction "GND") (pintype "passive"))
    (pad "1_14" smd rect locked (at 18.76 -17.526 180) (size 0.33 1.6) (layers "F.Cu" "F.Paste" "F.Mask")
      (net 1 "GND") (pinfunction "GND") (pintype "passive"))
    (pad "1_15" smd rect locked (at 18.26 -11.426 180) (size 0.33 1.6) (layers "F.Cu" "F.Paste" "F.Mask")
      (net 122 "PCIE0_REFCLK_P") (pinfunction "PCIE0_REFCLK_P") (pintype "output"))
    (pad "1_16" smd rect locked (at 18.26 -17.526 180) (size 0.33 1.6) (layers "F.Cu" "F.Paste" "F.Mask")
      (net 31 "CSI0_LN1_N") (pinfunction "CSI0_LN1_N") (pintype "input"))
    (pad "1_17" smd rect locked (at 17.76 -11.426 180) (size 0.33 1.6) (layers "F.Cu" "F.Paste" "F.Mask")
      (net 126 "PCIE0_REFCLK_N") (pinfunction "PCIE0_REFCLK_M") (pintype "output"))
    (pad "1_18" smd rect locked (at 17.76 -17.526 180) (size 0.33 1.6) (layers "F.Cu" "F.Paste" "F.Mask")
      (net 32 "CSI0_LN1_P") (pinfunction "CSI0_LN1_P") (pintype "input"))
    (pad "1_19" smd rect locked (at 17.26 -11.426 180) (size 0.33 1.6) (layers "F.Cu" "F.Paste" "F.Mask")
      (net 1 "GND") (pinfunction "GND") (pintype "passive"))
    (pad "1_20" smd rect locked (at 17.26 -17.526 180) (size 0.33 1.6) (layers "F.Cu" "F.Paste" "F.Mask")
      (net 1 "GND") (pinfunction "GND") (pintype "passive"))
    (pad "1_21" smd rect locked (at 16.76 -11.426 180) (size 0.33 1.6) (layers "F.Cu" "F.Paste" "F.Mask")
      (net 123 "PCIE0_RX_P") (pinfunction "PCIE0_RX_P") (pintype "input"))
    (pad "1_22" smd rect locked (at 16.76 -17.526 180) (size 0.33 1.6) (layers "F.Cu" "F.Paste" "F.Mask")
      (net 33 "CSI0_LN0_N") (pinfunction "CSI0_LN0_N") (pintype "input"))
    (pad "1_23" smd rect locked (at 16.26 -11.426 180) (size 0.33 1.6) (layers "F.Cu" "F.Paste" "F.Mask")
      (net 125 "PCIE0_RX_N") (pinfunction "PCIE0_RX_M") (pintype "input"))
    (pad "1_24" smd rect locked (at 16.26 -17.526 180) (size 0.33 1.6) (layers "F.Cu" "F.Paste" "F.Mask")
      (net 34 "CSI0_LN0_P") (pinfunction "CSI0_LN0_P") (pintype "input"))
    (pad "1_25" smd rect locked (at 15.761 -11.426 180) (size 0.33 1.6) (layers "F.Cu" "F.Paste" "F.Mask")
      (net 1 "GND") (pinfunction "GND") (pintype "passive"))
    (pad "1_26" smd rect locked (at 15.761 -17.526 180) (size 0.33 1.6) (layers "F.Cu" "F.Paste" "F.Mask")
      (net 1 "GND") (pinfunction "GND") (pintype "passive"))
    (pad "1_27" smd rect locked (at 15.261 -11.426 180) (size 0.33 1.6) (layers "F.Cu" "F.Paste" "F.Mask")
      (net 625 "unconnected-(U11-Pad1_27)") (pinfunction "UFS_RX_M") (pintype "input+no_connect"))
    (pad "1_28" smd rect locked (at 15.261 -17.526 180) (size 0.33 1.6) (layers "F.Cu" "F.Paste" "F.Mask")
      (net 13 "CSI0_CLK_P") (pinfunction "CSI0_CLK_P") (pintype "input"))
    (pad "1_29" smd rect locked (at 14.761 -11.426 180) (size 0.33 1.6) (layers "F.Cu" "F.Paste" "F.Mask")
      (net 624 "unconnected-(U11-Pad1_29)") (pinfunction "UFS_RX_P") (pintype "input+no_connect"))
    (pad "1_30" smd rect locked (at 14.761 -17.526 180) (size 0.33 1.6) (layers "F.Cu" "F.Paste" "F.Mask")
      (net 12 "CSI0_CLK_N") (pinfunction "CSI0_CLK_N") (pintype "input"))
    (pad "1_31" smd rect locked (at 14.261 -11.426 180) (size 0.33 1.6) (layers "F.Cu" "F.Paste" "F.Mask")
      (net 1 "GND") (pinfunction "GND") (pintype "passive"))
    (pad "1_32" smd rect locked (at 14.261 -17.526 180) (size 0.33 1.6) (layers "F.Cu" "F.Paste" "F.Mask")
      (net 1 "GND") (pinfunction "GND") (pintype "passive"))
    (pad "1_33" smd rect locked (at 13.761 -11.426 180) (size 0.33 1.6) (layers "F.Cu" "F.Paste" "F.Mask")
      (net 623 "unconnected-(U11-Pad1_33)") (pinfunction "UFS_TX_P") (pintype "output+no_connect"))
    (pad "1_34" smd rect locked (at 13.761 -17.526 180) (size 0.33 1.6) (layers "F.Cu" "F.Paste" "F.Mask")
      (net 18 "CSI1_LN3_N") (pinfunction "CSI1_LN3_N") (pintype "input"))
    (pad "1_35" smd rect locked (at 13.261 -11.426 180) (size 0.33 1.6) (layers "F.Cu" "F.Paste" "F.Mask")
      (net 622 "unconnected-(U11-Pad1_35)") (pinfunction "UFS_TX_M") (pintype "output+no_connect"))
    (pad "1_36" smd rect locked (at 13.261 -17.526 180) (size 0.33 1.6) (layers "F.Cu" "F.Paste" "F.Mask")
      (net 17 "CSI1_LN3_P") (pinfunction "CSI1_LN3_P") (pintype "input"))
    (pad "1_37" smd rect locked (at 12.761 -11.426 180) (size 0.33 1.6) (layers "F.Cu" "F.Paste" "F.Mask")
      (net 1 "GND") (pinfunction "GND") (pintype "passive"))
    (pad "1_38" smd rect locked (at 12.761 -17.526 180) (size 0.33 1.6) (layers "F.Cu" "F.Paste" "F.Mask")
      (net 1 "GND") (pinfunction "GND") (pintype "passive"))
    (pad "1_39" smd rect locked (at 12.261 -11.426 180) (size 0.33 1.6) (layers "F.Cu" "F.Paste" "F.Mask")
      (net 621 "unconnected-(U11-Pad1_39)") (pinfunction "UFS_CLK") (pintype "output+no_connect"))
    (pad "1_40" smd rect locked (at 12.261 -17.526 180) (size 0.33 1.6) (layers "F.Cu" "F.Paste" "F.Mask")
      (net 19 "CSI1_LN2_P") (pinfunction "CSI1_LN2_P") (pintype "input"))
    (pad "1_41" smd rect locked (at 11.761 -11.426 180) (size 0.33 1.6) (layers "F.Cu" "F.Paste" "F.Mask")
      (net 1 "GND") (pinfunction "GND") (pintype "passive"))
    (pad "1_42" smd rect locked (at 11.761 -17.526 180) (size 0.33 1.6) (layers "F.Cu" "F.Paste" "F.Mask")
      (net 20 "CSI1_LN2_N") (pinfunction "CSI1_LN2_N") (pintype "input"))
    (pad "1_43" smd rect locked (at 11.261 -11.426 180) (size 0.33 1.6) (layers "F.Cu" "F.Paste" "F.Mask")
      (net 620 "/SoM/LCM_VDD_EN") (pinfunction "UFS_DET") (pintype "output+no_connect"))
    (pad "1_44" smd rect locked (at 11.261 -17.526 180) (size 0.33 1.6) (layers "F.Cu" "F.Paste" "F.Mask")
      (net 1 "GND") (pinfunction "GND") (pintype "passive"))
    (pad "1_45" smd rect locked (at 10.761 -11.426 180) (size 0.33 1.6) (layers "F.Cu" "F.Paste" "F.Mask")
      (net 116 "SD_CLK") (pinfunction "SD_CLK") (pintype "output"))
    (pad "1_46" smd rect locked (at 10.761 -17.526 180) (size 0.33 1.6) (layers "F.Cu" "F.Paste" "F.Mask")
      (net 22 "CSI1_LN1_N") (pinfunction "CSI1_LN1_N") (pintype "input"))
    (pad "1_47" smd rect locked (at 10.261 -11.426 180) (size 0.33 1.6) (layers "F.Cu" "F.Paste" "F.Mask")
      (net 115 "SD_CMD") (pinfunction "SD_CMD") (pintype "output"))
    (pad "1_48" smd rect locked (at 10.261 -17.526 180) (size 0.33 1.6) (layers "F.Cu" "F.Paste" "F.Mask")
      (net 21 "CSI1_LN1_P") (pinfunction "CSI1_LN1_P") (pintype "input"))
    (pad "1_49" smd rect locked (at 9.761 -11.426 180) (size 0.33 1.6) (layers "F.Cu" "F.Paste" "F.Mask")
      (net 112 "SD_DET") (pinfunction "SD_DET") (pintype "input"))
    (pad "1_50" smd rect locked (at 9.761 -17.526 180) (size 0.33 1.6) (layers "F.Cu" "F.Paste" "F.Mask")
      (net 1 "GND") (pinfunction "GND") (pintype "passive"))
    (pad "1_51" smd rect locked (at 9.261 -11.426 180) (size 0.33 1.6) (layers "F.Cu" "F.Paste" "F.Mask")
      (net 118 "SD_DATA0") (pinfunction "SD_DATA0") (pintype "bidirectional"))
    (pad "1_52" smd rect locked (at 9.261 -17.526 180) (size 0.33 1.6) (layers "F.Cu" "F.Paste" "F.Mask")
      (net 23 "CSI1_LN0_N") (pinfunction "CSI1_LN0_N") (pintype "input"))
    (pad "1_53" smd rect locked (at 8.761 -11.426 180) (size 0.33 1.6) (layers "F.Cu" "F.Paste" "F.Mask")
      (net 117 "SD_DATA1") (pinfunction "SD_DATA1") (pintype "bidirectional"))
    (pad "1_54" smd rect locked (at 8.761 -17.526 180) (size 0.33 1.6) (layers "F.Cu" "F.Paste" "F.Mask")
      (net 24 "CSI1_LN0_P") (pinfunction "CSI1_LN0_P") (pintype "input"))
    (pad "1_55" smd rect locked (at 8.261 -11.426 180) (size 0.33 1.6) (layers "F.Cu" "F.Paste" "F.Mask")
      (net 113 "SD_DATA3") (pinfunction "SD_DATA3") (pintype "bidirectional"))
    (pad "1_56" smd rect locked (at 8.261 -17.526 180) (size 0.33 1.6) (layers "F.Cu" "F.Paste" "F.Mask")
      (net 1 "GND") (pinfunction "GND") (pintype "passive"))
    (pad "1_57" smd rect locked (at 7.76 -11.426 180) (size 0.33 1.6) (layers "F.Cu" "F.Paste" "F.Mask")
      (net 114 "SD_DATA2") (pinfunction "SD_DATA2") (pintype "bidirectional"))
    (pad "1_58" smd rect locked (at 7.76 -17.526 180) (size 0.33 1.6) (layers "F.Cu" "F.Paste" "F.Mask")
      (net 26 "CSI1_CLK_N") (pinfunction "CSI1_CLK_N") (pintype "input"))
    (pad "1_59" smd rect locked (at 7.26 -11.426 180) (size 0.33 1.6) (layers "F.Cu" "F.Paste" "F.Mask")
      (net 1 "GND") (pinfunction "GND") (pintype "passive"))
    (pad "1_60" smd rect locked (at 7.26 -17.526 180) (size 0.33 1.6) (layers "F.Cu" "F.Paste" "F.Mask")
      (net 25 "CSI1_CLK_P") (pinfunction "CSI1_CLK_P") (pintype "input"))
    (pad "1_61" smd rect locked (at 6.76 -11.426 180) (size 0.33 1.6) (layers "F.Cu" "F.Paste" "F.Mask")
      (net 619 "/SoM/CSI2_CLK_P") (pinfunction "CSI2_CLK_P") (pintype "input+no_connect"))
    (pad "1_62" smd rect locked (at 6.76 -17.526 180) (size 0.33 1.6) (layers "F.Cu" "F.Paste" "F.Mask")
      (net 1 "GND") (pinfunction "GND") (pintype "passive"))
    (pad "1_63" smd rect locked (at 6.26 -11.426 180) (size 0.33 1.6) (layers "F.Cu" "F.Paste" "F.Mask")
      (net 618 "/SoM/CSI2_CLK_N") (pinfunction "CSI2_CLK_N") (pintype "input+no_connect"))
    (pad "1_64" smd rect locked (at 6.26 -17.526 180) (size 0.33 1.6) (layers "F.Cu" "F.Paste" "F.Mask")
      (net 617 "/SoM/CSI2_LN1_P") (pinfunction "CSI2_LN1_P") (pintype "input+no_connect"))
    (pad "1_65" smd rect locked (at 5.761 -11.426 180) (size 0.33 1.6) (layers "F.Cu" "F.Paste" "F.Mask")
      (net 1 "GND") (pinfunction "GND") (pintype "passive"))
    (pad "1_66" smd rect locked (at 5.761 -17.526 180) (size 0.33 1.6) (layers "F.Cu" "F.Paste" "F.Mask")
      (net 616 "/SoM/CSI2_LN1_N") (pinfunction "CSI2_LN1_N") (pintype "input+no_connect"))
    (pad "1_67" smd rect locked (at 5.261 -11.426 180) (size 0.33 1.6) (layers "F.Cu" "F.Paste" "F.Mask")
      (net 615 "/SoM/CSI2_LN0_N") (pinfunction "CSI2_LN0_N") (pintype "input+no_connect"))
    (pad "1_68" smd rect locked (at 5.261 -17.526 180) (size 0.33 1.6) (layers "F.Cu" "F.Paste" "F.Mask")
      (net 1 "GND") (pinfunction "GND") (pintype "passive"))
    (pad "1_69" smd rect locked (at 4.761 -11.426 180) (size 0.33 1.6) (layers "F.Cu" "F.Paste" "F.Mask")
      (net 614 "/SoM/CSI2_LN0_P") (pinfunction "CSI2_LN0_P") (pintype "input+no_connect"))
    (pad "1_70" smd rect locked (at 4.761 -17.526 180) (size 0.33 1.6) (layers "F.Cu" "F.Paste" "F.Mask")
      (net 613 "/SoM/CSI2_LN2_P") (pinfunction "CSI2_LN2_P") (pintype "input+no_connect"))
    (pad "1_71" smd rect locked (at 4.261 -11.426 180) (size 0.33 1.6) (layers "F.Cu" "F.Paste" "F.Mask")
      (net 1 "GND") (pinfunction "GND") (pintype "passive"))
    (pad "1_72" smd rect locked (at 4.261 -17.526 180) (size 0.33 1.6) (layers "F.Cu" "F.Paste" "F.Mask")
      (net 612 "/SoM/CSI2_LN2_N") (pinfunction "CSI2_LN2_N") (pintype "input+no_connect"))
    (pad "1_73" smd rect locked (at 3.761 -11.426 180) (size 0.33 1.6) (layers "F.Cu" "F.Paste" "F.Mask")
      (net 611 "/SoM/CSI3_LN1_N") (pinfunction "CSI3_LN1_N") (pintype "input+no_connect"))
    (pad "1_74" smd rect locked (at 3.761 -17.526 180) (size 0.33 1.6) (layers "F.Cu" "F.Paste" "F.Mask")
      (net 1 "GND") (pinfunction "GND") (pintype "passive"))
    (pad "1_75" smd rect locked (at 3.261 -11.426 180) (size 0.33 1.6) (layers "F.Cu" "F.Paste" "F.Mask")
      (net 610 "/SoM/CSI3_LN1_P") (pinfunction "CSI3_LN1_P") (pintype "input+no_connect"))
    (pad "1_76" smd rect locked (at 3.261 -17.526 180) (size 0.33 1.6) (layers "F.Cu" "F.Paste" "F.Mask")
      (net 609 "/SoM/CSI2_LN3_P") (pinfunction "CSI2_LN3_P") (pintype "input+no_connect"))
    (pad "1_77" smd rect locked (at 2.761 -11.426 180) (size 0.33 1.6) (layers "F.Cu" "F.Paste" "F.Mask")
      (net 1 "GND") (pinfunction "GND") (pintype "passive"))
    (pad "1_78" smd rect locked (at 2.761 -17.526 180) (size 0.33 1.6) (layers "F.Cu" "F.Paste" "F.Mask")
      (net 608 "/SoM/CSI2_LN3_N") (pinfunction "CSI2_LN3_N") (pintype "input+no_connect"))
    (pad "1_79" smd rect locked (at 2.261 -11.426 180) (size 0.33 1.6) (layers "F.Cu" "F.Paste" "F.Mask")
      (net 607 "/SoM/CSI3_LN0_P") (pinfunction "CSI3_LN0_P") (pintype "input+no_connect"))
    (pad "1_80" smd rect locked (at 2.261 -17.526 180) (size 0.33 1.6) (layers "F.Cu" "F.Paste" "F.Mask")
      (net 1 "GND") (pinfunction "GND") (pintype "passive"))
    (pad "1_81" smd rect locked (at 1.761 -11.426 180) (size 0.33 1.6) (layers "F.Cu" "F.Paste" "F.Mask")
      (net 606 "/SoM/CSI3_LN0_N") (pinfunction "CSI3_LN0_N") (pintype "input+no_connect"))
    (pad "1_82" smd rect locked (at 1.761 -17.526 180) (size 0.33 1.6) (layers "F.Cu" "F.Paste" "F.Mask")
      (net 605 "unconnected-(U11-Pad1_82)") (pinfunction "SDC4_DATA0") (pintype "output+no_connect"))
    (pad "1_83" smd rect locked (at 1.261 -11.426 180) (size 0.33 1.6) (layers "F.Cu" "F.Paste" "F.Mask")
      (net 1 "GND") (pinfunction "GND") (pintype "passive"))
    (pad "1_84" smd rect locked (at 1.261 -17.526 180) (size 0.33 1.6) (layers "F.Cu" "F.Paste" "F.Mask")
      (net 604 "unconnected-(U11-Pad1_84)") (pinfunction "SDC4_DATA1") (pintype "output+no_connect"))
    (pad "1_85" smd rect locked (at 0.76 -11.426 180) (size 0.33 1.6) (layers "F.Cu" "F.Paste" "F.Mask")
      (net 603 "/SoM/CSI3_CLK_N") (pinfunction "CSI3_CLK_N") (pintype "input+no_connect"))
    (pad "1_86" smd rect locked (at 0.76 -17.526 180) (size 0.33 1.6) (layers "F.Cu" "F.Paste" "F.Mask")
      (net 602 "/SoM/CAM0_AFVDD_EN") (pinfunction "SDC4_CLK") (pintype "output+no_connect"))
    (pad "1_87" smd rect locked (at 0.261 -11.426 180) (size 0.33 1.6) (layers "F.Cu" "F.Paste" "F.Mask")
      (net 601 "/SoM/CSI3_CLK_P") (pinfunction "CSI3_CLK_P") (pintype "input+no_connect"))
    (pad "1_88" smd rect locked (at 0.261 -17.526 180) (size 0.33 1.6) (layers "F.Cu" "F.Paste" "F.Mask")
      (net 600 "/SoM/CAM1_AFVDD_EN") (pinfunction "SDC4_DATA2") (pintype "output+no_connect"))
    (pad "1_89" smd rect locked (at -0.24 -11.426 180) (size 0.33 1.6) (layers "F.Cu" "F.Paste" "F.Mask")
      (net 1 "GND") (pinfunction "GND") (pintype "passive"))
    (pad "1_90" smd rect locked (at -0.24 -17.526 180) (size 0.33 1.6) (layers "F.Cu" "F.Paste" "F.Mask")
      (net 599 "/SoM/LT6911_RST") (pinfunction "SDC4_DATA3") (pintype "output+no_connect"))
    (pad "1_91" smd rect locked (at -0.739 -11.426 180) (size 0.33 1.6) (layers "F.Cu" "F.Paste" "F.Mask")
      (net 598 "/SoM/CAM0_MCLK") (pinfunction "CAM0_MCLK") (pintype "output+no_connect"))
    (pad "1_92" smd rect locked (at -0.739 -17.526 180) (size 0.33 1.6) (layers "F.Cu" "F.Paste" "F.Mask")
      (net 597 "/SoM/HDMI1_INTO") (pinfunction "SDC4_CMD") (pintype "output+no_connect"))
    (pad "1_93" smd rect locked (at -1.24 -11.426 180) (size 0.33 1.6) (layers "F.Cu" "F.Paste" "F.Mask")
      (net 1 "GND") (pinfunction "GND") (pintype "passive"))
    (pad "1_94" smd rect locked (at -1.24 -17.526 180) (size 0.33 1.6) (layers "F.Cu" "F.Paste" "F.Mask")
      (net 1 "GND") (pinfunction "GND") (pintype "passive"))
    (pad "1_95" smd rect locked (at -1.74 -11.426 180) (size 0.33 1.6) (layers "F.Cu" "F.Paste" "F.Mask")
      (net 596 "/SoM/CAM1_MCLK") (pinfunction "CAM1_MCLK") (pintype "output+no_connect"))
    (pad "1_96" smd rect locked (at -1.74 -17.526 180) (size 0.33 1.6) (layers "F.Cu" "F.Paste" "F.Mask")
      (net 595 "/SoM/CAM1_RST") (pinfunction "CAM1_RST") (pintype "output+no_connect"))
    (pad "1_97" smd rect locked (at -2.239 -11.426 180) (size 0.33 1.6) (layers "F.Cu" "F.Paste" "F.Mask")
      (net 1 "GND") (pinfunction "GND") (pintype "passive"))
    (pad "1_98" smd rect locked (at -2.239 -17.526 180) (size 0.33 1.6) (layers "F.Cu" "F.Paste" "F.Mask")
      (net 594 "/SoM/CAM1_AVDD_EN") (pinfunction "CAM1_AVDD_EN") (pintype "output+no_connect"))
    (pad "1_99" smd rect locked (at -2.741 -11.426 180) (size 0.33 1.6) (layers "F.Cu" "F.Paste" "F.Mask")
      (net 593 "unconnected-(U11-Pad1_99)") (pinfunction "CAM2_MCLK") (pintype "output+no_connect"))
    (pad "1_100" smd rect locked (at -2.741 -17.526 180) (size 0.33 1.6) (layers "F.Cu" "F.Paste" "F.Mask")
      (net 15 "CAM0_RST") (pinfunction "CAM0_RST") (pintype "output"))
    (pad "1_101" smd rect locked (at -3.241 -11.426 180) (size 0.33 1.6) (layers "F.Cu" "F.Paste" "F.Mask")
      (net 1 "GND") (pinfunction "GND") (pintype "power_in"))
    (pad "1_102" smd rect locked (at -3.241 -17.526 180) (size 0.33 1.6) (layers "F.Cu" "F.Paste" "F.Mask")
      (net 592 "/SoM/CAM0_AVDD_EN") (pinfunction "CAM0_AVDD_EN") (pintype "output+no_connect"))
    (pad "1_103" smd rect locked (at -3.741 -11.426 180) (size 0.33 1.6) (layers "F.Cu" "F.Paste" "F.Mask")
      (net 591 "/SoM/CAM3_MCLK") (pinfunction "CAM3_MCLK") (pintype "output+no_connect"))
    (pad "1_104" smd rect locked (at -3.741 -17.526 180) (size 0.33 1.6) (layers "F.Cu" "F.Paste" "F.Mask")
      (net 590 "unconnected-(U11-Pad1_104)") (pinfunction "CAM2_AVDD_EN") (pintype "output+no_connect"))
    (pad "1_105" smd rect locked (at -4.241 -11.426 180) (size 0.33 1.6) (layers "F.Cu" "F.Paste" "F.Mask")
      (net 1 "GND") (pinfunction "GND") (pintype "passive"))
    (pad "1_106" smd rect locked (at -4.241 -17.526 180) (size 0.33 1.6) (layers "F.Cu" "F.Paste" "F.Mask")
      (net 589 "/SoM/LT6911_3V3_EN") (pinfunction "CAM2_PWDN") (pintype "output+no_connect"))
    (pad "1_107" smd rect locked (at -4.741 -11.426 180) (size 0.33 1.6) (layers "F.Cu" "F.Paste" "F.Mask")
      (net 163 "PCIE1_RST_N") (pinfunction "PCIE1_RST_N") (pintype "output"))
    (pad "1_108" smd rect locked (at -4.741 -17.526 180) (size 0.33 1.6) (layers "F.Cu" "F.Paste" "F.Mask")
      (net 588 "/SoM/CAM3_VCC_EN") (pinfunction "CAM3_AVDD_EN") (pintype "output+no_connect"))
    (pad "1_109" smd rect locked (at -5.241 -11.426 180) (size 0.33 1.6) (layers "F.Cu" "F.Paste" "F.Mask")
      (net 162 "PCIE1_CLKREQ_N") (pinfunction "PCIE1_CLKREQ_N") (pintype "input"))
    (pad "1_110" smd rect locked (at -5.241 -17.526 180) (size 0.33 1.6) (layers "F.Cu" "F.Paste" "F.Mask")
      (net 587 "/SoM/RESET_USBHUB") (pinfunction "CAM2_DVDD_EN") (pintype "output+no_connect"))
    (pad "1_111" smd rect locked (at -5.741 -11.426 180) (size 0.33 1.6) (layers "F.Cu" "F.Paste" "F.Mask")
      (net 161 "PCIE1_WAKE_N") (pinfunction "PCIE1_WAKE_N") (pintype "input"))
    (pad "1_112" smd rect locked (at -5.741 -17.526 180) (size 0.33 1.6) (layers "F.Cu" "F.Paste" "F.Mask")
      (net 586 "unconnected-(U11-Pad1_112)") (pinfunction "CAM3_PWDN") (pintype "output+no_connect"))
    (pad "1_113" smd rect locked (at -6.241 -11.426 180) (size 0.33 1.6) (layers "F.Cu" "F.Paste" "F.Mask")
      (net 1 "GND") (pinfunction "GND") (pintype "passive"))
    (pad "1_114" smd rect locked (at -6.241 -17.526 180) (size 0.33 1.6) (layers "F.Cu" "F.Paste" "F.Mask")
      (net 14 "CAM0_PWDN") (pinfunction "CAM0_PWDN") (pintype "output"))
    (pad "1_115" smd rect locked (at -6.741 -11.426 180) (size 0.33 1.6) (layers "F.Cu" "F.Paste" "F.Mask")
      (net 8 "PCIE1_RX_P") (pinfunction "PCIE1_RX_P") (pintype "input"))
    (pad "1_116" smd rect locked (at -6.741 -17.526 180) (size 0.33 1.6) (layers "F.Cu" "F.Paste" "F.Mask")
      (net 585 "unconnected-(U11-Pad1_116)") (pinfunction "CAM1_STROBE") (pintype "output+no_connect"))
    (pad "1_117" smd rect locked (at -7.241 -11.426 180) (size 0.33 1.6) (layers "F.Cu" "F.Paste" "F.Mask")
      (net 9 "PCIE1_RX_N") (pinfunction "PCIE1_RX_M") (pintype "input"))
    (pad "1_118" smd rect locked (at -7.241 -17.526 180) (size 0.33 1.6) (layers "F.Cu" "F.Paste" "F.Mask")
      (net 100 "USB2_FAULT") (pinfunction "CAM2_STROBE") (pintype "input"))
    (pad "1_119" smd rect locked (at -7.741 -11.426 180) (size 0.33 1.6) (layers "F.Cu" "F.Paste" "F.Mask")
      (net 1 "GND") (pinfunction "GND") (pintype "passive"))
    (pad "1_120" smd rect locked (at -7.741 -17.526 180) (size 0.33 1.6) (layers "F.Cu" "F.Paste" "F.Mask")
      (net 16 "CAM1_PWDN") (pinfunction "CAM1_PWDN") (pintype "output"))
    (pad "1_121" smd rect locked (at -8.241 -11.426 180) (size 0.33 1.6) (layers "F.Cu" "F.Paste" "F.Mask")
      (net 47 "PCIE1_REFCLK_P") (pinfunction "PCIE1_REFCLK_P") (pintype "output"))
    (pad "1_122" smd rect locked (at -8.241 -17.526 180) (size 0.33 1.6) (layers "F.Cu" "F.Paste" "F.Mask")
      (net 584 "unconnected-(U11-Pad1_122)") (pinfunction "CAM0_STROBE") (pintype "output+no_connect"))
    (pad "1_123" smd rect locked (at -8.741 -11.426 180) (size 0.33 1.6) (layers "F.Cu" "F.Paste" "F.Mask")
      (net 46 "PCIE1_REFCLK_N") (pinfunction "PCIE1_REFCLK_M") (pintype "output"))
    (pad "1_124" smd rect locked (at -8.741 -17.526 180) (size 0.33 1.6) (layers "F.Cu" "F.Paste" "F.Mask")
      (net 583 "/SoM/PWR_OFF") (pinfunction "CAM2_RST") (pintype "output+no_connect"))
    (pad "1_125" smd rect locked (at -9.241 -11.426 180) (size 0.33 1.6) (layers "F.Cu" "F.Paste" "F.Mask")
      (net 1 "GND") (pinfunction "GND") (pintype "passive"))
    (pad "1_126" smd rect locked (at -9.241 -17.526 180) (size 0.33 1.6) (layers "F.Cu" "F.Paste" "F.Mask")
      (net 582 "/SoM/CAM3_RST") (pinfunction "CAM3_RST") (pintype "output+no_connect"))
    (pad "1_127" smd rect locked (at -9.741 -11.426 180) (size 0.33 1.6) (layers "F.Cu" "F.Paste" "F.Mask")
      (net 48 "PCIE1_TX_N") (pinfunction "PCIE1_TX_M") (pintype "output"))
    (pad "1_128" smd rect locked (at -9.741 -17.526 180) (size 0.33 1.6) (layers "F.Cu" "F.Paste" "F.Mask")
      (net 581 "/SoM/CAM3_TRIGGER_OUT") (pinfunction "CAM3_DVDD_EN") (pintype "output+no_connect"))
    (pad "1_129" smd rect locked (at -10.24 -11.426 180) (size 0.33 1.6) (layers "F.Cu" "F.Paste" "F.Mask")
      (net 49 "PCIE1_TX_P") (pinfunction "PCIE1_TX_P") (pintype "output"))
    (pad "1_130" smd rect locked (at -10.24 -17.526 180) (size 0.33 1.6) (layers "F.Cu" "F.Paste" "F.Mask")
      (net 580 "/SoM/CAM1_DVDD_EN") (pinfunction "CAM1_DVDD_EN") (pintype "output+no_connect"))
    (pad "1_131" smd rect locked (at -10.74 -11.426 180) (size 0.33 1.6) (layers "F.Cu" "F.Paste" "F.Mask")
      (net 1 "GND") (pinfunction "GND") (pintype "passive"))
    (pad "1_132" smd rect locked (at -10.74 -17.526 180) (size 0.33 1.6) (layers "F.Cu" "F.Paste" "F.Mask")
      (net 579 "/SoM/CAM0_DVDD_EN") (pinfunction "CAM0_DVDD_EN") (pintype "output+no_connect"))
    (pad "1_133" smd rect locked (at -11.24 -11.426 180) (size 0.33 1.6) (layers "F.Cu" "F.Paste" "F.Mask")
      (net 578 "/SoM/MAG_INT") (pinfunction "MAG_INT") (pintype "input+no_connect"))
    (pad "1_134" smd rect locked (at -11.24 -17.526 180) (size 0.33 1.6) (layers "F.Cu" "F.Paste" "F.Mask")
      (net 419 "/SoM/AUTO_ON_N") (pinfunction "CBL_PWR_N") (pintype "input"))
    (pad "1_135" smd rect locked (at -11.74 -11.426 180) (size 0.33 1.6) (layers "F.Cu" "F.Paste" "F.Mask")
      (net 577 "/SoM/MAG_DRDY_INT") (pinfunction "MAG_DRDY_INT") (pintype "input+no_connect"))
    (pad "1_136" smd rect locked (at -11.74 -17.526 180) (size 0.33 1.6) (layers "F.Cu" "F.Paste" "F.Mask")
      (net 576 "unconnected-(U11-Pad1_136)") (pinfunction "SSC_SPI1_CS0") (pintype "output+no_connect"))
    (pad "1_137" smd rect locked (at -12.24 -11.426 180) (size 0.33 1.6) (layers "F.Cu" "F.Paste" "F.Mask")
      (net 575 "/SoM/GYRO_INT") (pinfunction "GYRO_INT") (pintype "input+no_connect"))
    (pad "1_138" smd rect locked (at -12.24 -17.526 180) (size 0.33 1.6) (layers "F.Cu" "F.Paste" "F.Mask")
      (net 574 "unconnected-(U11-Pad1_138)") (pinfunction "SSC_SPI1_CS1") (pintype "output+no_connect"))
    (pad "1_139" smd rect locked (at -12.74 -11.426 180) (size 0.33 1.6) (layers "F.Cu" "F.Paste" "F.Mask")
      (net 573 "/SoM/ACCL_INT") (pinfunction "ACCEL_INT") (pintype "input+no_connect"))
    (pad "1_140" smd rect locked (at -12.74 -17.526 180) (size 0.33 1.6) (layers "F.Cu" "F.Paste" "F.Mask")
      (net 572 "unconnected-(U11-Pad1_140)") (pinfunction "SSC_SPI1_CS2") (pintype "output+no_connect"))
    (pad "1_141" smd rect locked (at -13.24 -11.426 180) (size 0.33 1.6) (layers "F.Cu" "F.Paste" "F.Mask")
      (net 571 "unconnected-(U11-Pad1_141)") (pinfunction "SSC_SPI2_CS") (pintype "output+no_connect"))
    (pad "1_142" smd rect locked (at -13.24 -17.526 180) (size 0.33 1.6) (layers "F.Cu" "F.Paste" "F.Mask")
      (net 42 "CCI0_I2C_SCL") (pinfunction "CCI0_I2C_SCL") (pintype "output"))
    (pad "1_143" smd rect locked (at -13.74 -11.426 180) (size 0.33 1.6) (layers "F.Cu" "F.Paste" "F.Mask")
      (net 570 "unconnected-(U11-Pad1_143)") (pinfunction "SSC_SPI2_MOSI") (pintype "output+no_connect"))
    (pad "1_144" smd rect locked (at -13.74 -17.526 180) (size 0.33 1.6) (layers "F.Cu" "F.Paste" "F.Mask")
      (net 43 "CCI0_I2C_SDA") (pinfunction "CCI0_I2C_SDA") (pintype "bidirectional"))
    (pad "1_145" smd rect locked (at -14.24 -11.426 180) (size 0.33 1.6) (layers "F.Cu" "F.Paste" "F.Mask")
      (net 569 "unconnected-(U11-Pad1_145)") (pinfunction "SSC_SPI2_CLK") (pintype "output+no_connect"))
    (pad "1_146" smd rect locked (at -14.24 -17.526 180) (size 0.33 1.6) (layers "F.Cu" "F.Paste" "F.Mask")
      (net 45 "CCI1_I2C_SDA") (pinfunction "CCI1_I2C_SDA") (pintype "bidirectional"))
    (pad "1_147" smd rect locked (at -14.74 -11.426 180) (size 0.33 1.6) (layers "F.Cu" "F.Paste" "F.Mask")
      (net 568 "unconnected-(U11-Pad1_147)") (pinfunction "SSC_SPI2_MISO") (pintype "input+no_connect"))
    (pad "1_148" smd rect locked (at -14.74 -17.526 180) (size 0.33 1.6) (layers "F.Cu" "F.Paste" "F.Mask")
      (net 44 "CCI1_I2C_SCL") (pinfunction "CCI1_I2C_SCL") (pintype "output"))
    (pad "1_149" smd rect locked (at -15.24 -11.426 180) (size 0.33 1.6) (layers "F.Cu" "F.Paste" "F.Mask")
      (net 139 "LVS1A_1V8") (pinfunction "LVS1A_1V8") (pintype "power_in"))
    (pad "1_150" smd rect locked (at -15.24 -17.526 180) (size 0.33 1.6) (layers "F.Cu" "F.Paste" "F.Mask")
      (net 567 "unconnected-(U11-Pad1_150)") (pinfunction "SSC_SPI1_MISO") (pintype "input+no_connect"))
    (pad "1_151" smd rect locked (at -15.74 -11.426 180) (size 0.33 1.6) (layers "F.Cu" "F.Paste" "F.Mask")
      (net 106 "SD_LDO21A") (pinfunction "SD_LDO21A") (pintype "power_in"))
    (pad "1_152" smd rect locked (at -15.74 -17.526 180) (size 0.33 1.6) (layers "F.Cu" "F.Paste" "F.Mask")
      (net 566 "unconnected-(U11-Pad1_152)") (pinfunction "SSC_SPI1_MOSI") (pintype "output+no_connect"))
    (pad "1_153" smd rect locked (at -16.24 -11.426 180) (size 0.33 1.6) (layers "F.Cu" "F.Paste" "F.Mask")
      (net 106 "SD_LDO21A") (pinfunction "SD_LDO21A") (pintype "passive"))
    (pad "1_154" smd rect locked (at -16.24 -17.526 180) (size 0.33 1.6) (layers "F.Cu" "F.Paste" "F.Mask")
      (net 565 "unconnected-(U11-Pad1_154)") (pinfunction "SSC_SPI1_CLK") (pintype "output+no_connect"))
    (pad "1_155" smd rect locked (at -16.74 -11.426 180) (size 0.33 1.6) (layers "F.Cu" "F.Paste" "F.Mask")
      (net 106 "SD_LDO21A") (pinfunction "SD_LDO21A") (pintype "passive"))
    (pad "1_156" smd rect locked (at -16.74 -17.526 180) (size 0.33 1.6) (layers "F.Cu" "F.Paste" "F.Mask")
      (net 1 "GND") (pinfunction "GND") (pintype "passive"))
    (pad "1_157" smd rect locked (at -17.24 -11.426 180) (size 0.33 1.6) (layers "F.Cu" "F.Paste" "F.Mask")
      (net 1 "GND") (pinfunction "GND") (pintype "passive"))
    (pad "1_158" smd rect locked (at -17.24 -17.526 180) (size 0.33 1.6) (layers "F.Cu" "F.Paste" "F.Mask")
      (net 1 "GND") (pinfunction "GND") (pintype "passive"))
    (pad "1_159" smd rect locked (at -17.74 -11.426 180) (size 0.33 1.6) (layers "F.Cu" "F.Paste" "F.Mask")
      (net 424 "/SoM/VBAT_SOM") (pinfunction "VBAT") (pintype "power_in"))
    (pad "1_160" smd rect locked (at -17.74 -17.526 180) (size 0.33 1.6) (layers "F.Cu" "F.Paste" "F.Mask")
      (net 424 "/SoM/VBAT_SOM") (pinfunction "VBAT") (pintype "passive"))
    (pad "1_161" smd rect locked (at -18.24 -11.426 180) (size 0.33 1.6) (layers "F.Cu" "F.Paste" "F.Mask")
      (net 424 "/SoM/VBAT_SOM") (pinfunction "VBAT") (pintype "passive"))
    (pad "1_162" smd rect locked (at -18.24 -17.526 180) (size 0.33 1.6) (layers "F.Cu" "F.Paste" "F.Mask")
      (net 424 "/SoM/VBAT_SOM") (pinfunction "VBAT") (pintype "passive"))
    (pad "1_163" smd rect locked (at -18.74 -11.426 180) (size 0.33 1.6) (layers "F.Cu" "F.Paste" "F.Mask")
      (net 424 "/SoM/VBAT_SOM") (pinfunction "VBAT") (pintype "passive"))
    (pad "1_164" smd rect locked (at -18.74 -17.526 180) (size 0.33 1.6) (layers "F.Cu" "F.Paste" "F.Mask")
      (net 424 "/SoM/VBAT_SOM") (pinfunction "VBAT") (pintype "passive"))
    (pad "1_165" smd rect locked (at -19.24 -11.426 180) (size 0.33 1.6) (layers "F.Cu" "F.Paste" "F.Mask")
      (net 424 "/SoM/VBAT_SOM") (pinfunction "VBAT") (pintype "passive"))
    (pad "1_166" smd rect locked (at -19.24 -17.526 180) (size 0.33 1.6) (layers "F.Cu" "F.Paste" "F.Mask")
      (net 424 "/SoM/VBAT_SOM") (pinfunction "VBAT") (pintype "passive"))
    (pad "1_167" smd rect locked (at -19.74 -11.426 180) (size 0.33 1.6) (layers "F.Cu" "F.Paste" "F.Mask")
      (net 424 "/SoM/VBAT_SOM") (pinfunction "VBAT") (pintype "passive"))
    (pad "1_168" smd rect locked (at -19.74 -17.526 180) (size 0.33 1.6) (layers "F.Cu" "F.Paste" "F.Mask")
      (net 424 "/SoM/VBAT_SOM") (pinfunction "VBAT") (pintype "passive"))
    (pad "1_171" smd rect locked (at 24.961 -14.477 270) (size 3.2 1.6) (layers "F.Cu" "F.Paste" "F.Mask")
      (net 564 "unconnected-(U11-Pad1_171)") (pinfunction "NC") (pintype "no_connect"))
    (pad "1_172" smd rect locked (at -22.939 -14.477 270) (size 3.2 1.6) (layers "F.Cu" "F.Paste" "F.Mask")
      (net 563 "unconnected-(U11-Pad1_172)") (pinfunction "NC") (pintype "no_connect"))
    (pad "2_1" smd rect locked (at 19.76 17.573 180) (size 0.33 1.6) (layers "F.Cu" "F.Paste" "F.Mask")
      (net 93 "SBU_SW_OE") (pinfunction "SBU_SW_OE") (pintype "output"))
    (pad "2_2" smd rect locked (at 19.76 11.473 180) (size 0.33 1.6) (layers "F.Cu" "F.Paste" "F.Mask")
      (net 350 "/SoM/USER_LED") (pinfunction "GPIO_25") (pintype "bidirectional"))
    (pad "2_3" smd rect locked (at 19.26 17.573 180) (size 0.33 1.6) (layers "F.Cu" "F.Paste" "F.Mask")
      (net 98 "SBU_SW_SEL") (pinfunction "SBU_SW_SEL") (pintype "output"))
    (pad "2_4" smd rect locked (at 19.26 11.473 180) (size 0.33 1.6) (layers "F.Cu" "F.Paste" "F.Mask")
      (net 40 "I2C4_SDA") (pinfunction "I2C4_SDA") (pintype "bidirectional"))
    (pad "2_5" smd rect locked (at 18.76 17.573 180) (size 0.33 1.6) (layers "F.Cu" "F.Paste" "F.Mask")
      (net 95 "PWRKEY") (pinfunction "PWRKEY") (pintype "input"))
    (pad "2_6" smd rect locked (at 18.76 11.473 180) (size 0.33 1.6) (layers "F.Cu" "F.Paste" "F.Mask")
      (net 41 "I2C4_SCL") (pinfunction "I2C4_SCL") (pintype "output"))
    (pad "2_7" smd rect locked (at 18.26 17.573 180) (size 0.33 1.6) (layers "F.Cu" "F.Paste" "F.Mask")
      (net 97 "VOL_DOWN") (pinfunction "VOL_DOWN") (pintype "input"))
    (pad "2_8" smd rect locked (at 18.26 11.473 180) (size 0.33 1.6) (layers "F.Cu" "F.Paste" "F.Mask")
      (net 562 "/SoM/SSC_I2C1_SDA") (pinfunction "SSC_I2C1_SDA") (pintype "bidirectional+no_connect"))
    (pad "2_9" smd rect locked (at 17.76 17.573 180) (size 0.33 1.6) (layers "F.Cu" "F.Paste" "F.Mask")
      (net 96 "VOL_UP") (pinfunction "VOL_UP_") (pintype "input"))
    (pad "2_10" smd rect locked (at 17.76 11.473 180) (size 0.33 1.6) (layers "F.Cu" "F.Paste" "F.Mask")
      (net 561 "/SoM/SSC_I2C1_SCL") (pinfunction "SSC_I2C1_SCL") (pintype "output+no_connect"))
    (pad "2_11" smd rect locked (at 17.26 17.573 180) (size 0.33 1.6) (layers "F.Cu" "F.Paste" "F.Mask")
      (net 1 "GND") (pinfunction "GND") (pintype "passive"))
    (pad "2_12" smd rect locked (at 17.26 11.473 180) (size 0.33 1.6) (layers "F.Cu" "F.Paste" "F.Mask")
      (net 1 "GND") (pinfunction "GND") (pintype "passive"))
    (pad "2_13" smd rect locked (at 16.76 17.573 180) (size 0.33 1.6) (layers "F.Cu" "F.Paste" "F.Mask")
      (net 51 "DSI1_LN0_N") (pinfunction "DSI1_LN0_N") (pintype "output"))
    (pad "2_14" smd rect locked (at 16.76 11.473 180) (size 0.33 1.6) (layers "F.Cu" "F.Paste" "F.Mask")
      (net 90 "DSI0_LN3_N") (pinfunction "DSI0_LN3_N") (pintype "output"))
    (pad "2_15" smd rect locked (at 16.26 17.573 180) (size 0.33 1.6) (layers "F.Cu" "F.Paste" "F.Mask")
      (net 176 "DSI1_LN0_P") (pinfunction "DSI1_LN0_P") (pintype "output"))
    (pad "2_16" smd rect locked (at 16.26 11.473 180) (size 0.33 1.6) (layers "F.Cu" "F.Paste" "F.Mask")
      (net 89 "DSI0_LN3_P") (pinfunction "DSI0_LN3_P") (pintype "output"))
    (pad "2_17" smd rect locked (at 15.761 17.573 180) (size 0.33 1.6) (layers "F.Cu" "F.Paste" "F.Mask")
      (net 1 "GND") (pinfunction "GND") (pintype "passive"))
    (pad "2_18" smd rect locked (at 15.761 11.473 180) (size 0.33 1.6) (layers "F.Cu" "F.Paste" "F.Mask")
      (net 1 "GND") (pinfunction "GND") (pintype "passive"))
    (pad "2_19" smd rect locked (at 15.261 17.573 180) (size 0.33 1.6) (layers "F.Cu" "F.Paste" "F.Mask")
      (net 56 "DSI1_CLK_P") (pinfunction "DSI1_CLK_P") (pintype "output"))
    (pad "2_20" smd rect locked (at 15.261 11.473 180) (size 0.33 1.6) (layers "F.Cu" "F.Paste" "F.Mask")
      (net 91 "DSI0_LN2_N") (pinfunction "DSI0_LN2_N") (pintype "output"))
    (pad "2_21" smd rect locked (at 14.761 17.573 180) (size 0.33 1.6) (layers "F.Cu" "F.Paste" "F.Mask")
      (net 55 "DSI1_CLK_N") (pinfunction "DSI1_CLK_N") (pintype "output"))
    (pad "2_22" smd rect locked (at 14.761 11.473 180) (size 0.33 1.6) (layers "F.Cu" "F.Paste" "F.Mask")
      (net 92 "DSI0_LN2_P") (pinfunction "DSI0_LN2_P") (pintype "output"))
    (pad "2_23" smd rect locked (at 14.261 17.573 180) (size 0.33 1.6) (layers "F.Cu" "F.Paste" "F.Mask")
      (net 1 "GND") (pinfunction "GND") (pintype "passive"))
    (pad "2_24" smd rect locked (at 14.261 11.473 180) (size 0.33 1.6) (layers "F.Cu" "F.Paste" "F.Mask")
      (net 1 "GND") (pinfunction "GND") (pintype "passive"))
    (pad "2_25" smd rect locked (at 13.761 17.573 180) (size 0.33 1.6) (layers "F.Cu" "F.Paste" "F.Mask")
      (net 57 "DSI1_LN2_P") (pinfunction "DSI1_LN2_P") (pintype "output"))
    (pad "2_26" smd rect locked (at 13.761 11.473 180) (size 0.33 1.6) (layers "F.Cu" "F.Paste" "F.Mask")
      (net 86 "DSI0_CLK_N") (pinfunction "DSI0_CLK_N") (pintype "output"))
    (pad "2_27" smd rect locked (at 13.261 17.573 180) (size 0.33 1.6) (layers "F.Cu" "F.Paste" "F.Mask")
      (net 53 "DSI1_LN2_N") (pinfunction "DSI1_LN2_N") (pintype "output"))
    (pad "2_28" smd rect locked (at 13.261 11.473 180) (size 0.33 1.6) (layers "F.Cu" "F.Paste" "F.Mask")
      (net 85 "DSI0_CLK_P") (pinfunction "DSI0_CLK_P") (pintype "output"))
    (pad "2_29" smd rect locked (at 12.761 17.573 180) (size 0.33 1.6) (layers "F.Cu" "F.Paste" "F.Mask")
      (net 1 "GND") (pinfunction "GND") (pintype "passive"))
    (pad "2_30" smd rect locked (at 12.761 11.473 180) (size 0.33 1.6) (layers "F.Cu" "F.Paste" "F.Mask")
      (net 1 "GND") (pinfunction "GND") (pintype "passive"))
    (pad "2_31" smd rect locked (at 12.261 17.573 180) (size 0.33 1.6) (layers "F.Cu" "F.Paste" "F.Mask")
      (net 54 "DSI1_LN3_N") (pinfunction "DSI1_LN3_N") (pintype "output"))
    (pad "2_32" smd rect locked (at 12.261 11.473 180) (size 0.33 1.6) (layers "F.Cu" "F.Paste" "F.Mask")
      (net 83 "DSI0_LN1_N") (pinfunction "DSI0_LN1_N") (pintype "output"))
    (pad "2_33" smd rect locked (at 11.761 17.573 180) (size 0.33 1.6) (layers "F.Cu" "F.Paste" "F.Mask")
      (net 58 "DSI1_LN3_P") (pinfunction "DSI1_LN3_P") (pintype "output"))
    (pad "2_34" smd rect locked (at 11.761 11.473 180) (size 0.33 1.6) (layers "F.Cu" "F.Paste" "F.Mask")
      (net 84 "DSI0_LN1_P") (pinfunction "DSI0_LN1_P") (pintype "output"))
    (pad "2_35" smd rect locked (at 11.261 17.573 180) (size 0.33 1.6) (layers "F.Cu" "F.Paste" "F.Mask")
      (net 1 "GND") (pinfunction "GND") (pintype "passive"))
    (pad "2_36" smd rect locked (at 11.261 11.473 180) (size 0.33 1.6) (layers "F.Cu" "F.Paste" "F.Mask")
      (net 1 "GND") (pinfunction "GND") (pintype "passive"))
    (pad "2_37" smd rect locked (at 10.761 17.573 180) (size 0.33 1.6) (layers "F.Cu" "F.Paste" "F.Mask")
      (net 52 "DSI1_LN1_N") (pinfunction "DSI1_LN1_N") (pintype "output"))
    (pad "2_38" smd rect locked (at 10.761 11.473 180) (size 0.33 1.6) (layers "F.Cu" "F.Paste" "F.Mask")
      (net 87 "DSI0_LN0_N") (pinfunction "DSI0_LN0_N") (pintype "output"))
    (pad "2_39" smd rect locked (at 10.261 17.573 180) (size 0.33 1.6) (layers "F.Cu" "F.Paste" "F.Mask")
      (net 50 "DSI1_LN1_P") (pinfunction "DSI1_LN1_P") (pintype "output"))
    (pad "2_40" smd rect locked (at 10.261 11.473 180) (size 0.33 1.6) (layers "F.Cu" "F.Paste" "F.Mask")
      (net 88 "DSI0_LN0_P") (pinfunction "DSI0_LN0_P") (pintype "output"))
    (pad "2_41" smd rect locked (at 9.761 17.573 180) (size 0.33 1.6) (layers "F.Cu" "F.Paste" "F.Mask")
      (net 1 "GND") (pinfunction "GND") (pintype "passive"))
    (pad "2_42" smd rect locked (at 9.761 11.473 180) (size 0.33 1.6) (layers "F.Cu" "F.Paste" "F.Mask")
      (net 1 "GND") (pinfunction "GND") (pintype "passive"))
    (pad "2_43" smd rect locked (at 9.261 17.573 180) (size 0.33 1.6) (layers "F.Cu" "F.Paste" "F.Mask")
      (net 560 "/SoM/WCD_CLK") (pinfunction "WCD_CLK") (pintype "output+no_connect"))
    (pad "2_44" smd rect locked (at 9.261 11.473 180) (size 0.33 1.6) (layers "F.Cu" "F.Paste" "F.Mask")
      (net 81 "TP_I2C_SCL") (pinfunction "TP_I2C_SCL") (pintype "output"))
    (pad "2_45" smd rect locked (at 8.761 17.573 180) (size 0.33 1.6) (layers "F.Cu" "F.Paste" "F.Mask")
      (net 1 "GND") (pinfunction "GND") (pintype "passive"))
    (pad "2_46" smd rect locked (at 8.761 11.473 180) (size 0.33 1.6) (layers "F.Cu" "F.Paste" "F.Mask")
      (net 82 "TP_I2C_SDA") (pinfunction "TP_I2C_SDA") (pintype "bidirectional"))
    (pad "2_47" smd rect locked (at 8.261 17.573 180) (size 0.33 1.6) (layers "F.Cu" "F.Paste" "F.Mask")
      (net 559 "/SoM/SLIMBUS_DATA0") (pinfunction "SLIMBUS_DATA0") (pintype "bidirectional+no_connect"))
    (pad "2_48" smd rect locked (at 8.261 11.473 180) (size 0.33 1.6) (layers "F.Cu" "F.Paste" "F.Mask")
      (net 558 "/SoM/TP_INT") (pinfunction "TP_INT") (pintype "input+no_connect"))
    (pad "2_49" smd rect locked (at 7.76 17.573 180) (size 0.33 1.6) (layers "F.Cu" "F.Paste" "F.Mask")
      (net 557 "/SoM/SLIMBUS_DATA1") (pinfunction "SLIMBUS_DATA1") (pintype "bidirectional+no_connect"))
    (pad "2_50" smd rect locked (at 7.76 11.473 180) (size 0.33 1.6) (layers "F.Cu" "F.Paste" "F.Mask")
      (net 556 "/SoM/TP_RST") (pinfunction "TP_RST") (pintype "output+no_connect"))
    (pad "2_51" smd rect locked (at 7.26 17.573 180) (size 0.33 1.6) (layers "F.Cu" "F.Paste" "F.Mask")
      (net 555 "/SoM/SLIMBUS_CLK") (pinfunction "SLIMBUS_CLK") (pintype "output+no_connect"))
    (pad "2_52" smd rect locked (at 7.26 11.473 180) (size 0.33 1.6) (layers "F.Cu" "F.Paste" "F.Mask")
      (net 554 "unconnected-(U11-Pad2_52)") (pinfunction "SPI2_CLK") (pintype "output+no_connect"))
    (pad "2_53" smd rect locked (at 6.76 17.573 180) (size 0.33 1.6) (layers "F.Cu" "F.Paste" "F.Mask")
      (net 1 "GND") (pinfunction "GND") (pintype "passive"))
    (pad "2_54" smd rect locked (at 6.76 11.473 180) (size 0.33 1.6) (layers "F.Cu" "F.Paste" "F.Mask")
      (net 101 "USB2_EN") (pinfunction "SPI2_CS") (pintype "output"))
    (pad "2_55" smd rect locked (at 6.26 17.573 180) (size 0.33 1.6) (layers "F.Cu" "F.Paste" "F.Mask")
      (net 553 "/SoM/I2S2_WS") (pinfunction "I2S2_WS") (pintype "output+no_connect"))
    (pad "2_56" smd rect locked (at 6.26 11.473 180) (size 0.33 1.6) (layers "F.Cu" "F.Paste" "F.Mask")
      (net 552 "unconnected-(U11-Pad2_56)") (pinfunction "SPI2_MISO") (pintype "input+no_connect"))
    (pad "2_57" smd rect locked (at 5.761 17.573 180) (size 0.33 1.6) (layers "F.Cu" "F.Paste" "F.Mask")
      (net 551 "/SoM/I2S2_SCK") (pinfunction "I2S2_SCK") (pintype "output+no_connect"))
    (pad "2_58" smd rect locked (at 5.761 11.473 180) (size 0.33 1.6) (layers "F.Cu" "F.Paste" "F.Mask")
      (net 550 "unconnected-(U11-Pad2_58)") (pinfunction "SPI2_MOSI") (pintype "output+no_connect"))
    (pad "2_59" smd rect locked (at 5.261 17.573 180) (size 0.33 1.6) (layers "F.Cu" "F.Paste" "F.Mask")
      (net 549 "/SoM/I2S2_DATA0") (pinfunction "I2S2_DATA0") (pintype "bidirectional+no_connect"))
    (pad "2_60" smd rect locked (at 5.261 11.473 180) (size 0.33 1.6) (layers "F.Cu" "F.Paste" "F.Mask")
      (net 548 "unconnected-(U11-Pad2_60)") (pinfunction "LCD_TE") (pintype "input+no_connect"))
    (pad "2_61" smd rect locked (at 4.761 17.573 180) (size 0.33 1.6) (layers "F.Cu" "F.Paste" "F.Mask")
      (net 547 "/SoM/I2S2_DATA1") (pinfunction "I2S2_DATA1") (pintype "bidirectional+no_connect"))
    (pad "2_62" smd rect locked (at 4.761 11.473 180) (size 0.33 1.6) (layers "F.Cu" "F.Paste" "F.Mask")
      (net 546 "unconnected-(U11-Pad2_62)") (pinfunction "LCD_RST") (pintype "output+no_connect"))
    (pad "2_63" smd rect locked (at 4.261 17.573 180) (size 0.33 1.6) (layers "F.Cu" "F.Paste" "F.Mask")
      (net 545 "/SoM/I2S3_WS") (pinfunction "I2S3_WS") (pintype "output+no_connect"))
    (pad "2_64" smd rect locked (at 4.261 11.473 180) (size 0.33 1.6) (layers "F.Cu" "F.Paste" "F.Mask")
      (net 168 "STUSB4500_ALERT") (pinfunction "GPIO_42") (pintype "bidirectional"))
    (pad "2_65" smd rect locked (at 3.761 17.573 180) (size 0.33 1.6) (layers "F.Cu" "F.Paste" "F.Mask")
      (net 544 "unconnected-(U11-Pad2_65)") (pinfunction "I2S3_DATA1") (pintype "bidirectional+no_connect"))
    (pad "2_66" smd rect locked (at 3.761 11.473 180) (size 0.33 1.6) (layers "F.Cu" "F.Paste" "F.Mask")
      (net 165 "STUSB4500_AB_SIDE") (pinfunction "GPIO_44") (pintype "bidirectional"))
    (pad "2_67" smd rect locked (at 3.261 17.573 180) (size 0.33 1.6) (layers "F.Cu" "F.Paste" "F.Mask")
      (net 543 "unconnected-(U11-Pad2_67)") (pinfunction "I2S3_DATA2") (pintype "bidirectional+no_connect"))
    (pad "2_68" smd rect locked (at 3.261 11.473 180) (size 0.33 1.6) (layers "F.Cu" "F.Paste" "F.Mask")
      (net 35 "LT9611_GPIO5") (pinfunction "GPIO_52") (pintype "bidirectional"))
    (pad "2_69" smd rect locked (at 2.761 17.573 180) (size 0.33 1.6) (layers "F.Cu" "F.Paste" "F.Mask")
      (net 542 "/SoM/I2S3_DATA0") (pinfunction "I2S3_DATA0") (pintype "bidirectional+no_connect"))
    (pad "2_70" smd rect locked (at 2.761 11.473 180) (size 0.33 1.6) (layers "F.Cu" "F.Paste" "F.Mask")
      (net 36 "LT9611_RST") (pinfunction "GPIO_50") (pintype "bidirectional"))
    (pad "2_71" smd rect locked (at 2.261 17.573 180) (size 0.33 1.6) (layers "F.Cu" "F.Paste" "F.Mask")
      (net 541 "unconnected-(U11-Pad2_71)") (pinfunction "I2S3_DATA3") (pintype "bidirectional+no_connect"))
    (pad "2_72" smd rect locked (at 2.261 11.473 180) (size 0.33 1.6) (layers "F.Cu" "F.Paste" "F.Mask")
      (net 166 "STUSB4500_GPIO") (pinfunction "GPIO_134") (pintype "bidirectional"))
    (pad "2_73" smd rect locked (at 1.761 17.573 180) (size 0.33 1.6) (layers "F.Cu" "F.Paste" "F.Mask")
      (net 540 "/SoM/I2S3_SCK") (pinfunction "I2S3_SCK") (pintype "output+no_connect"))
    (pad "2_74" smd rect locked (at 1.761 11.473 180) (size 0.33 1.6) (layers "F.Cu" "F.Paste" "F.Mask")
      (net 167 "STUSB4500_ATTACH") (pinfunction "GPIO_122") (pintype "bidirectional"))
    (pad "2_75" smd rect locked (at 1.261 17.573 180) (size 0.33 1.6) (layers "F.Cu" "F.Paste" "F.Mask")
      (net 150 "I2C10_SCL") (pinfunction "I2C10_SCL") (pintype "output"))
    (pad "2_76" smd rect locked (at 1.261 11.473 180) (size 0.33 1.6) (layers "F.Cu" "F.Paste" "F.Mask")
      (net 351 "USB_PD_DISABLE") (pinfunction "GPIO_124") (pintype "bidirectional"))
    (pad "2_77" smd rect locked (at 0.76 17.573 180) (size 0.33 1.6) (layers "F.Cu" "F.Paste" "F.Mask")
      (net 151 "I2C10_SDA") (pinfunction "I2C10_SDA") (pintype "bidirectional"))
    (pad "2_78" smd rect locked (at 0.76 11.473 180) (size 0.33 1.6) (layers "F.Cu" "F.Paste" "F.Mask")
      (net 539 "unconnected-(U11-Pad2_78)") (pinfunction "GPIO_49") (pintype "bidirectional+no_connect"))
    (pad "2_79" smd rect locked (at 0.261 17.573 180) (size 0.33 1.6) (layers "F.Cu" "F.Paste" "F.Mask")
      (net 59 "I2S1_WS") (pinfunction "I2S1_WS") (pintype "output"))
    (pad "2_80" smd rect locked (at 0.261 11.473 180) (size 0.33 1.6) (layers "F.Cu" "F.Paste" "F.Mask")
      (net 99 "USB2_SINK") (pinfunction "SPI0_CS") (pintype "output"))
    (pad "2_81" smd rect locked (at -0.24 17.573 180) (size 0.33 1.6) (layers "F.Cu" "F.Paste" "F.Mask")
      (net 60 "I2S1_MCLK") (pinfunction "I2S1_MCLK") (pintype "output"))
    (pad "2_82" smd rect locked (at -0.24 11.473 180) (size 0.33 1.6) (layers "F.Cu" "F.Paste" "F.Mask")
      (net 538 "unconnected-(U11-Pad2_82)") (pinfunction "SPI0_MOSI") (pintype "output+no_connect"))
    (pad "2_83" smd rect locked (at -0.739 17.573 180) (size 0.33 1.6) (layers "F.Cu" "F.Paste" "F.Mask")
      (net 61 "I2S1_SCK") (pinfunction "I2S1_SCK") (pintype "output"))
    (pad "2_84" smd rect locked (at -0.739 11.473 180) (size 0.33 1.6) (layers "F.Cu" "F.Paste" "F.Mask")
      (net 537 "unconnected-(U11-Pad2_84)") (pinfunction "SPI0_MISO") (pintype "input+no_connect"))
    (pad "2_85" smd rect locked (at -1.24 17.573 180) (size 0.33 1.6) (layers "F.Cu" "F.Paste" "F.Mask")
      (net 536 "unconnected-(U11-Pad2_85)") (pinfunction "I2S1_DATA1") (pintype "bidirectional+no_connect"))
    (pad "2_86" smd rect locked (at -1.24 11.473 180) (size 0.33 1.6) (layers "F.Cu" "F.Paste" "F.Mask")
      (net 535 "unconnected-(U11-Pad2_86)") (pinfunction "SPI0_CLK") (pintype "output+no_connect"))
    (pad "2_87" smd rect locked (at -1.74 17.573 180) (size 0.33 1.6) (layers "F.Cu" "F.Paste" "F.Mask")
      (net 62 "I2S1_DATA0") (pinfunction "I2S1_DATA0") (pintype "bidirectional"))
    (pad "2_88" smd rect locked (at -1.74 11.473 180) (size 0.33 1.6) (layers "F.Cu" "F.Paste" "F.Mask")
      (net 534 "unconnected-(U11-Pad2_88)") (pinfunction "RESERVED2") (pintype "no_connect"))
    (pad "2_89" smd rect locked (at -2.239 17.573 180) (size 0.33 1.6) (layers "F.Cu" "F.Paste" "F.Mask")
      (net 533 "/SoM/CODEC_SPI_MISO") (pinfunction "CODEC_SPI_MISO") (pintype "input+no_connect"))
    (pad "2_90" smd rect locked (at -2.239 11.473 180) (size 0.33 1.6) (layers "F.Cu" "F.Paste" "F.Mask")
      (net 532 "unconnected-(U11-Pad2_90)") (pinfunction "CODEC_RST") (pintype "output+no_connect"))
    (pad "2_91" smd rect locked (at -2.741 17.573 180) (size 0.33 1.6) (layers "F.Cu" "F.Paste" "F.Mask")
      (net 531 "/SoM/CODEC_INT1") (pinfunction "CODEC_INT1") (pintype "input+no_connect"))
    (pad "2_92" smd rect locked (at -2.741 11.473 180) (size 0.33 1.6) (layers "F.Cu" "F.Paste" "F.Mask")
      (net 530 "unconnected-(U11-Pad2_92)") (pinfunction "CODEC_SPI_CLK") (pintype "output+no_connect"))
    (pad "2_93" smd rect locked (at -3.241 17.573 180) (size 0.33 1.6) (layers "F.Cu" "F.Paste" "F.Mask")
      (net 529 "/SoM/CODEC_INT2") (pinfunction "CODEC_INT2") (pintype "input+no_connect"))
    (pad "2_94" smd rect locked (at -3.241 11.473 180) (size 0.33 1.6) (layers "F.Cu" "F.Paste" "F.Mask")
      (net 528 "unconnected-(U11-Pad2_94)") (pinfunction "CODEC_SPI_MOSI") (pintype "output+no_connect"))
    (pad "2_95" smd rect locked (at -3.741 17.573 180) (size 0.33 1.6) (layers "F.Cu" "F.Paste" "F.Mask")
      (net 527 "/SoM/CAM3_TRIGGER_IN") (pinfunction "SPI11_MOSI") (pintype "output+no_connect"))
    (pad "2_96" smd rect locked (at -3.741 11.473 180) (size 0.33 1.6) (layers "F.Cu" "F.Paste" "F.Mask")
      (net 526 "unconnected-(U11-Pad2_96)") (pinfunction "CODEC_SPI_CS") (pintype "output+no_connect"))
    (pad "2_97" smd rect locked (at -4.241 17.573 180) (size 0.33 1.6) (layers "F.Cu" "F.Paste" "F.Mask")
      (net 525 "/SoM/ETH_3V3_EN") (pinfunction "SPI11_MISO") (pintype "input+no_connect"))
    (pad "2_98" smd rect locked (at -4.241 11.473 180) (size 0.33 1.6) (layers "F.Cu" "F.Paste" "F.Mask")
      (net 1 "GND") (pinfunction "GND") (pintype "passive"))
    (pad "2_99" smd rect locked (at -4.741 17.573 180) (size 0.33 1.6) (layers "F.Cu" "F.Paste" "F.Mask")
      (net 524 "unconnected-(U11-Pad2_99)") (pinfunction "SPI11_CLK") (pintype "output+no_connect"))
    (pad "2_100" smd rect locked (at -4.741 11.473 180) (size 0.33 1.6) (layers "F.Cu" "F.Paste" "F.Mask")
      (net 104 "USB2_SS_RX_N") (pinfunction "USB2_SS_RX_M") (pintype "input"))
    (pad "2_101" smd rect locked (at -5.241 17.573 180) (size 0.33 1.6) (layers "F.Cu" "F.Paste" "F.Mask")
      (net 523 "unconnected-(U11-Pad2_101)") (pinfunction "SPI11_CS") (pintype "output+no_connect"))
    (pad "2_102" smd rect locked (at -5.241 11.473 180) (size 0.33 1.6) (layers "F.Cu" "F.Paste" "F.Mask")
      (net 105 "USB2_SS_RX_P") (pinfunction "USB2_SS_RX_P") (pintype "input"))
    (pad "2_103" smd rect locked (at -5.741 17.573 180) (size 0.33 1.6) (layers "F.Cu" "F.Paste" "F.Mask")
      (net 1 "GND") (pinfunction "GND") (pintype "power_in"))
    (pad "2_104" smd rect locked (at -5.741 11.473 180) (size 0.33 1.6) (layers "F.Cu" "F.Paste" "F.Mask")
      (net 1 "GND") (pinfunction "GND") (pintype "passive"))
    (pad "2_105" smd rect locked (at -6.241 17.573 180) (size 0.33 1.6) (layers "F.Cu" "F.Paste" "F.Mask")
      (net 80 "USB2C_HS_D_P") (pinfunction "USB2_DP") (pintype "bidirectional"))
    (pad "2_106" smd rect locked (at -6.241 11.473 180) (size 0.33 1.6) (layers "F.Cu" "F.Paste" "F.Mask")
      (net 103 "USB2_SS_TX_P") (pinfunction "USB2_SS_TX_P") (pintype "output"))
    (pad "2_107" smd rect locked (at -6.741 17.573 180) (size 0.33 1.6) (layers "F.Cu" "F.Paste" "F.Mask")
      (net 79 "USB2C_HS_D_N") (pinfunction "USB2_DM") (pintype "bidirectional"))
    (pad "2_108" smd rect locked (at -6.741 11.473 180) (size 0.33 1.6) (layers "F.Cu" "F.Paste" "F.Mask")
      (net 102 "USB2_SS_TX_N") (pinfunction "USB2_SS_TX_M") (pintype "output"))
    (pad "2_109" smd rect locked (at -7.241 17.573 180) (size 0.33 1.6) (layers "F.Cu" "F.Paste" "F.Mask")
      (net 1 "GND") (pinfunction "GND") (pintype "passive"))
    (pad "2_110" smd rect locked (at -7.241 11.473 180) (size 0.33 1.6) (layers "F.Cu" "F.Paste" "F.Mask")
      (net 1 "GND") (pinfunction "GND") (pintype "passive"))
    (pad "2_111" smd rect locked (at -7.741 17.573 180) (size 0.33 1.6) (layers "F.Cu" "F.Paste" "F.Mask")
      (net 71 "USB1_SS_TX1_N") (pinfunction "USB1_SS2_TX_M") (pintype "output"))
    (pad "2_112" smd rect locked (at -7.741 11.473 180) (size 0.33 1.6) (layers "F.Cu" "F.Paste" "F.Mask")
      (net 68 "USB1_SS_RX1_P") (pinfunction "USB1_SS2_RX_P") (pintype "input"))
    (pad "2_113" smd rect locked (at -8.241 17.573 180) (size 0.33 1.6) (layers "F.Cu" "F.Paste" "F.Mask")
      (net 72 "USB1_SS_TX1_P") (pinfunction "USB1_SS2_TX_P") (pintype "output"))
    (pad "2_114" smd rect locked (at -8.241 11.473 180) (size 0.33 1.6) (layers "F.Cu" "F.Paste" "F.Mask")
      (net 67 "USB1_SS_RX1_N") (pinfunction "USB1_SS2_RX_M") (pintype "input"))
    (pad "2_115" smd rect locked (at -8.741 17.573 180) (size 0.33 1.6) (layers "F.Cu" "F.Paste" "F.Mask")
      (net 1 "GND") (pinfunction "GND") (pintype "passive"))
    (pad "2_116" smd rect locked (at -8.741 11.473 180) (size 0.33 1.6) (layers "F.Cu" "F.Paste" "F.Mask")
      (net 1 "GND") (pinfunction "GND") (pintype "passive"))
    (pad "2_117" smd rect locked (at -9.241 17.573 180) (size 0.33 1.6) (layers "F.Cu" "F.Paste" "F.Mask")
      (net 322 "USB1_D_N") (pinfunction "USB1_DM") (pintype "bidirectional"))
    (pad "2_118" smd rect locked (at -9.241 11.473 180) (size 0.33 1.6) (layers "F.Cu" "F.Paste" "F.Mask")
      (net 70 "USB1_SS_RX0_N") (pinfunction "USB1_SS1_RX_M") (pintype "input"))
    (pad "2_119" smd rect locked (at -9.741 17.573 180) (size 0.33 1.6) (layers "F.Cu" "F.Paste" "F.Mask")
      (net 321 "USB1_D_P") (pinfunction "USB1_DP") (pintype "bidirectional"))
    (pad "2_120" smd rect locked (at -9.741 11.473 180) (size 0.33 1.6) (layers "F.Cu" "F.Paste" "F.Mask")
      (net 69 "USB1_SS_RX0_P") (pinfunction "USB1_SS1_RX_P") (pintype "input"))
    (pad "2_121" smd rect locked (at -10.24 17.573 180) (size 0.33 1.6) (layers "F.Cu" "F.Paste" "F.Mask")
      (net 1 "GND") (pinfunction "GND") (pintype "passive"))
    (pad "2_122" smd rect locked (at -10.24 11.473 180) (size 0.33 1.6) (layers "F.Cu" "F.Paste" "F.Mask")
      (net 1 "GND") (pinfunction "GND") (pintype "passive"))
    (pad "2_123" smd rect locked (at -10.74 17.573 180) (size 0.33 1.6) (layers "F.Cu" "F.Paste" "F.Mask")
      (net 65 "USB1_SS_TX0_N") (pinfunction "USB1_SS1_TX_M") (pintype "output"))
    (pad "2_124" smd rect locked (at -10.74 11.473 180) (size 0.33 1.6) (layers "F.Cu" "F.Paste" "F.Mask")
      (net 132 "VREG_S4A_1V8") (pinfunction "VREG_S4A_1V8") (pintype "power_in"))
    (pad "2_125" smd rect locked (at -11.24 17.573 180) (size 0.33 1.6) (layers "F.Cu" "F.Paste" "F.Mask")
      (net 64 "USB1_SS_TX0_P") (pinfunction "USB1_SS1_TX_P") (pintype "output"))
    (pad "2_126" smd rect locked (at -11.24 11.473 180) (size 0.33 1.6) (layers "F.Cu" "F.Paste" "F.Mask")
      (net 132 "VREG_S4A_1V8") (pinfunction "VREG_S4A_1V8") (pintype "passive"))
    (pad "2_127" smd rect locked (at -11.74 17.573 180) (size 0.33 1.6) (layers "F.Cu" "F.Paste" "F.Mask")
      (net 1 "GND") (pinfunction "GND") (pintype "passive"))
    (pad "2_128" smd rect locked (at -11.74 11.473 180) (size 0.33 1.6) (layers "F.Cu" "F.Paste" "F.Mask")
      (net 132 "VREG_S4A_1V8") (pinfunction "VREG_S4A_1V8") (pintype "passive"))
    (pad "2_129" smd rect locked (at -12.24 17.573 180) (size 0.33 1.6) (layers "F.Cu" "F.Paste" "F.Mask")
      (net 11 "EDP_AUX_P") (pinfunction "EDP_AUX_P") (pintype "bidirectional"))
    (pad "2_130" smd rect locked (at -12.24 11.473 180) (size 0.33 1.6) (layers "F.Cu" "F.Paste" "F.Mask")
      (net 418 "/SoM/USB_BOOT") (pinfunction "USB_BOOT") (pintype "input"))
    (pad "2_131" smd rect locked (at -12.74 17.573 180) (size 0.33 1.6) (layers "F.Cu" "F.Paste" "F.Mask")
      (net 10 "EDP_AUX_N") (pinfunction "EDP_AUX_N") (pintype "bidirectional"))
    (pad "2_132" smd rect locked (at -12.74 11.473 180) (size 0.33 1.6) (layers "F.Cu" "F.Paste" "F.Mask")
      (net 320 "1V2_SYS_EN") (pinfunction "GPIO_128") (pintype "bidirectional"))
    (pad "2_133" smd rect locked (at -13.24 17.573 180) (size 0.33 1.6) (layers "F.Cu" "F.Paste" "F.Mask")
      (net 336 "/SoM/VRTC") (pinfunction "VRTC") (pintype "bidirectional"))
    (pad "2_134" smd rect locked (at -13.24 11.473 180) (size 0.33 1.6) (layers "F.Cu" "F.Paste" "F.Mask")
      (net 319 "3V3_SYS_EN") (pinfunction "GPIO_135") (pintype "bidirectional"))
    (pad "2_135" smd rect locked (at -13.74 17.573 180) (size 0.33 1.6) (layers "F.Cu" "F.Paste" "F.Mask")
      (net 129 "DBG_RXD") (pinfunction "DBG_RXD") (pintype "input"))
    (pad "2_136" smd rect locked (at -13.74 11.473 180) (size 0.33 1.6) (layers "F.Cu" "F.Paste" "F.Mask")
      (net 349 "/SoM/BOOT") (pinfunction "GPIO_129") (pintype "bidirectional"))
    (pad "2_137" smd rect locked (at -14.24 17.573 180) (size 0.33 1.6) (layers "F.Cu" "F.Paste" "F.Mask")
      (net 130 "DBG_TXD") (pinfunction "DBG_TXD") (pintype "output"))
    (pad "2_138" smd rect locked (at -14.24 11.473 180) (size 0.33 1.6) (layers "F.Cu" "F.Paste" "F.Mask")
      (net 522 "unconnected-(U11-Pad2_138)") (pinfunction "RESERVED1") (pintype "no_connect"))
    (pad "2_139" smd rect locked (at -14.74 17.573 180) (size 0.33 1.6) (layers "F.Cu" "F.Paste" "F.Mask")
      (net 327 "USB_CC2") (pinfunction "USB_CC2") (pintype "input"))
    (pad "2_140" smd rect locked (at -14.74 11.473 180) (size 0.33 1.6) (layers "F.Cu" "F.Paste" "F.Mask")
      (net 521 "unconnected-(U11-Pad2_140)") (pinfunction "VREG_BOB2") (pintype "power_in+no_connect"))
    (pad "2_141" smd rect locked (at -15.24 17.573 180) (size 0.33 1.6) (layers "F.Cu" "F.Paste" "F.Mask")
      (net 326 "USB_CC1") (pinfunction "USB_CC1") (pintype "input"))
    (pad "2_142" smd rect locked (at -15.24 11.473 180) (size 0.33 1.6) (layers "F.Cu" "F.Paste" "F.Mask")
      (net 520 "unconnected-(U11-Pad2_142)") (pinfunction "VREG_BOB1") (pintype "power_in+no_connect"))
    (pad "2_143" smd rect locked (at -15.74 17.573 180) (size 0.33 1.6) (layers "F.Cu" "F.Paste" "F.Mask")
      (net 398 "Net-(R70-Pad1)") (pinfunction "BAT_THERM") (pintype "input"))
    (pad "2_144" smd rect locked (at -15.74 11.473 180) (size 0.33 1.6) (layers "F.Cu" "F.Paste" "F.Mask")
      (net 519 "unconnected-(U11-Pad2_144)") (pinfunction "PWM_PMI_GPIO8") (pintype "output+no_connect"))
    (pad "2_145" smd rect locked (at -16.24 17.573 180) (size 0.33 1.6) (layers "F.Cu" "F.Paste" "F.Mask")
      (net 94 "HOME_KEY") (pinfunction "HOME_KEY") (pintype "input"))
    (pad "2_146" smd rect locked (at -16.24 11.473 180) (size 0.33 1.6) (layers "F.Cu" "F.Paste" "F.Mask")
      (net 518 "unconnected-(U11-Pad2_146)") (pinfunction "PWM_PMI_GPIO5") (pintype "output+no_connect"))
    (pad "2_147" smd rect locked (at -16.74 17.573 180) (size 0.33 1.6) (layers "F.Cu" "F.Paste" "F.Mask")
      (net 517 "unconnected-(U11-Pad2_147)") (pinfunction "PMU_GPIO10") (pintype "bidirectional+no_connect"))
    (pad "2_148" smd rect locked (at -16.74 11.473 180) (size 0.33 1.6) (layers "F.Cu" "F.Paste" "F.Mask")
      (net 516 "LVS2A_1V8") (pinfunction "LVS2A_1V8") (pintype "power_in"))
    (pad "2_149" smd rect locked (at -17.24 17.573 180) (size 0.33 1.6) (layers "F.Cu" "F.Paste" "F.Mask")
      (net 515 "unconnected-(U11-Pad2_149)") (pinfunction "PMU_GPIO13") (pintype "bidirectional+no_connect"))
    (pad "2_150" smd rect locked (at -17.24 11.473 180) (size 0.33 1.6) (layers "F.Cu" "F.Paste" "F.Mask")
      (net 514 "LDO19A_3V0") (pinfunction "LDO19A_3V0") (pintype "power_in"))
    (pad "2_151" smd rect locked (at -17.74 17.573 180) (size 0.33 1.6) (layers "F.Cu" "F.Paste" "F.Mask")
      (net 513 "unconnected-(U11-Pad2_151)") (pinfunction "ADC_PMU_GPIO21") (pintype "output+no_connect"))
    (pad "2_152" smd rect locked (at -17.74 11.473 180) (size 0.33 1.6) (layers "F.Cu" "F.Paste" "F.Mask")
      (net 512 "unconnected-(U11-Pad2_152)") (pinfunction "R_LED") (pintype "output+no_connect"))
    (pad "2_153" smd rect locked (at -18.24 17.573 180) (size 0.33 1.6) (layers "F.Cu" "F.Paste" "F.Mask")
      (net 511 "unconnected-(U11-Pad2_153)") (pinfunction "ADC_PMU_GPIO8") (pintype "output+no_connect"))
    (pad "2_154" smd rect locked (at -18.24 11.473 180) (size 0.33 1.6) (layers "F.Cu" "F.Paste" "F.Mask")
      (net 510 "unconnected-(U11-Pad2_154)") (pinfunction "B_LED") (pintype "output+no_connect"))
    (pad "2_155" smd rect locked (at -18.74 17.573 180) (size 0.33 1.6) (layers "F.Cu" "F.Paste" "F.Mask")
      (net 1 "GND") (pinfunction "GND") (pintype "passive"))
    (pad "2_156" smd rect locked (at -18.74 11.473 180) (size 0.33 1.6) (layers "F.Cu" "F.Paste" "F.Mask")
      (net 509 "unconnected-(U11-Pad2_156)") (pinfunction "G_LED") (pintype "output+no_connect"))
    (pad "2_157" smd rect locked (at -19.24 17.573 180) (size 0.33 1.6) (layers "F.Cu" "F.Paste" "F.Mask")
      (net 420 "Net-(R176-Pad1)") (pinfunction "CS_P") (pintype "input"))
    (pad "2_158" smd rect locked (at -19.24 11.473 180) (size 0.33 1.6) (layers "F.Cu" "F.Paste" "F.Mask")
      (net 1 "GND") (pinfunction "GND") (pintype "passive"))
    (pad "2_159" smd rect locked (at -19.74 17.573 180) (size 0.33 1.6) (layers "F.Cu" "F.Paste" "F.Mask")
      (net 421 "Net-(R177-Pad1)") (pinfunction "CS_M") (pintype "input"))
    (pad "2_160" smd rect locked (at -19.74 11.473 180) (size 0.33 1.6) (layers "F.Cu" "F.Paste" "F.Mask")
      (net 66 "USB_VBUS") (pinfunction "USB_VBUS") (pintype "power_in"))
    (pad "2_161" smd rect locked (at -20.24 17.573 180) (size 0.33 1.6) (layers "F.Cu" "F.Paste" "F.Mask")
      (net 1 "GND") (pinfunction "GND") (pintype "passive"))
    (pad "2_162" smd rect locked (at -20.24 11.473 180) (size 0.33 1.6) (layers "F.Cu" "F.Paste" "F.Mask")
      (net 66 "USB_VBUS") (pinfunction "USB_VBUS") (pintype "passive"))
    (pad "2_163" smd rect locked (at -20.74 17.573 180) (size 0.33 1.6) (layers "F.Cu" "F.Paste" "F.Mask")
      (net 422 "Net-(R178-Pad1)") (pinfunction "BAT_P") (pintype "input"))
    (pad "2_164" smd rect locked (at -20.74 11.473 180) (size 0.33 1.6) (layers "F.Cu" "F.Paste" "F.Mask")
      (net 66 "USB_VBUS") (pinfunction "USB_VBUS") (pintype "passive"))
    (pad "2_165" smd rect locked (at -21.24 17.573 180) (size 0.33 1.6) (layers "F.Cu" "F.Paste" "F.Mask")
      (net 423 "Net-(R179-Pad1)") (pinfunction "BAT_M") (pintype "input"))
    (pad "2_166" smd rect locked (at -21.24 11.473 180) (size 0.33 1.6) (layers "F.Cu" "F.Paste" "F.Mask")
      (net 66 "USB_VBUS") (pinfunction "USB_VBUS") (pintype "passive"))
    (pad "2_167" smd rect locked (at -21.74 17.573 180) (size 0.33 1.6) (layers "F.Cu" "F.Paste" "F.Mask")
      (net 1 "GND") (pinfunction "GND") (pintype "passive"))
    (pad "2_168" smd rect locked (at -21.74 11.473 180) (size 0.33 1.6) (layers "F.Cu" "F.Paste" "F.Mask")
      (net 66 "USB_VBUS") (pinfunction "USB_VBUS") (pintype "passive"))
    (pad "2_171" smd rect locked (at 22.961 14.524 270) (size 3.2 1.6) (layers "F.Cu" "F.Paste" "F.Mask")
      (net 508 "unconnected-(U11-Pad2_171)") (pinfunction "NC") (pintype "no_connect"))
    (pad "2_172" smd rect locked (at -24.939 14.524 270) (size 3.2 1.6) (layers "F.Cu" "F.Paste" "F.Mask")
      (net 507 "unconnected-(U11-Pad2_172)") (pinfunction "NC") (pintype "no_connect"))
  )

  (footprint "sa800u-baseboard-hw-footprints:LED_0603_1608Metric_G" (layer "F.Cu")
    (tedit 60C2DD7B)
    (at 73.7 129.79 90)
    (descr "LED SMD 0603 Green")
    (tags "LED SMD 0603 Green")
    (property "Author" "Antmicro")
    (property "License" "Apache-2.0")
    (property "MPN" "KP-1608ZGC")
    (property "Manufacturer" "Kingbright")
    (property "Sheetfile" "psu.kicad_sch")
    (property "Sheetname" "PSU")
    (attr smd)
    (fp_text reference "D27" (at -0.82 -0.7 90) (layer "F.SilkS")
      (effects (font (size 0.7 0.7) (thickness 0.15)) (justify left bottom))
    )
    (fp_text value "KP-1608EC" (at 0 1.6 90) (layer "F.Fab")
      (effects (font (size 0.7 0.7) (thickness 0.15)) (justify left bottom))
    )
    (fp_text user "License: Apache-2.0" (at -1.31 5.769 90) (layer "F.Fab") hide
      (effects (font (size 0.7 0.7) (thickness 0.15)) (justify left bottom))
    )
    (fp_text user "${REFERENCE}" (at -1.31 3.769 90) (layer "F.Fab") hide
      (effects (font (size 0.7 0.7) (thickness 0.15)) (justify left bottom))
    )
    (fp_text user "Author: Antmicro" (at -1.31 4.769 90) (layer "F.Fab") hide
      (effects (font (size 0.7 0.7) (thickness 0.15)) (justify left bottom))
    )
    (fp_line (start 1.25 0.32) (end 1.25 -0.32) (layer "F.SilkS") (width 0.15))
    (fp_line (start -0.106328 -0.200008) (end -0.106328 0.199992) (layer "F.SilkS") (width 0.1))
    (fp_line (start -0.106328 -0.000008) (end -0.29 0) (layer "F.SilkS") (width 0.1))
    (fp_line (start -0.27 -0.35) (end 0.27 -0.35) (layer "F.SilkS") (width 0.15))
    (fp_line (start 0.093672 -0.000008) (end -0.106328 0.199992) (layer "F.SilkS") (width 0.1))
    (fp_line (start 0.093672 -0.000008) (end 0.293672 -0.000008) (layer "F.SilkS") (width 0.1))
    (fp_line (start -0.106328 -0.200008) (end 0.093672 -0.000008) (layer "F.SilkS") (width 0.1))
    (fp_line (start 0.093672 -0.200008) (end 0.093672 0.199992) (layer "F.SilkS") (width 0.1))
    (fp_line (start -0.27 0.351) (end 0.27 0.351) (layer "F.SilkS") (width 0.15))
    (fp_rect (start 1.26 0.65) (end -1.26 -0.65) (layer "F.CrtYd") (width 0.05) (fill none))
    (fp_line (start 0.199 -0.2) (end 0.199 -0.1) (layer "F.Fab") (width 0.15))
    (fp_line (start 0.199 0) (end 0.597 0) (layer "F.Fab") (width 0.15))
    (fp_line (start 0.199 0.202) (end 0.199 -0.1) (layer "F.Fab") (width 0.15))
    (fp_line (start -0.201 0) (end -0.201 0.202) (layer "F.Fab") (width 0.15))
    (fp_line (start -0.201 -0.2) (end -0.201 0) (layer "F.Fab") (width 0.15))
    (fp_line (start 0.101 0) (end -0.201 -0.2) (layer "F.Fab") (width 0.15))
    (fp_line (start -0.599 0) (end -0.201 0) (layer "F.Fab") (width 0.15))
    (fp_line (start -0.201 0.202) (end 0.101 0) (layer "F.Fab") (width 0.15))
    (fp_rect (start -0.848 -0.4) (end 0.85 0.402) (layer "F.Fab") (width 0.15) (fill none))
    (pad "1" smd rect (at -0.75 0 270) (size 0.8 0.8) (layers "F.Cu" "F.Paste" "F.Mask")
      (net 378 "Net-(D27-Pad1)") (pinfunction "1") (pintype "passive"))
    (pad "2" smd rect (at 0.75 0 270) (size 0.8 0.8) (layers "F.Cu" "F.Paste" "F.Mask")
      (net 1 "GND") (pinfunction "2") (pintype "passive"))
  )

  (footprint "sa800u-baseboard-hw-footprints:R_0402_1005Metric" (layer "F.Cu")
    (tedit 5FD9C158)
    (at 74.95 130.2 90)
    (descr "Resistor SMD 0402")
    (tags "resistor SMD 0402")
    (property "Author" "Antmicro")
    (property "License" "Apache-2.0")
    (property "MPN" "CR0402-FX-1002GLF")
    (property "Manufacturer" "Bourns")
    (property "Sheetfile" "psu.kicad_sch")
    (property "Sheetname" "PSU")
    (property "Tolerance" "1%")
    (property "Val" "10k")
    (attr smd)
    (fp_text reference "R121" (at -0.97 1.38 90) (layer "F.SilkS")
      (effects (font (size 0.7 0.7) (thickness 0.15)) (justify left bottom))
    )
    (fp_text value "R_10k_0402" (at 0 1.4 90) (layer "F.Fab")
      (effects (font (size 0.7 0.7) (thickness 0.15)) (justify left bottom))
    )
    (fp_text user "License: Apache-2.0" (at -0.95 5.169 90) (layer "F.Fab") hide
      (effects (font (size 0.7 0.7) (thickness 0.15)) (justify left bottom))
    )
    (fp_text user "${REFERENCE}" (at -0.95 3.168 90) (layer "F.Fab") hide
      (effects (font (size 0.7 0.7) (thickness 0.15)) (justify left bottom))
    )
    (fp_text user "Author: Antmicro" (at -0.95 4.169 90) (layer "F.Fab") hide
      (effects (font (size 0.7 0.7) (thickness 0.15)) (justify left bottom))
    )
    (fp_rect (start -0.93 -0.47) (end 0.93 0.47) (layer "F.CrtYd") (width 0.05) (fill none))
    (fp_rect (start -0.5 -0.25) (end 0.5 0.25) (layer "F.Fab") (width 0.15) (fill none))
    (pad "1" smd roundrect (at -0.485 0 90) (size 0.59 0.64) (layers "F.Cu" "F.Paste" "F.Mask") (roundrect_rratio 0.25)
      (net 378 "Net-(D27-Pad1)") (pintype "passive"))
    (pad "2" smd roundrect (at 0.485 0 90) (size 0.59 0.64) (layers "F.Cu" "F.Paste" "F.Mask") (roundrect_rratio 0.25)
      (net 74 "VDD") (pintype "passive"))
  )

  (footprint "sa800u-baseboard-hw-footprints:LED_0603_1608Metric_G" (layer "F.Cu")
    (tedit 60C2DD7B)
    (at 147.45 94.4)
    (descr "LED SMD 0603 Green")
    (tags "LED SMD 0603 Green")
    (property "Author" "Antmicro")
    (property "License" "Apache-2.0")
    (property "MPN" "KP-1608ZGC")
    (property "Manufacturer" "Kingbright")
    (property "Sheetfile" "m2.kicad_sch")
    (property "Sheetname" "M2")
    (attr smd)
    (fp_text reference "D21" (at -1.18 1.28) (layer "F.SilkS")
      (effects (font (size 0.7 0.7) (thickness 0.15)) (justify left bottom))
    )
    (fp_text value "KP-1608EC" (at 0 1.6) (layer "F.Fab")
      (effects (font (size 0.7 0.7) (thickness 0.15)) (justify left bottom))
    )
    (fp_text user "License: Apache-2.0" (at -1.31 5.769) (layer "F.Fab") hide
      (effects (font (size 0.7 0.7) (thickness 0.15)) (justify left bottom))
    )
    (fp_text user "Author: Antmicro" (at -1.31 4.769) (layer "F.Fab") hide
      (effects (font (size 0.7 0.7) (thickness 0.15)) (justify left bottom))
    )
    (fp_text user "${REFERENCE}" (at -1.31 3.769) (layer "F.Fab") hide
      (effects (font (size 0.7 0.7) (thickness 0.15)) (justify left bottom))
    )
    (fp_line (start -0.27 -0.35) (end 0.27 -0.35) (layer "F.SilkS") (width 0.15))
    (fp_line (start -0.106328 -0.200008) (end 0.093672 -0.000008) (layer "F.SilkS") (width 0.1))
    (fp_line (start -0.106328 -0.000008) (end -0.29 0) (layer "F.SilkS") (width 0.1))
    (fp_line (start 0.093672 -0.000008) (end 0.293672 -0.000008) (layer "F.SilkS") (width 0.1))
    (fp_line (start 0.093672 -0.200008) (end 0.093672 0.199992) (layer "F.SilkS") (width 0.1))
    (fp_line (start 1.25 0.32) (end 1.25 -0.32) (layer "F.SilkS") (width 0.15))
    (fp_line (start -0.27 0.351) (end 0.27 0.351) (layer "F.SilkS") (width 0.15))
    (fp_line (start 0.093672 -0.000008) (end -0.106328 0.199992) (layer "F.SilkS") (width 0.1))
    (fp_line (start -0.106328 -0.200008) (end -0.106328 0.199992) (layer "F.SilkS") (width 0.1))
    (fp_rect (start 1.26 0.65) (end -1.26 -0.65) (layer "F.CrtYd") (width 0.05) (fill none))
    (fp_line (start 0.199 -0.2) (end 0.199 -0.1) (layer "F.Fab") (width 0.15))
    (fp_line (start 0.199 0.202) (end 0.199 -0.1) (layer "F.Fab") (width 0.15))
    (fp_line (start -0.201 -0.2) (end -0.201 0) (layer "F.Fab") (width 0.15))
    (fp_line (start -0.201 0.202) (end 0.101 0) (layer "F.Fab") (width 0.15))
    (fp_line (start -0.599 0) (end -0.201 0) (layer "F.Fab") (width 0.15))
    (fp_line (start 0.199 0) (end 0.597 0) (layer "F.Fab") (width 0.15))
    (fp_line (start 0.101 0) (end -0.201 -0.2) (layer "F.Fab") (width 0.15))
    (fp_line (start -0.201 0) (end -0.201 0.202) (layer "F.Fab") (width 0.15))
    (fp_rect (start -0.848 -0.4) (end 0.85 0.402) (layer "F.Fab") (width 0.15) (fill none))
    (pad "1" smd rect (at -0.75 0 180) (size 0.8 0.8) (layers "F.Cu" "F.Paste" "F.Mask")
      (net 373 "Net-(D21-Pad1)") (pinfunction "1") (pintype "passive"))
    (pad "2" smd rect (at 0.75 0 180) (size 0.8 0.8) (layers "F.Cu" "F.Paste" "F.Mask")
      (net 374 "Net-(D21-Pad2)") (pinfunction "2") (pintype "passive"))
  )

  (footprint "sa800u-baseboard-hw-footprints:R_0402_1005Metric" (layer "F.Cu")
    (tedit 5FD9C158)
    (at 96.5 120.68 -90)
    (descr "Resistor SMD 0402")
    (tags "resistor SMD 0402")
    (property "Author" "Antmicro")
    (property "License" "Apache-2.0")
    (property "MPN" "CR0402-FX-4702GLF")
    (property "Manufacturer" "Bourns")
    (property "Sheetfile" "som.kicad_sch")
    (property "Sheetname" "SoM")
    (property "Tolerance" "1%")
    (property "Val" "47k")
    (attr smd)
    (fp_text reference "R70" (at 3.03 -0.38 -90) (layer "F.SilkS")
      (effects (font (size 0.7 0.7) (thickness 0.15)) (justify left bottom))
    )
    (fp_text value "R_47k_0402" (at 0 1.4 -90) (layer "F.Fab")
      (effects (font (size 0.7 0.7) (thickness 0.15)) (justify left bottom))
    )
    (fp_text user "Author: Antmicro" (at -0.95 4.169 -90) (layer "F.Fab") hide
      (effects (font (size 0.7 0.7) (thickness 0.15)) (justify left bottom))
    )
    (fp_text user "${REFERENCE}" (at -0.95 3.168 -90) (layer "F.Fab") hide
      (effects (font (size 0.7 0.7) (thickness 0.15)) (justify left bottom))
    )
    (fp_text user "License: Apache-2.0" (at -0.95 5.169 -90) (layer "F.Fab") hide
      (effects (font (size 0.7 0.7) (thickness 0.15)) (justify left bottom))
    )
    (fp_rect (start -0.93 -0.47) (end 0.93 0.47) (layer "F.CrtYd") (width 0.05) (fill none))
    (fp_rect (start -0.5 -0.25) (end 0.5 0.25) (layer "F.Fab") (width 0.15) (fill none))
    (pad "1" smd roundrect (at -0.485 0 270) (size 0.59 0.64) (layers "F.Cu" "F.Paste" "F.Mask") (roundrect_rratio 0.25)
      (net 398 "Net-(R70-Pad1)") (pintype "passive"))
    (pad "2" smd roundrect (at 0.485 0 270) (size 0.59 0.64) (layers "F.Cu" "F.Paste" "F.Mask") (roundrect_rratio 0.25)
      (net 1 "GND") (pintype "passive"))
  )

  (footprint "sa800u-baseboard-hw-footprints:USB-C_12401610E4_2A" locked (layer "F.Cu")
    (tedit 6215EC4A)
    (at 87.75 147.95)
    (property "Author" "Antmicro")
    (property "License" "Apache-2.0")
    (property "MPN" "12401598E4#2A")
    (property "Manufacturer" "Amphenol")
    (property "Sheetfile" "usb-pd.kicad_sch")
    (property "Sheetname" "USB-PD")
    (attr smd)
    (fp_text reference "J11" (at 4.25 -5.55) (layer "F.SilkS")
      (effects (font (size 0.7 0.7) (thickness 0.15)) (justify left bottom))
    )
    (fp_text value "12401598E4_2A" (at 0 6.549) (layer "F.Fab")
      (effects (font (size 0.7 0.7) (thickness 0.15)) (justify left bottom))
    )
    (fp_text user "License: Apache-2.0" (at -4.901 10.948) (layer "F.Fab") hide
      (effects (font (size 0.7 0.7) (thickness 0.15)) (justify left bottom))
    )
    (fp_text user "${REFERENCE}" (at -4.901 8.55) (layer "F.Fab") hide
      (effects (font (size 0.7 0.7) (thickness 0.15)) (justify left bottom))
    )
    (fp_text user "Author: Antmicro" (at -4.901 9.749) (layer "F.Fab") hide
      (effects (font (size 0.7 0.7) (thickness 0.15)) (justify left bottom))
    )
    (fp_line (start -4.601 5.448) (end -4.1 5.448) (layer "F.SilkS") (width 0.15))
    (fp_line (start -4.601 -5.25) (end -4.601 -4.75) (layer "F.SilkS") (width 0.15))
    (fp_line (start 4.599 -5.25) (end 4.099 -5.25) (layer "F.SilkS") (width 0.15))
    (fp_line (start 4.599 5.448) (end 4.099 5.448) (layer "F.SilkS") (width 0.15))
    (fp_line (start -4.601 5.448) (end -4.601 4.948) (layer "F.SilkS") (width 0.15))
    (fp_line (start 4.599 -5.25) (end 4.599 -4.75) (layer "F.SilkS") (width 0.15))
    (fp_line (start -4.601 -5.25) (end -4.1 -5.25) (layer "F.SilkS") (width 0.15))
    (fp_line (start 4.599 5.448) (end 4.599 4.948) (layer "F.SilkS") (width 0.15))
    (fp_circle (center -3.101 -5.25) (end -3.052 -5.25) (layer "F.SilkS") (width 0.15) (fill solid))
    (fp_rect (start -4.92 -5.46) (end 4.9 5.44) (layer "F.CrtYd") (width 0.05) (fill none))
    (fp_line (start -4.491 -5.162) (end 4.49 -5.162) (layer "F.Fab") (width 0.15))
    (fp_line (start 4.49 -5.162) (end 4.49 5.339) (layer "F.Fab") (width 0.15))
    (fp_line (start -4.491 5.339) (end 4.49 5.339) (layer "F.Fab") (width 0.15))
    (fp_line (start -4.491 -5.162) (end -4.491 5.339) (layer "F.Fab") (width 0.15))
    (pad "" np_thru_hole circle locked (at -3.601 -4.25) (size 0.65 0.65) (drill 0.65) (layers *.Cu *.Mask))
    (pad "" np_thru_hole oval locked (at 3.6 -4.25) (size 0.95 0.65) (drill oval 0.95 0.65) (layers *.Cu *.Mask))
    (pad "A1" smd rect locked (at -2.75 -4.912) (size 0.3 0.7) (layers "F.Cu" "F.Paste" "F.Mask")
      (net 1 "GND") (pintype "passive"))
    (pad "A2" smd rect locked (at -2.25 -4.912) (size 0.3 0.7) (layers "F.Cu" "F.Paste" "F.Mask")
      (net 465 "unconnected-(J11-PadA2)") (pintype "passive+no_connect"))
    (pad "A3" smd rect locked (at -1.75 -4.912) (size 0.3 0.7) (layers "F.Cu" "F.Paste" "F.Mask")
      (net 464 "unconnected-(J11-PadA3)") (pintype "passive+no_connect"))
    (pad "A4" smd rect locked (at -1.25 -4.912) (size 0.3 0.7) (layers "F.Cu" "F.Paste" "F.Mask")
      (net 107 "/USB-PD/PD_VBUS") (pintype "passive"))
    (pad "A5" smd rect locked (at -0.75 -4.912) (size 0.3 0.7) (layers "F.Cu" "F.Paste" "F.Mask")
      (net 143 "/USB-PD/PD_CC1") (pintype "passive"))
    (pad "A6" smd rect locked (at -0.25 -4.912) (size 0.3 0.7) (layers "F.Cu" "F.Paste" "F.Mask")
      (net 463 "unconnected-(J11-PadA6)") (pintype "passive+no_connect"))
    (pad "A7" smd rect locked (at 0.247 -4.912) (size 0.3 0.7) (layers "F.Cu" "F.Paste" "F.Mask")
      (net 462 "unconnected-(J11-PadA7)") (pintype "passive+no_connect"))
    (pad "A8" smd rect locked (at 0.747 -4.912) (size 0.3 0.7) (layers "F.Cu" "F.Paste" "F.Mask")
      (net 461 "unconnected-(J11-PadA8)") (pintype "passive+no_connect"))
    (pad "A9" smd rect locked (at 1.249 -4.912) (size 0.3 0.7) (layers "F.Cu" "F.Paste" "F.Mask")
      (net 107 "/USB-PD/PD_VBUS") (pintype "passive"))
    (pad "A10" smd rect locked (at 1.749 -4.912) (size 0.3 0.7) (layers "F.Cu" "F.Paste" "F.Mask")
      (net 460 "unconnected-(J11-PadA10)") (pintype "passive+no_connect"))
    (pad "A11" smd rect locked (at 2.249 -4.912) (size 0.3 0.7) (layers "F.Cu" "F.Paste" "F.Mask")
      (net 459 "unconnected-(J11-PadA11)") (pintype "passive+no_connect"))
    (pad "A12" smd rect locked (at 2.749 -4.912) (size 0.3 0.7) (layers "F.Cu" "F.Paste" "F.Mask")
      (net 1 "GND") (pintype "passive"))
    (pad "B1" smd rect locked (at 2.499 -3.21) (size 0.3 0.7) (layers "F.Cu" "F.Paste" "F.Mask")
      (net 1 "GND") (pintype "passive"))
    (pad "B2" smd rect locked (at 1.999 -3.21) (size 0.3 0.7) (layers "F.Cu" "F.Paste" "F.Mask")
      (net 458 "unconnected-(J11-PadB2)") (pintype "passive+no_connect"))
    (pad "B3" smd rect locked (at 1.499 -3.21) (size 0.3 0.7) (layers "F.Cu" "F.Paste" "F.Mask")
      (net 457 "unconnected-(J11-PadB3)") (pintype "passive+no_connect"))
    (pad "B4" smd rect locked (at 0.997 -3.21) (size 0.3 0.7) (layers "F.Cu" "F.Paste" "F.Mask")
      (net 107 "/USB-PD/PD_VBUS") (pintype "passive"))
    (pad "B5" smd rect locked (at 0.497 -3.21) (size 0.3 0.7) (layers "F.Cu" "F.Paste" "F.Mask")
      (net 144 "/USB-PD/PD_CC2") (pintype "passive"))
    (pad "B6" smd rect locked (at 0 -3.21) (size 0.3 0.7) (layers "F.Cu" "F.Paste" "F.Mask")
      (net 456 "unconnected-(J11-PadB6)") (pintype "passive+no_connect"))
    (pad "B7" smd rect locked (at -0.5 -3.21) (size 0.3 0.7) (layers "F.Cu" "F.Paste" "F.Mask")
      (net 455 "unconnected-(J11-PadB7)") (pintype "passive+no_connect"))
    (pad "B8" smd rect locked (at -1 -3.21) (size 0.3 0.7) (layers "F.Cu" "F.Paste" "F.Mask")
      (net 454 "unconnected-(J11-PadB8)") (pintype "passive+no_connect"))
    (pad "B9" smd rect locked (at -1.5 -3.21) (size 0.3 0.7) (layers "F.Cu" "F.Paste" "F.Mask")
      (net 107 "/USB-PD/PD_VBUS") (pintype "passive"))
    (pad "B10" smd rect locked (at -2 -3.21) (size 0.3 0.7) (layers "F.Cu" "F.Paste" "F.Mask")
      (net 453 "unconnected-(J11-PadB10)") (pintype "passive+no_connect"))
    (pad "B11" smd rect locked (at -2.5 -3.21) (size 0.3 0.7) (layers "F.Cu" "F.Paste" "F.Mask")
      (net 452 "unconnected-(J11-PadB11)") (pintype "passive+no_connect"))
    (pad "B12" smd rect locked (at -3 -3.21) (size 0.3 0.7) (layers "F.Cu" "F.Paste" "F.Mask")
      (net 1 "GND") (pintype "passive"))
    (pad "SH" thru_hole oval locked (at -4.491 2.95) (size 0.85 1.45) (drill oval 0.5 1.1) (layers *.Cu *.Mask)
      (net 1 "GND") (pintype "input"))
    (pad "SH" thru_hole oval locked (at -4.13 -3.001) (size 0.85 1.45) (drill oval 0.5 1.1) (layers *.Cu *.Mask)
      (net 1 "GND") (pintype "input"))
    (pad "SH" thru_hole oval locked (at 4.49 2.95) (size 0.85 1.45) (drill oval 0.5 1.1) (layers *.Cu *.Mask)
      (net 1 "GND") (pintype "input"))
    (pad "SH" thru_hole oval locked (at 4.128 -3.001) (size 0.85 1.45) (drill oval 0.5 1.1) (layers *.Cu *.Mask)
      (net 1 "GND") (pintype "input"))
  )

  (footprint "sa800u-baseboard-hw-footprints:RJ45_5-2337992-8_Horizontal" locked (layer "F.Cu")
    (tedit 6215E152)
    (at 58.5 133.7)
    (property "Author" "Antmicro")
    (property "License" "Apache-2.0")
    (property "MPN" "5-2337992-8")
    (property "Manufacturer" "TE Connectivity")
    (property "Sheetfile" "ethernet-controller.kicad_sch")
    (property "Sheetname" "Ethernet Controller")
    (attr through_hole)
    (fp_text reference "J1" (at -2.2 -2.2) (layer "F.SilkS")
      (effects (font (size 0.7 0.7) (thickness 0.15)) (justify left bottom))
    )
    (fp_text value "Bus_RJ45_5-2337992-8" (at -2.6 22) (layer "F.Fab")
      (effects (font (size 0.7 0.7) (thickness 0.15)) (justify left bottom))
    )
    (fp_text user "License: Apache-2.0" (at -2.644 26.2) (layer "F.Fab") hide
      (effects (font (size 0.7 0.7) (thickness 0.15)) (justify left bottom))
    )
    (fp_text user "${REFERENCE}" (at -2.644 23.4) (layer "F.Fab") hide
      (effects (font (size 0.7 0.7) (thickness 0.15)) (justify left bottom))
    )
    (fp_text user "Author: Antmicro" (at -2.644 24.8) (layer "F.Fab") hide
      (effects (font (size 0.7 0.7) (thickness 0.15)) (justify left bottom))
    )
    (fp_line (start 13.791 4.48) (end 13.791 -1.845) (layer "F.SilkS") (width 0.15))
    (fp_line (start -2.363 -1.845) (end -2.363 4.48) (layer "F.SilkS") (width 0.15))
    (fp_line (start 13.791 -1.845) (end -2.363 -1.845) (layer "F.SilkS") (width 0.15))
    (fp_line (start 13.791 19.771) (end 13.791 7.217) (layer "F.SilkS") (width 0.15))
    (fp_line (start -2.363 19.771) (end 13.791 19.771) (layer "F.SilkS") (width 0.15))
    (fp_line (start -2.363 7.217) (end -2.363 19.771) (layer "F.SilkS") (width 0.15))
    (fp_rect (start -2.4 -1.8) (end 13.9 19.999) (layer "F.CrtYd") (width 0.05) (fill none))
    (fp_line (start 13.665 -1.718) (end -2.237 -1.718) (layer "F.Fab") (width 0.15))
    (fp_line (start -2.237 -1.718) (end -2.237 19.644) (layer "F.Fab") (width 0.15))
    (fp_line (start -2.237 19.644) (end 13.665 19.644) (layer "F.Fab") (width 0.15))
    (fp_line (start 13.665 19.644) (end 13.665 -1.718) (layer "F.Fab") (width 0.15))
    (pad "" np_thru_hole circle locked (at 0 8.9) (size 3.25 3.25) (drill 3.25) (layers *.Cu *.Mask))
    (pad "" np_thru_hole circle locked (at 11.429 8.9) (size 3.25 3.25) (drill 3.25) (layers *.Cu *.Mask))
    (pad "1" thru_hole circle locked (at 0 0) (size 1.397 1.397) (drill 0.889) (layers *.Cu *.Mask)
      (net 254 "/Ethernet Controller/LAN0_MDI0_N") (pinfunction "P1") (pintype "bidirectional"))
    (pad "2" thru_hole circle locked (at 1.269 2.539) (size 1.397 1.397) (drill 0.889) (layers *.Cu *.Mask)
      (net 255 "/Ethernet Controller/LAN0_MDI0_P") (pinfunction "P2") (pintype "bidirectional"))
    (pad "3" thru_hole circle locked (at 2.539 0) (size 1.397 1.397) (drill 0.889) (layers *.Cu *.Mask)
      (net 256 "/Ethernet Controller/LAN0_MDI1_N") (pinfunction "P3") (pintype "bidirectional"))
    (pad "4" thru_hole circle locked (at 3.809 2.539) (size 1.397 1.397) (drill 0.889) (layers *.Cu *.Mask)
      (net 63 "Net-(C16-Pad1)") (pinfunction "P4") (pintype "bidirectional"))
    (pad "5" thru_hole circle locked (at 5.078 0) (size 1.397 1.397) (drill 0.889) (layers *.Cu *.Mask)
      (net 63 "Net-(C16-Pad1)") (pinfunction "P5") (pintype "bidirectional"))
    (pad "6" thru_hole circle locked (at 6.349 2.539) (size 1.397 1.397) (drill 0.889) (layers *.Cu *.Mask)
      (net 257 "/Ethernet Controller/LAN0_MDI1_P") (pinfunction "P6") (pintype "bidirectional"))
    (pad "7" thru_hole circle locked (at 7.618 0) (size 1.397 1.397) (drill 0.889) (layers *.Cu *.Mask)
      (net 258 "/Ethernet Controller/LAN0_MDI2_N") (pinfunction "P7") (pintype "bidirectional"))
    (pad "8" thru_hole circle locked (at 8.89 2.539) (size 1.397 1.397) (drill 0.889) (layers *.Cu *.Mask)
      (net 259 "/Ethernet Controller/LAN0_MDI2_P") (pinfunction "P8") (pintype "bidirectional"))
    (pad "9" thru_hole circle locked (at 10.159 0) (size 1.397 1.397) (drill 0.889) (layers *.Cu *.Mask)
      (net 260 "/Ethernet Controller/LAN0_MDI3_N") (pinfunction "P9") (pintype "bidirectional"))
    (pad "10" thru_hole circle locked (at 11.429 2.539) (size 1.397 1.397) (drill 0.889) (layers *.Cu *.Mask)
      (net 261 "/Ethernet Controller/LAN0_MDI3_P") (pinfunction "P10") (pintype "bidirectional"))
    (pad "11" thru_hole circle locked (at 0 5.078) (size 1.397 1.397) (drill 0.889) (layers *.Cu *.Mask)
      (net 6 "PAIR12") (pinfunction "VC1") (pintype "bidirectional"))
    (pad "12" thru_hole circle locked (at 2.539 6.339) (size 1.397 1.397) (drill 0.889) (layers *.Cu *.Mask)
      (net 5 "PAIR36") (pinfunction "VC2") (pintype "bidirectional"))
    (pad "13" thru_hole circle locked (at 8.89 6.339) (size 1.397 1.397) (drill 0.889) (layers *.Cu *.Mask)
      (net 3 "PAIR45") (pinfunction "VC3") (pintype "bidirectional"))
    (pad "14" thru_hole circle locked (at 11.429 5.07) (size 1.397 1.397) (drill 0.889) (layers *.Cu *.Mask)
      (net 2 "PAIR78") (pinfunction "VC4") (pintype "bidirectional"))
    (pad "15" thru_hole circle locked (at -0.927 12.958) (size 1.524 1.524) (drill 1.016) (layers *.Cu *.Mask)
      (net 77 "Net-(J1-Pad15)") (pinfunction "LED_GRN+") (pintype "passive"))
    (pad "16" thru_hole circle locked (at 1.614 12.958) (size 1.524 1.524) (drill 1.016) (layers *.Cu *.Mask)
      (net 263 "/Ethernet Controller/ETH_LED2") (pinfunction "LED_GRN-") (pintype "passive"))
    (pad "17" thru_hole circle locked (at 9.814 12.958) (size 1.524 1.524) (drill 1.016) (layers *.Cu *.Mask)
      (net 78 "Net-(J1-Pad17)") (pinfunction "LED_YEL+") (pintype "passive"))
    (pad "18" thru_hole circle locked (at 12.355 12.958) (size 1.524 1.524) (drill 1.016) (layers *.Cu *.Mask)
      (net 262 "/Ethernet Controller/ETH_LED0") (pinfunction "LED_YEL-") (pintype "passive"))
    (pad "19" thru_hole circle locked (at -2.136 5.85) (size 2.1 2.1) (drill 1.6) (layers *.Cu *.Mask)
      (net 4 "Earth") (pinfunction "SHIELD") (pintype "passive"))
    (pad "20" thru_hole circle locked (at 13.563 5.85) (size 2.1082 2.1082) (drill 1.6002) (layers *.Cu *.Mask)
      (net 4 "Earth") (pinfunction "SHIELD") (pintype "passive"))
  )

  (footprint "sa800u-baseboard-hw-footprints:L_Murata_025020_0605Metric" (layer "F.Cu")
    (tedit 61AA2C4F)
    (at 152 130.5)
    (property "Author" "Antmicro")
    (property "License" "Apache-2.0")
    (property "MPN" "NFP0QHB242HS2D")
    (property "Manufacturer" "Murata")
    (property "Sheetfile" "lcm.kicad_sch")
    (property "Sheetname" "LCM")
    (attr smd)
    (fp_text reference "L15" (at -0.99 -0.72) (layer "F.SilkS")
      (effects (font (size 0.7 0.7) (thickness 0.15)) (justify left bottom))
    )
    (fp_text value "NFP0QHB242HS2D" (at 0 1.55) (layer "F.Fab")
      (effects (font (size 0.7 0.7) (thickness 0.15)) (justify left bottom))
    )
    (fp_text user "License: Apache-2.0" (at -1.027 5.805) (layer "F.Fab") hide
      (effects (font (size 0.7 0.7) (thickness 0.15)) (justify left bottom))
    )
    (fp_text user "${REFERENCE}" (at -1.027 3.406) (layer "F.Fab") hide
      (effects (font (size 0.7 0.7) (thickness 0.15)) (justify left bottom))
    )
    (fp_text user "Author: Antmicro" (at -1.027 4.605) (layer "F.Fab") hide
      (effects (font (size 0.7 0.7) (thickness 0.15)) (justify left bottom))
    )
    (fp_line (start -0.276 0.45) (end 0.276 0.45) (layer "F.SilkS") (width 0.15))
    (fp_line (start 0.276 -0.45) (end -0.276 -0.45) (layer "F.SilkS") (width 0.15))
    (fp_circle (center -0.5 -0.5) (end -0.449 -0.5) (layer "F.SilkS") (width 0.15) (fill solid))
    (fp_rect (start -0.5 -0.6) (end 0.5 0.6) (layer "F.CrtYd") (width 0.05) (fill none))
    (fp_line (start -0.277 0.349) (end 0.275 0.349) (layer "F.Fab") (width 0.15))
    (fp_line (start 0.275 -0.351) (end -0.277 -0.351) (layer "F.Fab") (width 0.15))
    (fp_line (start -0.277 -0.351) (end -0.277 0.349) (layer "F.Fab") (width 0.15))
    (fp_line (start 0.275 0.349) (end 0.275 -0.351) (layer "F.Fab") (width 0.15))
    (pad "1" smd rect (at -0.25 -0.24) (size 0.3 0.23) (layers "F.Cu" "F.Paste" "F.Mask")
      (net 310 "/LCM/DSI_CLK_L_N") (pinfunction "1") (pintype "passive"))
    (pad "2" smd rect (at 0.248 -0.24) (size 0.3 0.23) (layers "F.Cu" "F.Paste" "F.Mask")
      (net 86 "DSI0_CLK_N") (pinfunction "2") (pintype "passive"))
    (pad "3" smd rect (at 0.248 0.239) (size 0.3 0.23) (layers "F.Cu" "F.Paste" "F.Mask")
      (net 85 "DSI0_CLK_P") (pinfunction "3") (pintype "passive"))
    (pad "4" smd rect (at -0.25 0.239) (size 0.3 0.23) (layers "F.Cu" "F.Paste" "F.Mask")
      (net 309 "/LCM/DSI_CLK_L_P") (pinfunction "4") (pintype "passive"))
  )

  (footprint "sa800u-baseboard-hw-footprints:L_Murata_025020_0605Metric" (layer "F.Cu")
    (tedit 61AA2C4F)
    (at 152 127.5)
    (property "Author" "Antmicro")
    (property "License" "Apache-2.0")
    (property "MPN" "NFP0QHB242HS2D")
    (property "Manufacturer" "Murata")
    (property "Sheetfile" "lcm.kicad_sch")
    (property "Sheetname" "LCM")
    (attr smd)
    (fp_text reference "L14" (at -0.99 -0.72) (layer "F.SilkS")
      (effects (font (size 0.7 0.7) (thickness 0.15)) (justify left bottom))
    )
    (fp_text value "NFP0QHB242HS2D" (at 0 1.55) (layer "F.Fab")
      (effects (font (size 0.7 0.7) (thickness 0.15)) (justify left bottom))
    )
    (fp_text user "License: Apache-2.0" (at -1.027 5.805) (layer "F.Fab") hide
      (effects (font (size 0.7 0.7) (thickness 0.15)) (justify left bottom))
    )
    (fp_text user "Author: Antmicro" (at -1.027 4.605) (layer "F.Fab") hide
      (effects (font (size 0.7 0.7) (thickness 0.15)) (justify left bottom))
    )
    (fp_text user "${REFERENCE}" (at -1.027 3.406) (layer "F.Fab") hide
      (effects (font (size 0.7 0.7) (thickness 0.15)) (justify left bottom))
    )
    (fp_line (start -0.276 0.45) (end 0.276 0.45) (layer "F.SilkS") (width 0.15))
    (fp_line (start 0.276 -0.45) (end -0.276 -0.45) (layer "F.SilkS") (width 0.15))
    (fp_circle (center -0.5 -0.5) (end -0.449 -0.5) (layer "F.SilkS") (width 0.15) (fill solid))
    (fp_rect (start -0.5 -0.6) (end 0.5 0.6) (layer "F.CrtYd") (width 0.05) (fill none))
    (fp_line (start 0.275 0.349) (end 0.275 -0.351) (layer "F.Fab") (width 0.15))
    (fp_line (start -0.277 -0.351) (end -0.277 0.349) (layer "F.Fab") (width 0.15))
    (fp_line (start -0.277 0.349) (end 0.275 0.349) (layer "F.Fab") (width 0.15))
    (fp_line (start 0.275 -0.351) (end -0.277 -0.351) (layer "F.Fab") (width 0.15))
    (pad "1" smd rect (at -0.25 -0.24) (size 0.3 0.23) (layers "F.Cu" "F.Paste" "F.Mask")
      (net 312 "/LCM/DSI_LN0_L_N") (pinfunction "1") (pintype "passive"))
    (pad "2" smd rect (at 0.248 -0.24) (size 0.3 0.23) (layers "F.Cu" "F.Paste" "F.Mask")
      (net 87 "DSI0_LN0_N") (pinfunction "2") (pintype "passive"))
    (pad "3" smd rect (at 0.248 0.239) (size 0.3 0.23) (layers "F.Cu" "F.Paste" "F.Mask")
      (net 88 "DSI0_LN0_P") (pinfunction "3") (pintype "passive"))
    (pad "4" smd rect (at -0.25 0.239) (size 0.3 0.23) (layers "F.Cu" "F.Paste" "F.Mask")
      (net 311 "/LCM/DSI_LN0_L_P") (pinfunction "4") (pintype "passive"))
  )

  (footprint "sa800u-baseboard-hw-footprints:L_Murata_025020_0605Metric" (layer "F.Cu")
    (tedit 61AA2C4F)
    (at 152 124.5)
    (property "Author" "Antmicro")
    (property "License" "Apache-2.0")
    (property "MPN" "NFP0QHB242HS2D")
    (property "Manufacturer" "Murata")
    (property "Sheetfile" "lcm.kicad_sch")
    (property "Sheetname" "LCM")
    (attr smd)
    (fp_text reference "L13" (at -0.99 -0.72) (layer "F.SilkS")
      (effects (font (size 0.7 0.7) (thickness 0.15)) (justify left bottom))
    )
    (fp_text value "NFP0QHB242HS2D" (at 0 1.55) (layer "F.Fab")
      (effects (font (size 0.7 0.7) (thickness 0.15)) (justify left bottom))
    )
    (fp_text user "${REFERENCE}" (at -1.027 3.406) (layer "F.Fab") hide
      (effects (font (size 0.7 0.7) (thickness 0.15)) (justify left bottom))
    )
    (fp_text user "License: Apache-2.0" (at -1.027 5.805) (layer "F.Fab") hide
      (effects (font (size 0.7 0.7) (thickness 0.15)) (justify left bottom))
    )
    (fp_text user "Author: Antmicro" (at -1.027 4.605) (layer "F.Fab") hide
      (effects (font (size 0.7 0.7) (thickness 0.15)) (justify left bottom))
    )
    (fp_line (start -0.276 0.45) (end 0.276 0.45) (layer "F.SilkS") (width 0.15))
    (fp_line (start 0.276 -0.45) (end -0.276 -0.45) (layer "F.SilkS") (width 0.15))
    (fp_circle (center -0.5 -0.5) (end -0.449 -0.5) (layer "F.SilkS") (width 0.15) (fill solid))
    (fp_rect (start -0.5 -0.6) (end 0.5 0.6) (layer "F.CrtYd") (width 0.05) (fill none))
    (fp_line (start -0.277 -0.351) (end -0.277 0.349) (layer "F.Fab") (width 0.15))
    (fp_line (start -0.277 0.349) (end 0.275 0.349) (layer "F.Fab") (width 0.15))
    (fp_line (start 0.275 -0.351) (end -0.277 -0.351) (layer "F.Fab") (width 0.15))
    (fp_line (start 0.275 0.349) (end 0.275 -0.351) (layer "F.Fab") (width 0.15))
    (pad "1" smd rect (at -0.25 -0.24) (size 0.3 0.23) (layers "F.Cu" "F.Paste" "F.Mask")
      (net 314 "/LCM/DSI_LN1_L_N") (pinfunction "1") (pintype "passive"))
    (pad "2" smd rect (at 0.248 -0.24) (size 0.3 0.23) (layers "F.Cu" "F.Paste" "F.Mask")
      (net 83 "DSI0_LN1_N") (pinfunction "2") (pintype "passive"))
    (pad "3" smd rect (at 0.248 0.239) (size 0.3 0.23) (layers "F.Cu" "F.Paste" "F.Mask")
      (net 84 "DSI0_LN1_P") (pinfunction "3") (pintype "passive"))
    (pad "4" smd rect (at -0.25 0.239) (size 0.3 0.23) (layers "F.Cu" "F.Paste" "F.Mask")
      (net 313 "/LCM/DSI_LN1_L_P") (pinfunction "4") (pintype "passive"))
  )

  (footprint "sa800u-baseboard-hw-footprints:R_0402_1005Metric" (layer "F.Cu")
    (tedit 5FD9C158)
    (at 148.3 142.5 -90)
    (descr "Resistor SMD 0402")
    (tags "resistor SMD 0402")
    (property "Author" "Antmicro")
    (property "Current" "1A")
    (property "License" "Apache-2.0")
    (property "MPN" "ERJ2GE0R00X")
    (property "Manufacturer" "Panasonic")
    (property "Sheetfile" "hdmi-converter.kicad_sch")
    (property "Sheetname" "HDMI converter")
    (property "Tolerance" "")
    (property "Val" "0R")
    (attr smd)
    (fp_text reference "R30" (at 0.96 0.58 -90) (layer "F.SilkS")
      (effects (font (size 0.7 0.7) (thickness 0.15)) (justify left bottom))
    )
    (fp_text value "R_0R_0402" (at 0 1.4 -90) (layer "F.Fab")
      (effects (font (size 0.7 0.7) (thickness 0.15)) (justify left bottom))
    )
    (fp_text user "License: Apache-2.0" (at -0.95 5.169 -90) (layer "F.Fab") hide
      (effects (font (size 0.7 0.7) (thickness 0.15)) (justify left bottom))
    )
    (fp_text user "Author: Antmicro" (at -0.95 4.169 -90) (layer "F.Fab") hide
      (effects (font (size 0.7 0.7) (thickness 0.15)) (justify left bottom))
    )
    (fp_text user "${REFERENCE}" (at -0.95 3.168 -90) (layer "F.Fab") hide
      (effects (font (size 0.7 0.7) (thickness 0.15)) (justify left bottom))
    )
    (fp_rect (start -0.93 -0.47) (end 0.93 0.47) (layer "F.CrtYd") (width 0.05) (fill none))
    (fp_rect (start -0.5 -0.25) (end 0.5 0.25) (layer "F.Fab") (width 0.15) (fill none))
    (pad "1" smd roundrect (at -0.485 0 270) (size 0.59 0.64) (layers "F.Cu" "F.Paste" "F.Mask") (roundrect_rratio 0.25)
      (net 395 "Net-(R27-Pad1)") (pintype "passive"))
    (pad "2" smd roundrect (at 0.485 0 270) (size 0.59 0.64) (layers "F.Cu" "F.Paste" "F.Mask") (roundrect_rratio 0.25)
      (net 234 "/HDMI converter/HDMI_DETECT") (pintype "passive"))
  )

  (footprint "sa800u-baseboard-hw-footprints:C_0603_1608Metric" (layer "F.Cu")
    (tedit 5D5E94D2)
    (at 83.2 141.1 -90)
    (descr "Capacitor SMD 0603")
    (tags "capacitor 0603")
    (property "Author" "Antmicro")
    (property "Dielectric" "")
    (property "License" "Apache-2.0")
    (property "MPN" "0603YD105KAT2A")
    (property "Manufacturer" "Walsin")
    (property "Sheetfile" "usb-pd.kicad_sch")
    (property "Sheetname" "USB-PD")
    (property "Val" "1u")
    (property "Voltage" "")
    (attr smd)
    (fp_text reference "C153" (at 1.21 -0.64) (layer "F.SilkS")
      (effects (font (size 0.7 0.7) (thickness 0.15)) (justify left bottom))
    )
    (fp_text value "C_1u_0603" (at 0 1.6 -90) (layer "F.Fab")
      (effects (font (size 0.7 0.7) (thickness 0.15)) (justify left bottom))
    )
    (fp_text user "License: Apache-2.0" (at -1.682 5.895 -90) (layer "F.Fab") hide
      (effects (font (size 0.7 0.7) (thickness 0.15)) (justify left bottom))
    )
    (fp_text user "${REFERENCE}" (at -1.682 3.895 -90) (layer "F.Fab") hide
      (effects (font (size 0.7 0.7) (thickness 0.15)) (justify left bottom))
    )
    (fp_text user "Author: Antmicro" (at -1.682 4.894 -90) (layer "F.Fab") hide
      (effects (font (size 0.7 0.7) (thickness 0.15)) (justify left bottom))
    )
    (fp_line (start -0.3 0.3) (end 0.3 0.3) (layer "F.SilkS") (width 0.15))
    (fp_line (start -0.3 -0.3) (end 0.3 -0.3) (layer "F.SilkS") (width 0.15))
    (fp_rect (start -1.24 -0.7) (end 1.24 0.7) (layer "F.CrtYd") (width 0.05) (fill none))
    (fp_rect (start -0.8 -0.4) (end 0.8 0.4) (layer "F.Fab") (width 0.15) (fill none))
    (pad "1" smd roundrect (at -0.7 0 270) (size 0.6 0.8) (layers "F.Cu" "F.Paste" "F.Mask") (roundrect_rratio 0.2)
      (net 364 "Net-(C153-Pad1)") (pintype "passive"))
    (pad "2" smd roundrect (at 0.7 0 270) (size 0.6 0.8) (layers "F.Cu" "F.Paste" "F.Mask") (roundrect_rratio 0.2)
      (net 1 "GND") (pintype "passive"))
  )

  (footprint "sa800u-baseboard-hw-footprints:R_0402_1005Metric" (layer "F.Cu")
    (tedit 5FD9C158)
    (at 83.4 139.3)
    (descr "Resistor SMD 0402")
    (tags "resistor SMD 0402")
    (property "Author" "Antmicro")
    (property "License" "Apache-2.0")
    (property "MPN" "CR0402-FX-1001GLF")
    (property "Manufacturer" "Bourns")
    (property "Sheetfile" "usb-pd.kicad_sch")
    (property "Sheetname" "USB-PD")
    (property "Tolerance" "1%")
    (property "Val" "1k")
    (attr smd)
    (fp_text reference "R159" (at 0.34 1.48) (layer "F.SilkS")
      (effects (font (size 0.7 0.7) (thickness 0.15)) (justify left bottom))
    )
    (fp_text value "R_1k_0402" (at 0 1.4) (layer "F.Fab")
      (effects (font (size 0.7 0.7) (thickness 0.15)) (justify left bottom))
    )
    (fp_text user "License: Apache-2.0" (at -0.95 5.169) (layer "F.Fab") hide
      (effects (font (size 0.7 0.7) (thickness 0.15)) (justify left bottom))
    )
    (fp_text user "${REFERENCE}" (at -0.95 3.168) (layer "F.Fab") hide
      (effects (font (size 0.7 0.7) (thickness 0.15)) (justify left bottom))
    )
    (fp_text user "Author: Antmicro" (at -0.95 4.169) (layer "F.Fab") hide
      (effects (font (size 0.7 0.7) (thickness 0.15)) (justify left bottom))
    )
    (fp_rect (start -0.93 -0.47) (end 0.93 0.47) (layer "F.CrtYd") (width 0.05) (fill none))
    (fp_rect (start -0.5 -0.25) (end 0.5 0.25) (layer "F.Fab") (width 0.15) (fill none))
    (pad "1" smd roundrect (at -0.485 0) (size 0.59 0.64) (layers "F.Cu" "F.Paste" "F.Mask") (roundrect_rratio 0.25)
      (net 364 "Net-(C153-Pad1)") (pintype "passive"))
    (pad "2" smd roundrect (at 0.485 0) (size 0.59 0.64) (layers "F.Cu" "F.Paste" "F.Mask") (roundrect_rratio 0.25)
      (net 466 "/USB-PD/VS_DISCH") (pintype "passive"))
  )

  (footprint "sa800u-baseboard-hw-footprints:C_0402_1005Metric" (layer "F.Cu")
    (tedit 616D63CF)
    (at 81.175 138.05 180)
    (descr "Capacitor SMD 0402")
    (tags "capacitor SMD 0402")
    (property "Author" "Antmicro")
    (property "Dielectric" "X5R")
    (property "License" "Apache-2.0")
    (property "MPN" "GRM155R61H104KE14D")
    (property "Manufacturer" "Murata")
    (property "Sheetfile" "usb-pd.kicad_sch")
    (property "Sheetname" "USB-PD")
    (property "Val" "100n")
    (property "Voltage" "50V")
    (attr smd)
    (fp_text reference "C155" (at 3.555 -1.47 180) (layer "F.SilkS")
      (effects (font (size 0.7 0.7) (thickness 0.15)) (justify left bottom))
    )
    (fp_text value "C_100n_0402" (at 0 1.4 180) (layer "F.Fab")
      (effects (font (size 0.7 0.7) (thickness 0.15)) (justify left bottom))
    )
    (fp_text user "Author: Antmicro" (at -0.932 4.17 180) (layer "F.Fab") hide
      (effects (font (size 0.7 0.7) (thickness 0.15)) (justify left bottom))
    )
    (fp_text user "License: Apache-2.0" (at -0.932 5.17 180) (layer "F.Fab") hide
      (effects (font (size 0.7 0.7) (thickness 0.15)) (justify left bottom))
    )
    (fp_text user "${REFERENCE}" (at -0.932 3.168 180) (layer "F.Fab") hide
      (effects (font (size 0.7 0.7) (thickness 0.15)) (justify left bottom))
    )
    (fp_rect (start -0.94 -0.47) (end 0.94 0.47) (layer "F.CrtYd") (width 0.05) (fill none))
    (fp_rect (start -0.499 -0.249) (end 0.499 0.249) (layer "F.Fab") (width 0.15) (fill none))
    (pad "1" smd roundrect (at -0.484 0 180) (size 0.59 0.64) (layers "F.Cu" "F.Paste" "F.Mask") (roundrect_rratio 0.25)
      (net 142 "PD_VDD") (pintype "passive"))
    (pad "2" smd roundrect (at 0.484 0 180) (size 0.59 0.64) (layers "F.Cu" "F.Paste" "F.Mask") (roundrect_rratio 0.25)
      (net 365 "Net-(C155-Pad2)") (pintype "passive"))
  )

  (footprint "sa800u-baseboard-hw-footprints:R_0402_1005Metric" (layer "F.Cu")
    (tedit 5FD9C158)
    (at 80.05 136.525 90)
    (descr "Resistor SMD 0402")
    (tags "resistor SMD 0402")
    (property "Author" "Antmicro")
    (property "License" "Apache-2.0")
    (property "MPN" "CR0402-FX-1003GLF")
    (property "Manufacturer" "Bourns")
    (property "Sheetfile" "usb-pd.kicad_sch")
    (property "Sheetname" "USB-PD")
    (property "Tolerance" "1%")
    (property "Val" "100k")
    (attr smd)
    (fp_text reference "R160" (at -1.765 -0.61 90) (layer "F.SilkS")
      (effects (font (size 0.7 0.7) (thickness 0.15)) (justify left bottom))
    )
    (fp_text value "R_100k_0402" (at 0 1.4 90) (layer "F.Fab")
      (effects (font (size 0.7 0.7) (thickness 0.15)) (justify left bottom))
    )
    (fp_text user "${REFERENCE}" (at -0.95 3.168 90) (layer "F.Fab") hide
      (effects (font (size 0.7 0.7) (thickness 0.15)) (justify left bottom))
    )
    (fp_text user "License: Apache-2.0" (at -0.95 5.169 90) (layer "F.Fab") hide
      (effects (font (size 0.7 0.7) (thickness 0.15)) (justify left bottom))
    )
    (fp_text user "Author: Antmicro" (at -0.95 4.169 90) (layer "F.Fab") hide
      (effects (font (size 0.7 0.7) (thickness 0.15)) (justify left bottom))
    )
    (fp_rect (start -0.93 -0.47) (end 0.93 0.47) (layer "F.CrtYd") (width 0.05) (fill none))
    (fp_rect (start -0.5 -0.25) (end 0.5 0.25) (layer "F.Fab") (width 0.15) (fill none))
    (pad "1" smd roundrect (at -0.485 0 90) (size 0.59 0.64) (layers "F.Cu" "F.Paste" "F.Mask") (roundrect_rratio 0.25)
      (net 107 "/USB-PD/PD_VBUS") (pintype "passive"))
    (pad "2" smd roundrect (at 0.485 0 90) (size 0.59 0.64) (layers "F.Cu" "F.Paste" "F.Mask") (roundrect_rratio 0.25)
      (net 391 "Net-(Q17-Pad4)") (pintype "passive"))
  )

  (footprint "sa800u-baseboard-hw-footprints:R_0402_1005Metric" (layer "F.Cu")
    (tedit 5FD9C158)
    (at 81.47 136.05)
    (descr "Resistor SMD 0402")
    (tags "resistor SMD 0402")
    (property "Author" "Antmicro")
    (property "License" "Apache-2.0")
    (property "MPN" "CR0402-FX-2202GLF")
    (property "Manufacturer" "Bourns")
    (property "Sheetfile" "usb-pd.kicad_sch")
    (property "Sheetname" "USB-PD")
    (property "Tolerance" "1%")
    (property "Val" "22k")
    (attr smd)
    (fp_text reference "R161" (at -1.71 -1.58) (layer "F.SilkS")
      (effects (font (size 0.7 0.7) (thickness 0.15)) (justify left bottom))
    )
    (fp_text value "R_22k_0402" (at 0 1.4) (layer "F.Fab")
      (effects (font (size 0.7 0.7) (thickness 0.15)) (justify left bottom))
    )
    (fp_text user "Author: Antmicro" (at -0.95 4.169) (layer "F.Fab") hide
      (effects (font (size 0.7 0.7) (thickness 0.15)) (justify left bottom))
    )
    (fp_text user "${REFERENCE}" (at -0.95 3.168) (layer "F.Fab") hide
      (effects (font (size 0.7 0.7) (thickness 0.15)) (justify left bottom))
    )
    (fp_text user "License: Apache-2.0" (at -0.95 5.169) (layer "F.Fab") hide
      (effects (font (size 0.7 0.7) (thickness 0.15)) (justify left bottom))
    )
    (fp_rect (start -0.93 -0.47) (end 0.93 0.47) (layer "F.CrtYd") (width 0.05) (fill none))
    (fp_rect (start -0.5 -0.25) (end 0.5 0.25) (layer "F.Fab") (width 0.15) (fill none))
    (pad "1" smd roundrect (at -0.485 0) (size 0.59 0.64) (layers "F.Cu" "F.Paste" "F.Mask") (roundrect_rratio 0.25)
      (net 391 "Net-(Q17-Pad4)") (pintype "passive"))
    (pad "2" smd roundrect (at 0.485 0) (size 0.59 0.64) (layers "F.Cu" "F.Paste" "F.Mask") (roundrect_rratio 0.25)
      (net 467 "/USB-PD/EN_SINK") (pintype "passive"))
  )

  (footprint "sa800u-baseboard-hw-footprints:R_0402_1005Metric" (layer "F.Cu")
    (tedit 5FD9C158)
    (at 81.45 137.05)
    (descr "Resistor SMD 0402")
    (tags "resistor SMD 0402")
    (property "Author" "Antmicro")
    (property "License" "Apache-2.0")
    (property "MPN" "CR0402-FX-1000GLF")
    (property "Manufacturer" "Bourns")
    (property "Sheetfile" "usb-pd.kicad_sch")
    (property "Sheetname" "USB-PD")
    (property "Tolerance" "1%")
    (property "Val" "100R")
    (attr smd)
    (fp_text reference "R166" (at -1.71 -1.58) (layer "F.SilkS")
      (effects (font (size 0.7 0.7) (thickness 0.15)) (justify left bottom))
    )
    (fp_text value "R_100R_0402" (at 0 1.4) (layer "F.Fab")
      (effects (font (size 0.7 0.7) (thickness 0.15)) (justify left bottom))
    )
    (fp_text user "${REFERENCE}" (at -0.95 3.168) (layer "F.Fab") hide
      (effects (font (size 0.7 0.7) (thickness 0.15)) (justify left bottom))
    )
    (fp_text user "Author: Antmicro" (at -0.95 4.169) (layer "F.Fab") hide
      (effects (font (size 0.7 0.7) (thickness 0.15)) (justify left bottom))
    )
    (fp_text user "License: Apache-2.0" (at -0.95 5.169) (layer "F.Fab") hide
      (effects (font (size 0.7 0.7) (thickness 0.15)) (justify left bottom))
    )
    (fp_rect (start -0.93 -0.47) (end 0.93 0.47) (layer "F.CrtYd") (width 0.05) (fill none))
    (fp_rect (start -0.5 -0.25) (end 0.5 0.25) (layer "F.Fab") (width 0.15) (fill none))
    (pad "1" smd roundrect (at -0.485 0) (size 0.59 0.64) (layers "F.Cu" "F.Paste" "F.Mask") (roundrect_rratio 0.25)
      (net 391 "Net-(Q17-Pad4)") (pintype "passive"))
    (pad "2" smd roundrect (at 0.485 0) (size 0.59 0.64) (layers "F.Cu" "F.Paste" "F.Mask") (roundrect_rratio 0.25)
      (net 365 "Net-(C155-Pad2)") (pintype "passive"))
  )

  (footprint "sa800u-baseboard-hw-footprints:D_SOD-323F" (layer "F.Cu")
    (tedit 60F16F6B)
    (at 81.5 141.4 -90)
    (property "Author" "Antmicro")
    (property "License" "Apache-2.0")
    (property "MPN" "PMEG6002EJ,115")
    (property "Manufacturer" "Nexperia")
    (property "Sheetfile" "usb-pd.kicad_sch")
    (property "Sheetname" "USB-PD")
    (attr smd)
    (fp_text reference "D35" (at 3.7 -0.5 -90) (layer "F.SilkS")
      (effects (font (size 0.7 0.7) (thickness 0.15)) (justify left bottom))
    )
    (fp_text value "PMEG6002EJ,115" (at -1.7 1.9 -90) (layer "F.Fab")
      (effects (font (size 0.7 0.7) (thickness 0.15)) (justify left bottom))
    )
    (fp_text user "Author: Antmicro" (at -1.8 4.46 -90) (layer "F.Fab") hide
      (effects (font (size 0.7 0.7) (thickness 0.15)) (justify left bottom))
    )
    (fp_text user "${REFERENCE}" (at -1.8 3.2 -90) (layer "F.Fab") hide
      (effects (font (size 0.7 0.7) (thickness 0.15)) (justify left bottom))
    )
    (fp_text user "License: Apache-2.0" (at -1.8 5.8 -90) (layer "F.Fab") hide
      (effects (font (size 0.7 0.7) (thickness 0.15)) (justify left bottom))
    )
    (fp_line (start 0.973 0.45) (end 0.973 0.748) (layer "F.SilkS") (width 0.15))
    (fp_line (start 0.623 -0.75) (end 0.973 -0.75) (layer "F.SilkS") (width 0.15))
    (fp_line (start -0.625 -0.75) (end -0.975 -0.75) (layer "F.SilkS") (width 0.15))
    (fp_line (start 0.973 0.748) (end 0.623 0.748) (layer "F.SilkS") (width 0.15))
    (fp_line (start -0.625 0.748) (end -0.975 0.748) (layer "F.SilkS") (width 0.15))
    (fp_line (start -0.5 -0.426) (end -0.5 0.424) (layer "F.SilkS") (width 0.15))
    (fp_line (start -0.975 -0.75) (end -0.975 -0.45) (layer "F.SilkS") (width 0.15))
    (fp_line (start -0.975 0.748) (end -0.975 0.45) (layer "F.SilkS") (width 0.15))
    (fp_line (start 0.973 -0.75) (end 0.973 -0.45) (layer "F.SilkS") (width 0.15))
    (fp_rect (start -1.6 -0.827) (end 1.599 0.825) (layer "F.CrtYd") (width 0.05) (fill none))
    (fp_line (start -0.85 0.623) (end -0.85 -0.625) (layer "F.Fab") (width 0.15))
    (fp_line (start -0.85 0.623) (end 0.848 0.623) (layer "F.Fab") (width 0.15))
    (fp_line (start 0.848 -0.625) (end 0.848 0.623) (layer "F.Fab") (width 0.15))
    (fp_line (start -0.85 -0.625) (end 0.848 -0.625) (layer "F.Fab") (width 0.15))
    (pad "A" smd roundrect (at 1.05 0 270) (size 0.8 0.6) (layers "F.Cu" "F.Paste" "F.Mask") (roundrect_rratio 0.15)
      (net 107 "/USB-PD/PD_VBUS") (pinfunction "A") (pintype "passive"))
    (pad "K" smd roundrect (at -1.051 0 270) (size 0.8 0.6) (layers "F.Cu" "F.Paste" "F.Mask") (roundrect_rratio 0.15)
      (net 364 "Net-(C153-Pad1)") (pinfunction "K") (pintype "passive"))
  )

  (footprint "sa800u-baseboard-hw-footprints:C_0603_1608Metric" (layer "F.Cu")
    (tedit 5D5E94D2)
    (at 81.97 120.05 -90)
    (descr "Capacitor SMD 0603")
    (tags "capacitor 0603")
    (property "Author" "Antmicro")
    (property "Dielectric" "")
    (property "License" "Apache-2.0")
    (property "MPN" "GRM188R60J226MEA0D")
    (property "Manufacturer" "Murata")
    (property "Sheetfile" "psu.kicad_sch")
    (property "Sheetname" "PSU")
    (property "Val" "22u")
    (property "Voltage" "")
    (attr smd)
    (fp_text reference "C143" (at 1.32 -2.96 -90) (layer "F.SilkS")
      (effects (font (size 0.7 0.7) (thickness 0.15)) (justify left bottom))
    )
    (fp_text value "C_22u_0603" (at 0 1.6 -90) (layer "F.Fab")
      (effects (font (size 0.7 0.7) (thickness 0.15)) (justify left bottom))
    )
    (fp_text user "Author: Antmicro" (at -1.682 4.894 -90) (layer "F.Fab") hide
      (effects (font (size 0.7 0.7) (thickness 0.15)) (justify left bottom))
    )
    (fp_text user "${REFERENCE}" (at -1.682 3.895 -90) (layer "F.Fab") hide
      (effects (font (size 0.7 0.7) (thickness 0.15)) (justify left bottom))
    )
    (fp_text user "License: Apache-2.0" (at -1.682 5.895 -90) (layer "F.Fab") hide
      (effects (font (size 0.7 0.7) (thickness 0.15)) (justify left bottom))
    )
    (fp_line (start -0.3 -0.3) (end 0.3 -0.3) (layer "F.SilkS") (width 0.15))
    (fp_line (start -0.3 0.3) (end 0.3 0.3) (layer "F.SilkS") (width 0.15))
    (fp_rect (start -1.24 -0.7) (end 1.24 0.7) (layer "F.CrtYd") (width 0.05) (fill none))
    (fp_rect (start -0.8 -0.4) (end 0.8 0.4) (layer "F.Fab") (width 0.15) (fill none))
    (pad "1" smd roundrect (at -0.7 0 270) (size 0.6 0.8) (layers "F.Cu" "F.Paste" "F.Mask") (roundrect_rratio 0.2)
      (net 133 "5V_SYS") (pintype "passive"))
    (pad "2" smd roundrect (at 0.7 0 270) (size 0.6 0.8) (layers "F.Cu" "F.Paste" "F.Mask") (roundrect_rratio 0.2)
      (net 1 "GND") (pintype "passive"))
  )

  (footprint "sa800u-baseboard-hw-footprints:R_0402_1005Metric" (layer "F.Cu")
    (tedit 5FD9C158)
    (at 71.6 117.3)
    (descr "Resistor SMD 0402")
    (tags "resistor SMD 0402")
    (property "Author" "Antmicro")
    (property "License" "Apache-2.0")
    (property "MPN" "CR0402-FX-5232GLF")
    (property "Manufacturer" "Bourns")
    (property "Sheetfile" "psu.kicad_sch")
    (property "Sheetname" "PSU")
    (property "Tolerance" "1%")
    (property "Val" "52k3")
    (attr smd)
    (fp_text reference "R141" (at 0.95 4.53) (layer "F.SilkS")
      (effects (font (size 0.7 0.7) (thickness 0.15)) (justify left bottom))
    )
    (fp_text value "R_52k3_0402" (at 0 1.4) (layer "F.Fab")
      (effects (font (size 0.7 0.7) (thickness 0.15)) (justify left bottom))
    )
    (fp_text user "License: Apache-2.0" (at -0.95 5.169) (layer "F.Fab") hide
      (effects (font (size 0.7 0.7) (thickness 0.15)) (justify left bottom))
    )
    (fp_text user "${REFERENCE}" (at -0.95 3.168) (layer "F.Fab") hide
      (effects (font (size 0.7 0.7) (thickness 0.15)) (justify left bottom))
    )
    (fp_text user "Author: Antmicro" (at -0.95 4.169) (layer "F.Fab") hide
      (effects (font (size 0.7 0.7) (thickness 0.15)) (justify left bottom))
    )
    (fp_rect (start -0.93 -0.47) (end 0.93 0.47) (layer "F.CrtYd") (width 0.05) (fill none))
    (fp_rect (start -0.5 -0.25) (end 0.5 0.25) (layer "F.Fab") (width 0.15) (fill none))
    (pad "1" smd roundrect (at -0.485 0) (size 0.59 0.64) (layers "F.Cu" "F.Paste" "F.Mask") (roundrect_rratio 0.25)
      (net 133 "5V_SYS") (pintype "passive"))
    (pad "2" smd roundrect (at 0.485 0) (size 0.59 0.64) (layers "F.Cu" "F.Paste" "F.Mask") (roundrect_rratio 0.25)
      (net 173 "Net-(R141-Pad2)") (pintype "passive"))
  )

  (footprint "sa800u-baseboard-hw-footprints:C_0402_1005Metric" (layer "F.Cu")
    (tedit 616D63CF)
    (at 73.55 114.2)
    (descr "Capacitor SMD 0402")
    (tags "capacitor SMD 0402")
    (property "Author" "Antmicro")
    (property "Dielectric" "X5R")
    (property "License" "Apache-2.0")
    (property "MPN" "GRM155R61H104KE14D")
    (property "Manufacturer" "Murata")
    (property "Sheetfile" "psu.kicad_sch")
    (property "Sheetname" "PSU")
    (property "Val" "100n")
    (property "Voltage" "50V")
    (attr smd)
    (fp_text reference "C133" (at -3.75 0.29) (layer "F.SilkS")
      (effects (font (size 0.7 0.7) (thickness 0.15)) (justify left bottom))
    )
    (fp_text value "C_100n_0402" (at 0 1.4) (layer "F.Fab")
      (effects (font (size 0.7 0.7) (thickness 0.15)) (justify left bottom))
    )
    (fp_text user "${REFERENCE}" (at -0.932 3.168) (layer "F.Fab") hide
      (effects (font (size 0.7 0.7) (thickness 0.15)) (justify left bottom))
    )
    (fp_text user "Author: Antmicro" (at -0.932 4.17) (layer "F.Fab") hide
      (effects (font (size 0.7 0.7) (thickness 0.15)) (justify left bottom))
    )
    (fp_text user "License: Apache-2.0" (at -0.932 5.17) (layer "F.Fab") hide
      (effects (font (size 0.7 0.7) (thickness 0.15)) (justify left bottom))
    )
    (fp_rect (start -0.94 -0.47) (end 0.94 0.47) (layer "F.CrtYd") (width 0.05) (fill none))
    (fp_rect (start -0.499 -0.249) (end 0.499 0.249) (layer "F.Fab") (width 0.15) (fill none))
    (pad "1" smd roundrect (at -0.484 0) (size 0.59 0.64) (layers "F.Cu" "F.Paste" "F.Mask") (roundrect_rratio 0.25)
      (net 358 "Net-(C133-Pad1)") (pintype "passive"))
    (pad "2" smd roundrect (at 0.484 0) (size 0.59 0.64) (layers "F.Cu" "F.Paste" "F.Mask") (roundrect_rratio 0.25)
      (net 359 "Net-(C133-Pad2)") (pintype "passive"))
  )

  (footprint "sa800u-baseboard-hw-footprints:C_0402_1005Metric" (layer "F.Cu")
    (tedit 616D63CF)
    (at 101.549174 104.257734)
    (descr "Capacitor SMD 0402")
    (tags "capacitor SMD 0402")
    (property "Author" "Antmicro")
    (property "DNP" "DNP")
    (property "Dielectric" "")
    (property "License" "Apache-2.0")
    (property "MPN" "GRM155R61A475MEAAD")
    (property "Manufacturer" "Murata")
    (property "Sheetfile" "ethernet-controller.kicad_sch")
    (property "Sheetname" "Ethernet Controller")
    (property "Val" "4u7")
    (property "Voltage" "")
    (attr exclude_from_pos_files)
    (fp_text reference "C9" (at 0.910826 0.362266) (layer "F.SilkS")
      (effects (font (size 0.7 0.7) (thickness 0.15)) (justify left bottom))
    )
    (fp_text value "C_4u7_0402" (at 0 1.4) (layer "F.Fab")
      (effects (font (size 0.7 0.7) (thickness 0.15)) (justify left bottom))
    )
    (fp_text user "${REFERENCE}" (at -0.932 3.168) (layer "F.Fab") hide
      (effects (font (size 0.7 0.7) (thickness 0.15)) (justify left bottom))
    )
    (fp_text user "License: Apache-2.0" (at -0.932 5.17) (layer "F.Fab") hide
      (effects (font (size 0.7 0.7) (thickness 0.15)) (justify left bottom))
    )
    (fp_text user "Author: Antmicro" (at -0.932 4.17) (layer "F.Fab") hide
      (effects (font (size 0.7 0.7) (thickness 0.15)) (justify left bottom))
    )
    (fp_rect (start -0.94 -0.47) (end 0.94 0.47) (layer "F.CrtYd") (width 0.05) (fill none))
    (fp_rect (start -0.499 -0.249) (end 0.499 0.249) (layer "F.Fab") (width 0.15) (fill none))
    (pad "1" smd roundrect (at -0.484 0) (size 0.59 0.64) (layers "F.Cu" "F.Paste" "F.Mask") (roundrect_rratio 0.25)
      (net 177 "/Ethernet Controller/ETH_3V3") (pintype "passive"))
    (pad "2" smd roundrect (at 0.484 0) (size 0.59 0.64) (layers "F.Cu" "F.Paste" "F.Mask") (roundrect_rratio 0.25)
      (net 1 "GND") (pintype "passive"))
  )

  (footprint "sa800u-baseboard-hw-footprints:R_0603_1608Metric" (layer "F.Cu")
    (tedit 5D5D3E92)
    (at 98.73 102.55 180)
    (descr "Resistor SMD 0603")
    (tags "resistor SMD 0603")
    (property "Author" "Antmicro")
    (property "License" "Apache-2.0")
    (property "MPN" "CR0603-FX-1502ELF")
    (property "Manufacturer" "Bourns")
    (property "Sheetfile" "ethernet-controller.kicad_sch")
    (property "Sheetname" "Ethernet Controller")
    (property "Tolerance" "1%")
    (property "Val" "15k")
    (attr smd)
    (fp_text reference "R10" (at 1.07 0.62 180) (layer "F.SilkS")
      (effects (font (size 0.7 0.7) (thickness 0.15)) (justify left bottom))
    )
    (fp_text value "R_15k_0603" (at 0 1.6 180) (layer "F.Fab")
      (effects (font (size 0.7 0.7) (thickness 0.15)) (justify left bottom))
    )
    (fp_text user "${REFERENCE}" (at -1.25 3.898 180) (layer "F.Fab") hide
      (effects (font (size 0.7 0.7) (thickness 0.15)) (justify left bottom))
    )
    (fp_text user "Author: Antmicro" (at -1.25 4.9 180) (layer "F.Fab") hide
      (effects (font (size 0.7 0.7) (thickness 0.15)) (justify left bottom))
    )
    (fp_text user "License: Apache-2.0" (at -1.25 5.9 180) (layer "F.Fab") hide
      (effects (font (size 0.7 0.7) (thickness 0.15)) (justify left bottom))
    )
    (fp_line (start -0.3 -0.3) (end 0.3 -0.3) (layer "F.SilkS") (width 0.15))
    (fp_line (start -0.3 0.3) (end 0.3 0.3) (layer "F.SilkS") (width 0.15))
    (fp_rect (start -1.25 -0.7) (end 1.25 0.7) (layer "F.CrtYd") (width 0.05) (fill none))
    (fp_rect (start -0.8 -0.4) (end 0.8 0.4) (layer "F.Fab") (width 0.15) (fill none))
    (pad "1" smd roundrect (at -0.7 0 180) (size 0.6 0.8) (layers "F.Cu" "F.Paste" "F.Mask") (roundrect_rratio 0.2)
      (net 286 "/Ethernet Controller/ETH_ISOLATEB") (pintype "passive"))
    (pad "2" smd roundrect (at 0.7 0 180) (size 0.6 0.8) (layers "F.Cu" "F.Paste" "F.Mask") (roundrect_rratio 0.2)
      (net 1 "GND") (pintype "passive"))
  )

  (footprint "sa800u-baseboard-hw-footprints:C_0402_1005Metric" (layer "F.Cu")
    (tedit 616D63CF)
    (at 99 103.8 180)
    (descr "Capacitor SMD 0402")
    (tags "capacitor SMD 0402")
    (property "Author" "Antmicro")
    (property "Dielectric" "X5R")
    (property "License" "Apache-2.0")
    (property "MPN" "GRM155R61H104KE14D")
    (property "Manufacturer" "Murata")
    (property "Sheetfile" "ethernet-controller.kicad_sch")
    (property "Sheetname" "Ethernet Controller")
    (property "Val" "100n")
    (property "Voltage" "50V")
    (attr smd)
    (fp_text reference "C12" (at 1.12 -1.24 180) (layer "F.SilkS")
      (effects (font (size 0.7 0.7) (thickness 0.15)) (justify left bottom))
    )
    (fp_text value "C_100n_0402" (at 0 1.4 180) (layer "F.Fab")
      (effects (font (size 0.7 0.7) (thickness 0.15)) (justify left bottom))
    )
    (fp_text user "License: Apache-2.0" (at -0.932 5.17 180) (layer "F.Fab") hide
      (effects (font (size 0.7 0.7) (thickness 0.15)) (justify left bottom))
    )
    (fp_text user "Author: Antmicro" (at -0.932 4.17 180) (layer "F.Fab") hide
      (effects (font (size 0.7 0.7) (thickness 0.15)) (justify left bottom))
    )
    (fp_text user "${REFERENCE}" (at -0.932 3.168 180) (layer "F.Fab") hide
      (effects (font (size 0.7 0.7) (thickness 0.15)) (justify left bottom))
    )
    (fp_rect (start -0.94 -0.47) (end 0.94 0.47) (layer "F.CrtYd") (width 0.05) (fill none))
    (fp_rect (start -0.499 -0.249) (end 0.499 0.249) (layer "F.Fab") (width 0.15) (fill none))
    (pad "1" smd roundrect (at -0.484 0 180) (size 0.59 0.64) (layers "F.Cu" "F.Paste" "F.Mask") (roundrect_rratio 0.25)
      (net 181 "/Ethernet Controller/ETH_1V0") (pintype "passive"))
    (pad "2" smd roundrect (at 0.484 0 180) (size 0.59 0.64) (layers "F.Cu" "F.Paste" "F.Mask") (roundrect_rratio 0.25)
      (net 1 "GND") (pintype "passive"))
  )

  (footprint "sa800u-baseboard-hw-footprints:C_0402_1005Metric" (layer "F.Cu")
    (tedit 616D63CF)
    (at 95.519764 103.700522)
    (descr "Capacitor SMD 0402")
    (tags "capacitor SMD 0402")
    (property "Author" "Antmicro")
    (property "Dielectric" "X5R")
    (property "License" "Apache-2.0")
    (property "MPN" "GRM155R61H104KE14D")
    (property "Manufacturer" "Murata")
    (property "Sheetfile" "ethernet-controller.kicad_sch")
    (property "Sheetname" "Ethernet Controller")
    (property "Val" "100n")
    (property "Voltage" "50V")
    (attr smd)
    (fp_text reference "C15" (at -3.059764 0.339478) (layer "F.SilkS")
      (effects (font (size 0.7 0.7) (thickness 0.15)) (justify left bottom))
    )
    (fp_text value "C_100n_0402" (at 0 1.4) (layer "F.Fab")
      (effects (font (size 0.7 0.7) (thickness 0.15)) (justify left bottom))
    )
    (fp_text user "License: Apache-2.0" (at -0.932 5.17) (layer "F.Fab") hide
      (effects (font (size 0.7 0.7) (thickness 0.15)) (justify left bottom))
    )
    (fp_text user "${REFERENCE}" (at -0.932 3.168) (layer "F.Fab") hide
      (effects (font (size 0.7 0.7) (thickness 0.15)) (justify left bottom))
    )
    (fp_text user "Author: Antmicro" (at -0.932 4.17) (layer "F.Fab") hide
      (effects (font (size 0.7 0.7) (thickness 0.15)) (justify left bottom))
    )
    (fp_rect (start -0.94 -0.47) (end 0.94 0.47) (layer "F.CrtYd") (width 0.05) (fill none))
    (fp_rect (start -0.499 -0.249) (end 0.499 0.249) (layer "F.Fab") (width 0.15) (fill none))
    (pad "1" smd roundrect (at -0.484 0) (size 0.59 0.64) (layers "F.Cu" "F.Paste" "F.Mask") (roundrect_rratio 0.25)
      (net 181 "/Ethernet Controller/ETH_1V0") (pintype "passive"))
    (pad "2" smd roundrect (at 0.484 0) (size 0.59 0.64) (layers "F.Cu" "F.Paste" "F.Mask") (roundrect_rratio 0.25)
      (net 1 "GND") (pintype "passive"))
  )

  (footprint "sa800u-baseboard-hw-footprints:C_0402_1005Metric" (layer "F.Cu")
    (tedit 616D63CF)
    (at 93.928774 105.432933 180)
    (descr "Capacitor SMD 0402")
    (tags "capacitor SMD 0402")
    (property "Author" "Antmicro")
    (property "DNP" "DNP")
    (property "Dielectric" "")
    (property "License" "Apache-2.0")
    (property "MPN" "GRM155R61A475MEAAD")
    (property "Manufacturer" "Murata")
    (property "Sheetfile" "ethernet-controller.kicad_sch")
    (property "Sheetname" "Ethernet Controller")
    (property "Val" "4u7")
    (property "Voltage" "")
    (attr exclude_from_pos_files)
    (fp_text reference "C8" (at 2.438774 -0.347067 180) (layer "F.SilkS")
      (effects (font (size 0.7 0.7) (thickness 0.15)) (justify left bottom))
    )
    (fp_text value "C_4u7_0402" (at 0 1.4 180) (layer "F.Fab")
      (effects (font (size 0.7 0.7) (thickness 0.15)) (justify left bottom))
    )
    (fp_text user "License: Apache-2.0" (at -0.932 5.17 180) (layer "F.Fab") hide
      (effects (font (size 0.7 0.7) (thickness 0.15)) (justify left bottom))
    )
    (fp_text user "${REFERENCE}" (at -0.932 3.168 180) (layer "F.Fab") hide
      (effects (font (size 0.7 0.7) (thickness 0.15)) (justify left bottom))
    )
    (fp_text user "Author: Antmicro" (at -0.932 4.17 180) (layer "F.Fab") hide
      (effects (font (size 0.7 0.7) (thickness 0.15)) (justify left bottom))
    )
    (fp_rect (start -0.94 -0.47) (end 0.94 0.47) (layer "F.CrtYd") (width 0.05) (fill none))
    (fp_rect (start -0.499 -0.249) (end 0.499 0.249) (layer "F.Fab") (width 0.15) (fill none))
    (pad "1" smd roundrect (at -0.484 0 180) (size 0.59 0.64) (layers "F.Cu" "F.Paste" "F.Mask") (roundrect_rratio 0.25)
      (net 177 "/Ethernet Controller/ETH_3V3") (pintype "passive"))
    (pad "2" smd roundrect (at 0.484 0 180) (size 0.59 0.64) (layers "F.Cu" "F.Paste" "F.Mask") (roundrect_rratio 0.25)
      (net 1 "GND") (pintype "passive"))
  )

  (footprint "sa800u-baseboard-hw-footprints:FB_0603_1608Metric" (layer "F.Cu")
    (tedit 618B9E9E)
    (at 101.31 101.72 180)
    (property "Author" "Antmicro")
    (property "License" "Apache-2.0")
    (property "MPN" "BLM18SG121TN1D")
    (property "Manufacturer" "Murata")
    (property "Sheetfile" "ethernet-controller.kicad_sch")
    (property "Sheetname" "Ethernet Controller")
    (attr smd)
    (fp_text reference "FB1" (at -1.23 -0.36 180) (layer "F.SilkS")
      (effects (font (size 0.7 0.7) (thickness 0.15)) (justify left bottom))
    )
    (fp_text value "FB_120Z_3A_0603" (at 0 1.5 180) (layer "F.Fab")
      (effects (font (size 0.7 0.7) (thickness 0.15)) (justify left bottom))
    )
    (fp_text user "License: Apache-2.0" (at -1.653 5.9 180) (layer "F.Fab") hide
      (effects (font (size 0.7 0.7) (thickness 0.15)) (justify left bottom))
    )
    (fp_text user "${REFERENCE}" (at -1.653 4.6 180) (layer "F.Fab") hide
      (effects (font (size 0.7 0.7) (thickness 0.15)) (justify left bottom))
    )
    (fp_text user "Author: Antmicro" (at -1.653 3.162 180) (layer "F.Fab") hide
      (effects (font (size 0.7 0.7) (thickness 0.15)) (justify left bottom))
    )
    (fp_line (start -0.196 -0.408) (end 0.193 -0.408) (layer "F.SilkS") (width 0.15))
    (fp_line (start -0.196 0.406) (end 0.193 0.406) (layer "F.SilkS") (width 0.15))
    (fp_rect (start -1.3 -0.6) (end 1.3 0.6) (layer "F.CrtYd") (width 0.05) (fill none))
    (fp_line (start 0.8 0.406) (end -0.803 0.406) (layer "F.Fab") (width 0.15))
    (fp_line (start -0.803 0.406) (end -0.803 -0.408) (layer "F.Fab") (width 0.15))
    (fp_line (start 0.8 -0.408) (end -0.803 -0.408) (layer "F.Fab") (width 0.15))
    (fp_line (start 0.8 -0.408) (end 0.8 0.406) (layer "F.Fab") (width 0.15))
    (pad "1" smd roundrect (at -0.891 0 180) (size 0.762 1.09) (layers "F.Cu" "F.Paste" "F.Mask") (roundrect_rratio 0.15)
      (net 131 "3V3_SYS") (pintype "passive"))
    (pad "2" smd roundrect (at 0.888 0 180) (size 0.762 1.09) (layers "F.Cu" "F.Paste" "F.Mask") (roundrect_rratio 0.15)
      (net 177 "/Ethernet Controller/ETH_3V3") (pintype "passive"))
  )

  (footprint "sa800u-baseboard-hw-footprints:C_0402_1005Metric" (layer "F.Cu")
    (tedit 616D63CF)
    (at 96 101.35 -90)
    (descr "Capacitor SMD 0402")
    (tags "capacitor SMD 0402")
    (property "Author" "Antmicro")
    (property "Dielectric" "X5R")
    (property "License" "Apache-2.0")
    (property "MPN" "GRM155R61H104KE14D")
    (property "Manufacturer" "Murata")
    (property "Sheetfile" "ethernet-controller.kicad_sch")
    (property "Sheetname" "Ethernet Controller")
    (property "Val" "100n")
    (property "Voltage" "50V")
    (attr smd)
    (fp_text reference "C3" (at -0.87 -0.38 -90) (layer "F.SilkS")
      (effects (font (size 0.7 0.7) (thickness 0.15)) (justify left bottom))
    )
    (fp_text value "C_100n_0402" (at 0 1.4 -90) (layer "F.Fab")
      (effects (font (size 0.7 0.7) (thickness 0.15)) (justify left bottom))
    )
    (fp_text user "License: Apache-2.0" (at -0.932 5.17 -90) (layer "F.Fab") hide
      (effects (font (size 0.7 0.7) (thickness 0.15)) (justify left bottom))
    )
    (fp_text user "${REFERENCE}" (at -0.932 3.168 -90) (layer "F.Fab") hide
      (effects (font (size 0.7 0.7) (thickness 0.15)) (justify left bottom))
    )
    (fp_text user "Author: Antmicro" (at -0.932 4.17 -90) (layer "F.Fab") hide
      (effects (font (size 0.7 0.7) (thickness 0.15)) (justify left bottom))
    )
    (fp_rect (start -0.94 -0.47) (end 0.94 0.47) (layer "F.CrtYd") (width 0.05) (fill none))
    (fp_rect (start -0.499 -0.249) (end 0.499 0.249) (layer "F.Fab") (width 0.15) (fill none))
    (pad "1" smd roundrect (at -0.484 0 270) (size 0.59 0.64) (layers "F.Cu" "F.Paste" "F.Mask") (roundrect_rratio 0.25)
      (net 177 "/Ethernet Controller/ETH_3V3") (pintype "passive"))
    (pad "2" smd roundrect (at 0.484 0 270) (size 0.59 0.64) (layers "F.Cu" "F.Paste" "F.Mask") (roundrect_rratio 0.25)
      (net 1 "GND") (pintype "passive"))
  )

  (footprint "sa800u-baseboard-hw-footprints:Nexperia_DFN-10_2.5x1mm_P0.5mm" (layer "F.Cu")
    (tedit 6215DC23)
    (at 115.35 138.7 180)
    (property "Author" "Antmicro")
    (property "License" "Apache-2.0")
    (property "MPN" "PUSB3F96X")
    (property "Manufacturer" "Nexperia")
    (property "Sheetfile" "usb-c-interface.kicad_sch")
    (property "Sheetname" "USB-C Interface ")
    (attr smd)
    (fp_text reference "D12" (at -2.33 -0.98 270) (layer "F.SilkS")
      (effects (font (size 0.7 0.7) (thickness 0.15)) (justify left bottom))
    )
    (fp_text value "PUSB3F96X_PASS" (at -0.016 1.705 180) (layer "F.Fab")
      (effects (font (size 0.7 0.7) (thickness 0.15)) (justify left bottom))
    )
    (fp_text user "${REFERENCE}" (at -1.367 3.704 180) (layer "F.Fab") hide
      (effects (font (size 0.7 0.7) (thickness 0.15)) (justify left bottom))
    )
    (fp_text user "Author: Antmicro" (at -1.367 4.905 180) (layer "F.Fab") hide
      (effects (font (size 0.7 0.7) (thickness 0.15)) (justify left bottom))
    )
    (fp_text user "License: Apache-2.0" (at -1.367 6.105 180) (layer "F.Fab") hide
      (effects (font (size 0.7 0.7) (thickness 0.15)) (justify left bottom))
    )
    (fp_line (start 1.233 0.405) (end 1.233 -0.396) (layer "F.SilkS") (width 0.15))
    (fp_line (start -1.266 -0.396) (end -1.266 0.405) (layer "F.SilkS") (width 0.15))
    (fp_circle (center -1.317 0.704) (end -1.266 0.704) (layer "F.SilkS") (width 0.15) (fill solid))
    (fp_rect (start -1.4 -0.7) (end 1.4 0.7) (layer "F.CrtYd") (width 0.05) (fill none))
    (pad "1" smd rect (at -1.016 0.392 180) (size 0.2 0.475) (layers "F.Cu" "F.Paste" "F.Mask")
      (net 79 "USB2C_HS_D_N") (pinfunction "CH1") (pintype "passive"))
    (pad "2" smd rect (at -0.517 0.392 180) (size 0.2 0.475) (layers "F.Cu" "F.Paste" "F.Mask")
      (net 80 "USB2C_HS_D_P") (pinfunction "CH2") (pintype "passive"))
    (pad "3" smd rect (at -0.016 0.392 180) (size 0.2 0.475) (layers "F.Cu" "F.Paste" "F.Mask")
      (net 1 "GND") (pinfunction "GND") (pintype "passive"))
    (pad "4" smd rect (at 0.482 0.392 180) (size 0.2 0.475) (layers "F.Cu" "F.Paste" "F.Mask")
      (net 370 "unconnected-(D12-Pad4)") (pinfunction "CH3") (pintype "passive+no_connect"))
    (pad "5" smd rect (at 0.982 0.392 180) (size 0.2 0.475) (layers "F.Cu" "F.Paste" "F.Mask")
      (net 412 "unconnected-(D12-Pad5)") (pinfunction "CH4") (pintype "passive+no_connect"))
    (pad "6" smd rect (at 0.982 -0.383) (size 0.2 0.475) (layers "F.Cu" "F.Paste" "F.Mask")
      (net 412 "unconnected-(D12-Pad5)") (pinfunction "CH4") (pintype "passive+no_connect"))
    (pad "7" smd rect (at 0.482 -0.383) (size 0.2 0.475) (layers "F.Cu" "F.Paste" "F.Mask")
      (net 370 "unconnected-(D12-Pad4)") (pinfunction "CH3") (pintype "passive+no_connect"))
    (pad "8" smd rect (at -0.016 -0.383) (size 0.2 0.475) (layers "F.Cu" "F.Paste" "F.Mask")
      (net 1 "GND") (pinfunction "GND") (pintype "passive"))
    (pad "9" smd rect (at -0.517 -0.383) (size 0.2 0.475) (layers "F.Cu" "F.Paste" "F.Mask")
      (net 80 "USB2C_HS_D_P") (pinfunction "CH2") (pintype "passive"))
    (pad "10" smd rect (at -1.016 -0.383) (size 0.2 0.475) (layers "F.Cu" "F.Paste" "F.Mask")
      (net 79 "USB2C_HS_D_N") (pinfunction "CH1") (pintype "passive"))
  )

  (footprint "sa800u-baseboard-hw-footprints:C_0402_1005Metric" (layer "F.Cu")
    (tedit 616D63CF)
    (at 85.55 99.85 90)
    (descr "Capacitor SMD 0402")
    (tags "capacitor SMD 0402")
    (property "Author" "Antmicro")
    (property "Dielectric" "X5R")
    (property "License" "Apache-2.0")
    (property "MPN" "GRM155R61H104KE14D")
    (property "Manufacturer" "Murata")
    (property "Sheetfile" "psu.kicad_sch")
    (property "Sheetname" "PSU")
    (property "Val" "100n")
    (property "Voltage" "50V")
    (attr smd)
    (fp_text reference "C132" (at -0.44 1.36 90) (layer "F.SilkS")
      (effects (font (size 0.7 0.7) (thickness 0.15)) (justify left bottom))
    )
    (fp_text value "C_100n_0402" (at 0 1.4 90) (layer "F.Fab")
      (effects (font (size 0.7 0.7) (thickness 0.15)) (justify left bottom))
    )
    (fp_text user "${REFERENCE}" (at -0.932 3.168 90) (layer "F.Fab") hide
      (effects (font (size 0.7 0.7) (thickness 0.15)) (justify left bottom))
    )
    (fp_text user "Author: Antmicro" (at -0.932 4.17 90) (layer "F.Fab") hide
      (effects (font (size 0.7 0.7) (thickness 0.15)) (justify left bottom))
    )
    (fp_text user "License: Apache-2.0" (at -0.932 5.17 90) (layer "F.Fab") hide
      (effects (font (size 0.7 0.7) (thickness 0.15)) (justify left bottom))
    )
    (fp_rect (start -0.94 -0.47) (end 0.94 0.47) (layer "F.CrtYd") (width 0.05) (fill none))
    (fp_rect (start -0.499 -0.249) (end 0.499 0.249) (layer "F.Fab") (width 0.15) (fill none))
    (pad "1" smd roundrect (at -0.484 0 90) (size 0.59 0.64) (layers "F.Cu" "F.Paste" "F.Mask") (roundrect_rratio 0.25)
      (net 356 "Net-(C132-Pad1)") (pintype "passive"))
    (pad "2" smd roundrect (at 0.484 0 90) (size 0.59 0.64) (layers "F.Cu" "F.Paste" "F.Mask") (roundrect_rratio 0.25)
      (net 357 "Net-(C132-Pad2)") (pintype "passive"))
  )

  (footprint "sa800u-baseboard-hw-footprints:R_0402_1005Metric" (layer "F.Cu")
    (tedit 5FD9C158)
    (at 83.45 101.8 90)
    (descr "Resistor SMD 0402")
    (tags "resistor SMD 0402")
    (property "Author" "Antmicro")
    (property "DNP" "")
    (property "License" "Apache-2.0")
    (property "MPN" "CR0402-FX-1002GLF")
    (property "Manufacturer" "Bourns")
    (property "Sheetfile" "psu.kicad_sch")
    (property "Sheetname" "PSU")
    (property "Tolerance" "1%")
    (property "Val" "10k")
    (attr smd)
    (fp_text reference "R131" (at -1.07 4 90) (layer "F.SilkS")
      (effects (font (size 0.7 0.7) (thickness 0.15)) (justify left bottom))
    )
    (fp_text value "R_10k_0402" (at 0 1.4 90) (layer "F.Fab")
      (effects (font (size 0.7 0.7) (thickness 0.15)) (justify left bottom))
    )
    (fp_text user "License: Apache-2.0" (at -0.95 5.169 90) (layer "F.Fab") hide
      (effects (font (size 0.7 0.7) (thickness 0.15)) (justify left bottom))
    )
    (fp_text user "${REFERENCE}" (at -0.95 3.168 90) (layer "F.Fab") hide
      (effects (font (size 0.7 0.7) (thickness 0.15)) (justify left bottom))
    )
    (fp_text user "Author: Antmicro" (at -0.95 4.169 90) (layer "F.Fab") hide
      (effects (font (size 0.7 0.7) (thickness 0.15)) (justify left bottom))
    )
    (fp_rect (start -0.93 -0.47) (end 0.93 0.47) (layer "F.CrtYd") (width 0.05) (fill none))
    (fp_rect (start -0.5 -0.25) (end 0.5 0.25) (layer "F.Fab") (width 0.15) (fill none))
    (pad "1" smd roundrect (at -0.485 0 90) (size 0.59 0.64) (layers "F.Cu" "F.Paste" "F.Mask") (roundrect_rratio 0.25)
      (net 74 "VDD") (pintype "passive"))
    (pad "2" smd roundrect (at 0.485 0 90) (size 0.59 0.64) (layers "F.Cu" "F.Paste" "F.Mask") (roundrect_rratio 0.25)
      (net 409 "Net-(R131-Pad2)") (pintype "passive"))
  )

  (footprint "sa800u-baseboard-hw-footprints:R_0402_1005Metric" (layer "F.Cu")
    (tedit 5FD9C158)
    (at 81.95 101.3)
    (descr "Resistor SMD 0402")
    (tags "resistor SMD 0402")
    (property "Author" "Antmicro")
    (property "License" "Apache-2.0")
    (property "MPN" "CR0402-FX-7502GLF")
    (property "Manufacturer" "Bourns")
    (property "Sheetfile" "psu.kicad_sch")
    (property "Sheetname" "PSU")
    (property "Tolerance" "1%")
    (property "Val" "75k")
    (attr smd)
    (fp_text reference "R135" (at 1.92 0.4) (layer "F.SilkS")
      (effects (font (size 0.7 0.7) (thickness 0.15)) (justify left bottom))
    )
    (fp_text value "R_75k_0402" (at 0 1.4) (layer "F.Fab")
      (effects (font (size 0.7 0.7) (thickness 0.15)) (justify left bottom))
    )
    (fp_text user "Author: Antmicro" (at -0.95 4.169) (layer "F.Fab") hide
      (effects (font (size 0.7 0.7) (thickness 0.15)) (justify left bottom))
    )
    (fp_text user "License: Apache-2.0" (at -0.95 5.169) (layer "F.Fab") hide
      (effects (font (size 0.7 0.7) (thickness 0.15)) (justify left bottom))
    )
    (fp_text user "${REFERENCE}" (at -0.95 3.168) (layer "F.Fab") hide
      (effects (font (size 0.7 0.7) (thickness 0.15)) (justify left bottom))
    )
    (fp_rect (start -0.93 -0.47) (end 0.93 0.47) (layer "F.CrtYd") (width 0.05) (fill none))
    (fp_rect (start -0.5 -0.25) (end 0.5 0.25) (layer "F.Fab") (width 0.15) (fill none))
    (pad "1" smd roundrect (at -0.485 0) (size 0.59 0.64) (layers "F.Cu" "F.Paste" "F.Mask") (roundrect_rratio 0.25)
      (net 137 "3V8_SYS") (pintype "passive"))
    (pad "2" smd roundrect (at 0.485 0) (size 0.59 0.64) (layers "F.Cu" "F.Paste" "F.Mask") (roundrect_rratio 0.25)
      (net 171 "Net-(R135-Pad2)") (pintype "passive"))
  )

  (footprint "sa800u-baseboard-hw-footprints:AP62301WU-7-TSOT23-6" (layer "F.Cu")
    (tedit 6215EA50)
    (at 83.15 98.75 180)
    (property "Author" "Antmicro")
    (property "License" "Apache-2.0")
    (property "MPN" "AP62301WU-7")
    (property "Manufacturer" "Diodes Incorporated")
    (property "Sheetfile" "psu.kicad_sch")
    (property "Sheetname" "PSU")
    (attr smd)
    (fp_text reference "U19" (at -2.59 1.94 90) (layer "F.SilkS")
      (effects (font (size 0.7 0.7) (thickness 0.15)) (justify right bottom))
    )
    (fp_text value "AP62301WU-7" (at -0.005 2.6) (layer "F.Fab")
      (effects (font (size 0.7 0.7) (thickness 0.15)) (justify right bottom))
    )
    (fp_text user "License: Apache-2.0" (at -1.893 4.967) (layer "F.Fab") hide
      (effects (font (size 0.7 0.7) (thickness 0.15)) (justify right bottom))
    )
    (fp_text user "${REFERENCE}" (at -1.893 6.168) (layer "F.Fab") hide
      (effects (font (size 0.7 0.7) (thickness 0.15)) (justify right bottom))
    )
    (fp_text user "Author: Antmicro" (at -1.893 7.368) (layer "F.Fab") hide
      (effects (font (size 0.7 0.7) (thickness 0.15)) (justify right bottom))
    )
    (fp_line (start -1.4805 0.725) (end -1.4795 -0.725) (layer "F.SilkS") (width 0.15))
    (fp_line (start 1.479 0.73) (end 1.38 0.73) (layer "F.SilkS") (width 0.15))
    (fp_line (start -1.4805 0.725) (end -1.3905 0.725) (layer "F.SilkS") (width 0.15))
    (fp_line (start 1.48 -0.72) (end 1.38 -0.72) (layer "F.SilkS") (width 0.15))
    (fp_line (start 1.48 -0.72) (end 1.479 0.73) (layer "F.SilkS") (width 0.15))
    (fp_line (start -1.4795 -0.725) (end -1.3905 -0.725) (layer "F.SilkS") (width 0.15))
    (fp_circle (center -1.499 1.236) (end -1.45 1.236) (layer "F.SilkS") (width 0.15) (fill solid))
    (fp_rect (start -1.65 -1.61) (end 1.65 1.61) (layer "F.CrtYd") (width 0.05) (fill none))
    (fp_line (start -1.527 -0.833) (end 1.523 -0.833) (layer "F.Fab") (width 0.15))
    (fp_line (start 1.523 -0.833) (end 1.523 0.916) (layer "F.Fab") (width 0.15))
    (fp_line (start -1.527 0.491) (end -1.102 0.916) (layer "F.Fab") (width 0.15))
    (fp_line (start -1.527 0.491) (end -1.527 -0.833) (layer "F.Fab") (width 0.15))
    (fp_line (start -1.102 0.916) (end 1.523 0.916) (layer "F.Fab") (width 0.15))
    (pad "1" smd rect (at -0.952 1.18 180) (size 0.7 0.8) (layers "F.Cu" "F.Paste" "F.Mask")
      (net 1 "GND") (pinfunction "GND") (pintype "power_in"))
    (pad "2" smd rect (at -0.001 1.18 180) (size 0.7 0.8) (layers "F.Cu" "F.Paste" "F.Mask")
      (net 357 "Net-(C132-Pad2)") (pinfunction "SW") (pintype "power_out"))
    (pad "3" smd rect (at 0.947 1.18 180) (size 0.7 0.8) (layers "F.Cu" "F.Paste" "F.Mask")
      (net 74 "VDD") (pinfunction "VIN") (pintype "power_in"))
    (pad "4" smd rect (at 0.947 -1.18 180) (size 0.7 0.8) (layers "F.Cu" "F.Paste" "F.Mask")
      (net 171 "Net-(R135-Pad2)") (pinfunction "FB") (pintype "input"))
    (pad "5" smd rect (at -0.001 -1.18 180) (size 0.7 0.8) (layers "F.Cu" "F.Paste" "F.Mask")
      (net 409 "Net-(R131-Pad2)") (pinfunction "EN") (pintype "input"))
    (pad "6" smd rect (at -0.952 -1.18 180) (size 0.7 0.8) (layers "F.Cu" "F.Paste" "F.Mask")
      (net 356 "Net-(C132-Pad1)") (pinfunction "BST") (pintype "output"))
  )

  (footprint "sa800u-baseboard-hw-footprints:R_0402_1005Metric" (layer "F.Cu")
    (tedit 5FD9C158)
    (at 81.95 102.3)
    (descr "Resistor SMD 0402")
    (tags "resistor SMD 0402")
    (property "Author" "Antmicro")
    (property "License" "Apache-2.0")
    (property "MPN" "CR0402-FX-2002GLF")
    (property "Manufacturer" "Bourns")
    (property "Sheetfile" "psu.kicad_sch")
    (property "Sheetname" "PSU")
    (property "Tolerance" "1%")
    (property "Val" "20k")
    (attr smd)
    (fp_text reference "R136" (at 1.92 0.4) (layer "F.SilkS")
      (effects (font (size 0.7 0.7) (thickness 0.15)) (justify left bottom))
    )
    (fp_text value "R_20k_0402" (at 0 1.4) (layer "F.Fab")
      (effects (font (size 0.7 0.7) (thickness 0.15)) (justify left bottom))
    )
    (fp_text user "Author: Antmicro" (at -0.95 4.169) (layer "F.Fab") hide
      (effects (font (size 0.7 0.7) (thickness 0.15)) (justify left bottom))
    )
    (fp_text user "${REFERENCE}" (at -0.95 3.168) (layer "F.Fab") hide
      (effects (font (size 0.7 0.7) (thickness 0.15)) (justify left bottom))
    )
    (fp_text user "License: Apache-2.0" (at -0.95 5.169) (layer "F.Fab") hide
      (effects (font (size 0.7 0.7) (thickness 0.15)) (justify left bottom))
    )
    (fp_rect (start -0.93 -0.47) (end 0.93 0.47) (layer "F.CrtYd") (width 0.05) (fill none))
    (fp_rect (start -0.5 -0.25) (end 0.5 0.25) (layer "F.Fab") (width 0.15) (fill none))
    (pad "1" smd roundrect (at -0.485 0) (size 0.59 0.64) (layers "F.Cu" "F.Paste" "F.Mask") (roundrect_rratio 0.25)
      (net 1 "GND") (pintype "passive"))
    (pad "2" smd roundrect (at 0.485 0) (size 0.59 0.64) (layers "F.Cu" "F.Paste" "F.Mask") (roundrect_rratio 0.25)
      (net 171 "Net-(R135-Pad2)") (pintype "passive"))
  )

  (footprint "sa800u-baseboard-hw-footprints:L_Coilcraft_XEL4030" (layer "F.Cu")
    (tedit 6215D867)
    (at 78.8 118.02)
    (property "Author" "Antmicro")
    (property "IMax" "")
    (property "ISat" "")
    (property "License" "Apache-2.0")
    (property "MPN" "XEL4030-222MEC")
    (property "Manufacturer" "Coilcraft")
    (property "MaxCur" "6.1A")
    (property "Sheetfile" "psu.kicad_sch")
    (property "Sheetname" "PSU")
    (property "Size" "4x4")
    (property "Val" "2u2/6.1A")
    (attr smd)
    (fp_text reference "L29" (at -0.83 3.13) (layer "F.SilkS")
      (effects (font (size 0.7 0.7) (thickness 0.15)) (justify left bottom))
    )
    (fp_text value "L_2u2_6.1A_XEL4030" (at 0 3.35) (layer "F.Fab")
      (effects (font (size 0.7 0.7) (thickness 0.15)) (justify left bottom))
    )
    (fp_text user "${REFERENCE}" (at -2.15 4.996) (layer "F.Fab") hide
      (effects (font (size 0.7 0.7) (thickness 0.15)) (justify left bottom))
    )
    (fp_text user "Author: Antmicro" (at -2.15 5.996) (layer "F.Fab") hide
      (effects (font (size 0.7 0.7) (thickness 0.15)) (justify left bottom))
    )
    (fp_text user "License: Apache-2.0" (at -2.15 6.996) (layer "F.Fab") hide
      (effects (font (size 0.7 0.7) (thickness 0.15)) (justify left bottom))
    )
    (fp_line (start -1.8 2.2) (end 1.85 2.199) (layer "F.SilkS") (width 0.15))
    (fp_line (start -1.8 -2.2) (end 1.85 -2.201) (layer "F.SilkS") (width 0.15))
    (fp_rect (start -2.45 -2.45) (end 2.45 2.45) (layer "F.CrtYd") (width 0.05) (fill none))
    (fp_line (start 1.999 -2) (end 1.999 1.999) (layer "F.Fab") (width 0.15))
    (fp_line (start 1.999 1.999) (end -2 1.999) (layer "F.Fab") (width 0.15))
    (fp_line (start -2 1.999) (end -2 -2) (layer "F.Fab") (width 0.15))
    (fp_line (start -2 -2) (end 1.999 -2) (layer "F.Fab") (width 0.15))
    (pad "1" smd rect (at -1.186 0) (size 0.98 3.4) (layers "F.Cu" "F.Paste" "F.Mask")
      (net 363 "Net-(C138-Pad2)") (pintype "passive"))
    (pad "2" smd rect (at 1.185 0) (size 0.98 3.4) (layers "F.Cu" "F.Paste" "F.Mask")
      (net 133 "5V_SYS") (pintype "passive"))
  )

  (footprint "sa800u-baseboard-hw-footprints:C_0603_1608Metric" (layer "F.Cu")
    (tedit 5D5E94D2)
    (at 77 114.86)
    (descr "Capacitor SMD 0603")
    (tags "capacitor 0603")
    (property "Author" "Antmicro")
    (property "Dielectric" "")
    (property "License" "Apache-2.0")
    (property "MPN" "C1608X5R1E106M080AC")
    (property "Manufacturer" "TDK")
    (property "Sheetfile" "psu.kicad_sch")
    (property "Sheetname" "PSU")
    (property "Val" "10u/25V")
    (property "Voltage" "")
    (attr smd)
    (fp_text reference "C131" (at 1.05 0.35) (layer "F.SilkS")
      (effects (font (size 0.7 0.7) (thickness 0.15)) (justify left bottom))
    )
    (fp_text value "C_10u_25V_0603" (at 0 1.6) (layer "F.Fab")
      (effects (font (size 0.7 0.7) (thickness 0.15)) (justify left bottom))
    )
    (fp_text user "Author: Antmicro" (at -1.682 4.894) (layer "F.Fab") hide
      (effects (font (size 0.7 0.7) (thickness 0.15)) (justify left bottom))
    )
    (fp_text user "${REFERENCE}" (at -1.682 3.895) (layer "F.Fab") hide
      (effects (font (size 0.7 0.7) (thickness 0.15)) (justify left bottom))
    )
    (fp_text user "License: Apache-2.0" (at -1.682 5.895) (layer "F.Fab") hide
      (effects (font (size 0.7 0.7) (thickness 0.15)) (justify left bottom))
    )
    (fp_line (start -0.3 -0.3) (end 0.3 -0.3) (layer "F.SilkS") (width 0.15))
    (fp_line (start -0.3 0.3) (end 0.3 0.3) (layer "F.SilkS") (width 0.15))
    (fp_rect (start -1.24 -0.7) (end 1.24 0.7) (layer "F.CrtYd") (width 0.05) (fill none))
    (fp_rect (start -0.8 -0.4) (end 0.8 0.4) (layer "F.Fab") (width 0.15) (fill none))
    (pad "1" smd roundrect (at -0.7 0) (size 0.6 0.8) (layers "F.Cu" "F.Paste" "F.Mask") (roundrect_rratio 0.2)
      (net 74 "VDD") (pintype "passive"))
    (pad "2" smd roundrect (at 0.7 0) (size 0.6 0.8) (layers "F.Cu" "F.Paste" "F.Mask") (roundrect_rratio 0.2)
      (net 1 "GND") (pintype "passive"))
  )

  (footprint "sa800u-baseboard-hw-footprints:C_0402_1005Metric" (layer "F.Cu")
    (tedit 616D63CF)
    (at 72 119.6 -90)
    (descr "Capacitor SMD 0402")
    (tags "capacitor SMD 0402")
    (property "Author" "Antmicro")
    (property "Dielectric" "X5R")
    (property "License" "Apache-2.0")
    (property "MPN" "GRM155R61H104KE14D")
    (property "Manufacturer" "Murata")
    (property "Sheetfile" "psu.kicad_sch")
    (property "Sheetname" "PSU")
    (property "Val" "100n")
    (property "Voltage" "50V")
    (attr smd)
    (fp_text reference "C138" (at 3.73 -0.42 -90) (layer "F.SilkS")
      (effects (font (size 0.7 0.7) (thickness 0.15)) (justify left bottom))
    )
    (fp_text value "C_100n_0402" (at 0 1.4 -90) (layer "F.Fab")
      (effects (font (size 0.7 0.7) (thickness 0.15)) (justify left bottom))
    )
    (fp_text user "${REFERENCE}" (at -0.932 3.168 -90) (layer "F.Fab") hide
      (effects (font (size 0.7 0.7) (thickness 0.15)) (justify left bottom))
    )
    (fp_text user "License: Apache-2.0" (at -0.932 5.17 -90) (layer "F.Fab") hide
      (effects (font (size 0.7 0.7) (thickness 0.15)) (justify left bottom))
    )
    (fp_text user "Author: Antmicro" (at -0.932 4.17 -90) (layer "F.Fab") hide
      (effects (font (size 0.7 0.7) (thickness 0.15)) (justify left bottom))
    )
    (fp_rect (start -0.94 -0.47) (end 0.94 0.47) (layer "F.CrtYd") (width 0.05) (fill none))
    (fp_rect (start -0.499 -0.249) (end 0.499 0.249) (layer "F.Fab") (width 0.15) (fill none))
    (pad "1" smd roundrect (at -0.484 0 270) (size 0.59 0.64) (layers "F.Cu" "F.Paste" "F.Mask") (roundrect_rratio 0.25)
      (net 362 "Net-(C138-Pad1)") (pintype "passive"))
    (pad "2" smd roundrect (at 0.484 0 270) (size 0.59 0.64) (layers "F.Cu" "F.Paste" "F.Mask") (roundrect_rratio 0.25)
      (net 363 "Net-(C138-Pad2)") (pintype "passive"))
  )

  (footprint "sa800u-baseboard-hw-footprints:C_0603_1608Metric" (layer "F.Cu")
    (tedit 5D5E94D2)
    (at 83.47 120.05 -90)
    (descr "Capacitor SMD 0603")
    (tags "capacitor 0603")
    (property "Author" "Antmicro")
    (property "Dielectric" "")
    (property "License" "Apache-2.0")
    (property "MPN" "GRM188R60J226MEA0D")
    (property "Manufacturer" "Murata")
    (property "Sheetfile" "psu.kicad_sch")
    (property "Sheetname" "PSU")
    (property "Val" "22u")
    (property "Voltage" "")
    (attr smd)
    (fp_text reference "C142" (at 1.29 -2.52 -90) (layer "F.SilkS")
      (effects (font (size 0.7 0.7) (thickness 0.15)) (justify left bottom))
    )
    (fp_text value "C_22u_0603" (at 0 1.6 -90) (layer "F.Fab")
      (effects (font (size 0.7 0.7) (thickness 0.15)) (justify left bottom))
    )
    (fp_text user "Author: Antmicro" (at -1.682 4.894 -90) (layer "F.Fab") hide
      (effects (font (size 0.7 0.7) (thickness 0.15)) (justify left bottom))
    )
    (fp_text user "License: Apache-2.0" (at -1.682 5.895 -90) (layer "F.Fab") hide
      (effects (font (size 0.7 0.7) (thickness 0.15)) (justify left bottom))
    )
    (fp_text user "${REFERENCE}" (at -1.682 3.895 -90) (layer "F.Fab") hide
      (effects (font (size 0.7 0.7) (thickness 0.15)) (justify left bottom))
    )
    (fp_line (start -0.3 -0.3) (end 0.3 -0.3) (layer "F.SilkS") (width 0.15))
    (fp_line (start -0.3 0.3) (end 0.3 0.3) (layer "F.SilkS") (width 0.15))
    (fp_rect (start -1.24 -0.7) (end 1.24 0.7) (layer "F.CrtYd") (width 0.05) (fill none))
    (fp_rect (start -0.8 -0.4) (end 0.8 0.4) (layer "F.Fab") (width 0.15) (fill none))
    (pad "1" smd roundrect (at -0.7 0 270) (size 0.6 0.8) (layers "F.Cu" "F.Paste" "F.Mask") (roundrect_rratio 0.2)
      (net 133 "5V_SYS") (pintype "passive"))
    (pad "2" smd roundrect (at 0.7 0 270) (size 0.6 0.8) (layers "F.Cu" "F.Paste" "F.Mask") (roundrect_rratio 0.2)
      (net 1 "GND") (pintype "passive"))
  )

  (footprint "sa800u-baseboard-hw-footprints:UQFN-12_2x1.7mm_P0.4mm_Texas_RUT" (layer "F.Cu")
    (tedit 5F354333)
    (at 110.3 138.1 -90)
    (descr "Texas_R_PUQFN-N12")
    (tags "Texas_R_PUQFN-N12")
    (property "Author" "Antmicro")
    (property "License" "Apache-2.0")
    (property "MPN" "TXB0104RUTR")
    (property "Manufacturer" "Texas Instruments")
    (property "Sheetfile" "usb-c-interface.kicad_sch")
    (property "Sheetname" "USB-C Interface ")
    (attr smd)
    (fp_text reference "U8" (at -1.26 0.8) (layer "F.SilkS")
      (effects (font (size 0.7 0.7) (thickness 0.15)) (justify left bottom))
    )
    (fp_text value "TXB0104_UQFN" (at 0 2.35 -90) (layer "F.Fab")
      (effects (font (size 0.7 0.7) (thickness 0.15)) (justify left bottom))
    )
    (fp_text user "Author: Antmicro" (at -1.1 4.35 -90) (layer "F.Fab") hide
      (effects (font (size 0.7 0.7) (thickness 0.15)) (justify left bottom))
    )
    (fp_text user "License: Apache-2.0" (at -1.1 6.75 -90) (layer "F.Fab") hide
      (effects (font (size 0.7 0.7) (thickness 0.15)) (justify left bottom))
    )
    (fp_text user "${REFERENCE}" (at -1.1 5.55 -90) (layer "F.Fab") hide
      (effects (font (size 0.7 0.7) (thickness 0.15)) (justify left bottom))
    )
    (fp_line (start 0.597 -1.301) (end -0.55 -1.301) (layer "F.SilkS") (width 0.15))
    (fp_line (start 0.497 1.3) (end -0.5 1.3) (layer "F.SilkS") (width 0.15))
    (fp_circle (center -0.85 -1.2) (end -0.8 -1.2) (layer "F.SilkS") (width 0.15) (fill solid))
    (fp_rect (start -1.1 -1.3) (end 1.1 1.3) (layer "F.CrtYd") (width 0.05) (fill none))
    (fp_line (start 0.847 -1) (end 0.847 0.997) (layer "F.Fab") (width 0.15))
    (fp_line (start -0.5 -1) (end -0.85 -0.5) (layer "F.Fab") (width 0.15))
    (fp_line (start -0.85 0.997) (end -0.85 -0.5) (layer "F.Fab") (width 0.15))
    (fp_line (start -0.5 -1) (end 0.847 -1) (layer "F.Fab") (width 0.15))
    (fp_line (start 0.847 0.997) (end -0.85 0.997) (layer "F.Fab") (width 0.15))
    (pad "1" smd rect (at -0.653 -0.803 180) (size 0.2 0.6) (layers "F.Cu" "F.Paste" "F.Mask")
      (net 134 "1V8_SYS") (pinfunction "VCCA") (pintype "power_in"))
    (pad "1" smd rect (at -0.425 -0.975 270) (size 0.15 0.25) (layers "F.Cu" "F.Paste" "F.Mask")
      (net 134 "1V8_SYS") (pinfunction "VCCA") (pintype "power_in"))
    (pad "2" smd rect (at -0.653 -0.403 180) (size 0.2 0.6) (layers "F.Cu" "F.Paste" "F.Mask")
      (net 99 "USB2_SINK") (pinfunction "A1") (pintype "tri_state"))
    (pad "3" smd rect (at -0.653 0 180) (size 0.2 0.6) (layers "F.Cu" "F.Paste" "F.Mask")
      (net 100 "USB2_FAULT") (pinfunction "A2") (pintype "tri_state"))
    (pad "4" smd rect (at -0.653 0.4 180) (size 0.2 0.6) (layers "F.Cu" "F.Paste" "F.Mask")
      (net 101 "USB2_EN") (pinfunction "A3") (pintype "tri_state"))
    (pad "5" smd rect (at -0.653 0.8 180) (size 0.2 0.6) (layers "F.Cu" "F.Paste" "F.Mask")
      (net 506 "unconnected-(U8-Pad5)") (pinfunction "A4") (pintype "tri_state+no_connect"))
    (pad "6" smd rect (at 0 0.8 180) (size 0.6 0.2) (layers "F.Cu" "F.Paste" "F.Mask")
      (net 1 "GND") (pinfunction "GND") (pintype "power_in"))
    (pad "7" smd rect (at 0.65 0.8 180) (size 0.2 0.6) (layers "F.Cu" "F.Paste" "F.Mask")
      (net 505 "unconnected-(U8-Pad7)") (pinfunction "B4") (pintype "tri_state+no_connect"))
    (pad "8" smd rect (at 0.65 0.4 180) (size 0.2 0.6) (layers "F.Cu" "F.Paste" "F.Mask")
      (net 301 "/USB-C Interface /USB2_EN_5V") (pinfunction "B3") (pintype "tri_state"))
    (pad "9" smd rect (at 0.65 0 180) (size 0.2 0.6) (layers "F.Cu" "F.Paste" "F.Mask")
      (net 292 "/USB-C Interface /USB2_FAULT_5V") (pinfunction "B2") (pintype "tri_state"))
    (pad "10" smd rect (at 0.65 -0.403 180) (size 0.2 0.6) (layers "F.Cu" "F.Paste" "F.Mask")
      (net 291 "/USB-C Interface /USB2_SINK_5V") (pinfunction "B1") (pintype "tri_state"))
    (pad "11" smd rect (at 0.65 -0.803 180) (size 0.2 0.6) (layers "F.Cu" "F.Paste" "F.Mask")
      (net 133 "5V_SYS") (pinfunction "VCCB") (pintype "power_in"))
    (pad "12" smd rect (at 0 -0.803 180) (size 0.6 0.2) (layers "F.Cu" "F.Paste" "F.Mask")
      (net 134 "1V8_SYS") (pinfunction "OE") (pintype "input"))
  )

  (footprint "sa800u-baseboard-hw-footprints:AP62301WU-7-TSOT23-6" (layer "F.Cu")
    (tedit 6215EA50)
    (at 74.59 117.65 90)
    (property "Author" "Antmicro")
    (property "License" "Apache-2.0")
    (property "MPN" "AP62301WU-7")
    (property "Manufacturer" "Diodes Incorporated")
    (property "Sheetfile" "psu.kicad_sch")
    (property "Sheetname" "PSU")
    (attr smd)
    (fp_text reference "U22" (at 1.62 -0.18 180) (layer "F.SilkS")
      (effects (font (size 0.7 0.7) (thickness 0.15)) (justify left bottom))
    )
    (fp_text value "AP62301WU-7" (at -0.005 2.6 90) (layer "F.Fab")
      (effects (font (size 0.7 0.7) (thickness 0.15)) (justify left bottom))
    )
    (fp_text user "Author: Antmicro" (at -1.893 7.368 90) (layer "F.Fab") hide
      (effects (font (size 0.7 0.7) (thickness 0.15)) (justify left bottom))
    )
    (fp_text user "License: Apache-2.0" (at -1.893 4.967 90) (layer "F.Fab") hide
      (effects (font (size 0.7 0.7) (thickness 0.15)) (justify left bottom))
    )
    (fp_text user "${REFERENCE}" (at -1.893 6.168 90) (layer "F.Fab") hide
      (effects (font (size 0.7 0.7) (thickness 0.15)) (justify left bottom))
    )
    (fp_line (start 1.48 -0.72) (end 1.479 0.73) (layer "F.SilkS") (width 0.15))
    (fp_line (start 1.48 -0.72) (end 1.38 -0.72) (layer "F.SilkS") (width 0.15))
    (fp_line (start -1.4805 0.725) (end -1.3905 0.725) (layer "F.SilkS") (width 0.15))
    (fp_line (start 1.479 0.73) (end 1.38 0.73) (layer "F.SilkS") (width 0.15))
    (fp_line (start -1.4795 -0.725) (end -1.3905 -0.725) (layer "F.SilkS") (width 0.15))
    (fp_line (start -1.4805 0.725) (end -1.4795 -0.725) (layer "F.SilkS") (width 0.15))
    (fp_circle (center -1.499 1.236) (end -1.45 1.236) (layer "F.SilkS") (width 0.15) (fill solid))
    (fp_rect (start -1.65 -1.61) (end 1.65 1.61) (layer "F.CrtYd") (width 0.05) (fill none))
    (fp_line (start -1.102 0.916) (end 1.523 0.916) (layer "F.Fab") (width 0.15))
    (fp_line (start 1.523 -0.833) (end 1.523 0.916) (layer "F.Fab") (width 0.15))
    (fp_line (start -1.527 0.491) (end -1.527 -0.833) (layer "F.Fab") (width 0.15))
    (fp_line (start -1.527 -0.833) (end 1.523 -0.833) (layer "F.Fab") (width 0.15))
    (fp_line (start -1.527 0.491) (end -1.102 0.916) (layer "F.Fab") (width 0.15))
    (pad "1" smd rect (at -0.952 1.18 90) (size 0.7 0.8) (layers "F.Cu" "F.Paste" "F.Mask")
      (net 1 "GND") (pinfunction "GND") (pintype "power_in"))
    (pad "2" smd rect (at -0.001 1.18 90) (size 0.7 0.8) (layers "F.Cu" "F.Paste" "F.Mask")
      (net 363 "Net-(C138-Pad2)") (pinfunction "SW") (pintype "power_out"))
    (pad "3" smd rect (at 0.947 1.18 90) (size 0.7 0.8) (layers "F.Cu" "F.Paste" "F.Mask")
      (net 74 "VDD") (pinfunction "VIN") (pintype "power_in"))
    (pad "4" smd rect (at 0.947 -1.18 90) (size 0.7 0.8) (layers "F.Cu" "F.Paste" "F.Mask")
      (net 173 "Net-(R141-Pad2)") (pinfunction "FB") (pintype "input"))
    (pad "5" smd rect (at -0.001 -1.18 90) (size 0.7 0.8) (layers "F.Cu" "F.Paste" "F.Mask")
      (net 164 "/PSU/5V_DC_DC_ENABLE") (pinfunction "EN") (pintype "input"))
    (pad "6" smd rect (at -0.952 -1.18 90) (size 0.7 0.8) (layers "F.Cu" "F.Paste" "F.Mask")
      (net 362 "Net-(C138-Pad1)") (pinfunction "BST") (pintype "output"))
  )

  (footprint "sa800u-baseboard-hw-footprints:USB-C_12401610E4_2A" locked (layer "F.Cu")
    (tedit 6215EC4A)
    (at 115.75 147.95)
    (property "Author" "Antmicro")
    (property "License" "Apache-2.0")
    (property "MPN" "12401598E4#2A")
    (property "Manufacturer" "Amphenol")
    (property "Sheetfile" "usb-c-interface.kicad_sch")
    (property "Sheetname" "USB-C Interface ")
    (attr smd)
    (fp_text reference "J4" (at 3.27 -5.58) (layer "F.SilkS")
      (effects (font (size 0.7 0.7) (thickness 0.15)) (justify left bottom))
    )
    (fp_text value "12401598E4_2A" (at 0 6.549) (layer "F.Fab")
      (effects (font (size 0.7 0.7) (thickness 0.15)) (justify left bottom))
    )
    (fp_text user "License: Apache-2.0" (at -4.901 10.948) (layer "F.Fab") hide
      (effects (font (size 0.7 0.7) (thickness 0.15)) (justify left bottom))
    )
    (fp_text user "${REFERENCE}" (at -4.901 8.55) (layer "F.Fab") hide
      (effects (font (size 0.7 0.7) (thickness 0.15)) (justify left bottom))
    )
    (fp_text user "Author: Antmicro" (at -4.901 9.749) (layer "F.Fab") hide
      (effects (font (size 0.7 0.7) (thickness 0.15)) (justify left bottom))
    )
    (fp_line (start -4.601 5.448) (end -4.601 4.948) (layer "F.SilkS") (width 0.15))
    (fp_line (start 4.599 -5.25) (end 4.599 -4.75) (layer "F.SilkS") (width 0.15))
    (fp_line (start -4.601 -5.25) (end -4.1 -5.25) (layer "F.SilkS") (width 0.15))
    (fp_line (start 4.599 5.448) (end 4.599 4.948) (layer "F.SilkS") (width 0.15))
    (fp_line (start 4.599 -5.25) (end 4.099 -5.25) (layer "F.SilkS") (width 0.15))
    (fp_line (start 4.599 5.448) (end 4.099 5.448) (layer "F.SilkS") (width 0.15))
    (fp_line (start -4.601 5.448) (end -4.1 5.448) (layer "F.SilkS") (width 0.15))
    (fp_line (start -4.601 -5.25) (end -4.601 -4.75) (layer "F.SilkS") (width 0.15))
    (fp_circle (center -3.101 -5.25) (end -3.052 -5.25) (layer "F.SilkS") (width 0.15) (fill solid))
    (fp_rect (start -4.92 -5.46) (end 4.9 5.44) (layer "F.CrtYd") (width 0.05) (fill none))
    (fp_line (start -4.491 5.339) (end 4.49 5.339) (layer "F.Fab") (width 0.15))
    (fp_line (start -4.491 -5.162) (end 4.49 -5.162) (layer "F.Fab") (width 0.15))
    (fp_line (start -4.491 -5.162) (end -4.491 5.339) (layer "F.Fab") (width 0.15))
    (fp_line (start 4.49 -5.162) (end 4.49 5.339) (layer "F.Fab") (width 0.15))
    (pad "" np_thru_hole circle locked (at -3.601 -4.25) (size 0.65 0.65) (drill 0.65) (layers *.Cu *.Mask))
    (pad "" np_thru_hole oval locked (at 3.6 -4.25) (size 0.95 0.65) (drill oval 0.95 0.65) (layers *.Cu *.Mask))
    (pad "A1" smd rect locked (at -2.75 -4.912) (size 0.3 0.7) (layers "F.Cu" "F.Paste" "F.Mask")
      (net 1 "GND") (pintype "passive"))
    (pad "A2" smd rect locked (at -2.25 -4.912) (size 0.3 0.7) (layers "F.Cu" "F.Paste" "F.Mask")
      (net 215 "/USB-C Interface /USB2C_TX1_C_P") (pintype "passive"))
    (pad "A3" smd rect locked (at -1.75 -4.912) (size 0.3 0.7) (layers "F.Cu" "F.Paste" "F.Mask")
      (net 211 "/USB-C Interface /USB2C_TX1_C_N") (pintype "passive"))
    (pad "A4" smd rect locked (at -1.25 -4.912) (size 0.3 0.7) (layers "F.Cu" "F.Paste" "F.Mask")
      (net 210 "/USB-C Interface /USB2_5V") (pintype "passive"))
    (pad "A5" smd rect locked (at -0.75 -4.912) (size 0.3 0.7) (layers "F.Cu" "F.Paste" "F.Mask")
      (net 265 "/USB-C Interface /USB2_CC1") (pintype "passive"))
    (pad "A6" smd rect locked (at -0.25 -4.912) (size 0.3 0.7) (layers "F.Cu" "F.Paste" "F.Mask")
      (net 80 "USB2C_HS_D_P") (pintype "passive"))
    (pad "A7" smd rect locked (at 0.247 -4.912) (size 0.3 0.7) (layers "F.Cu" "F.Paste" "F.Mask")
      (net 79 "USB2C_HS_D_N") (pintype "passive"))
    (pad "A8" smd rect locked (at 0.747 -4.912) (size 0.3 0.7) (layers "F.Cu" "F.Paste" "F.Mask")
      (net 426 "unconnected-(J4-PadA8)") (pintype "passive+no_connect"))
    (pad "A9" smd rect locked (at 1.249 -4.912) (size 0.3 0.7) (layers "F.Cu" "F.Paste" "F.Mask")
      (net 210 "/USB-C Interface /USB2_5V") (pintype "passive"))
    (pad "A10" smd rect locked (at 1.749 -4.912) (size 0.3 0.7) (layers "F.Cu" "F.Paste" "F.Mask")
      (net 217 "/USB-C Interface /USB2C_RX2_C_N") (pintype "passive"))
    (pad "A11" smd rect locked (at 2.249 -4.912) (size 0.3 0.7) (layers "F.Cu" "F.Paste" "F.Mask")
      (net 213 "/USB-C Interface /USB2C_RX2_C_P") (pintype "passive"))
    (pad "A12" smd rect locked (at 2.749 -4.912) (size 0.3 0.7) (layers "F.Cu" "F.Paste" "F.Mask")
      (net 1 "GND") (pintype "passive"))
    (pad "B1" smd rect locked (at 2.499 -3.21) (size 0.3 0.7) (layers "F.Cu" "F.Paste" "F.Mask")
      (net 1 "GND") (pintype "passive"))
    (pad "B2" smd rect locked (at 1.999 -3.21) (size 0.3 0.7) (layers "F.Cu" "F.Paste" "F.Mask")
      (net 222 "/USB-C Interface /USB2C_TX2_C_P") (pintype "passive"))
    (pad "B3" smd rect locked (at 1.499 -3.21) (size 0.3 0.7) (layers "F.Cu" "F.Paste" "F.Mask")
      (net 226 "/USB-C Interface /USB2C_TX2_C_N") (pintype "passive"))
    (pad "B4" smd rect locked (at 0.997 -3.21) (size 0.3 0.7) (layers "F.Cu" "F.Paste" "F.Mask")
      (net 210 "/USB-C Interface /USB2_5V") (pintype "passive"))
    (pad "B5" smd rect locked (at 0.497 -3.21) (size 0.3 0.7) (layers "F.Cu" "F.Paste" "F.Mask")
      (net 264 "/USB-C Interface /USB2_CC2") (pintype "passive"))
    (pad "B6" smd rect locked (at 0 -3.21) (size 0.3 0.7) (layers "F.Cu" "F.Paste" "F.Mask")
      (net 80 "USB2C_HS_D_P") (pintype "passive"))
    (pad "B7" smd rect locked (at -0.5 -3.21) (size 0.3 0.7) (layers "F.Cu" "F.Paste" "F.Mask")
      (net 79 "USB2C_HS_D_N") (pintype "passive"))
    (pad "B8" smd rect locked (at -1 -3.21) (size 0.3 0.7) (layers "F.Cu" "F.Paste" "F.Mask")
      (net 425 "unconnected-(J4-PadB8)") (pintype "passive+no_connect"))
    (pad "B9" smd rect locked (at -1.5 -3.21) (size 0.3 0.7) (layers "F.Cu" "F.Paste" "F.Mask")
      (net 210 "/USB-C Interface /USB2_5V") (pintype "passive"))
    (pad "B10" smd rect locked (at -2 -3.21) (size 0.3 0.7) (layers "F.Cu" "F.Paste" "F.Mask")
      (net 220 "/USB-C Interface /USB2C_RX1_C_N") (pintype "passive"))
    (pad "B11" smd rect locked (at -2.5 -3.21) (size 0.3 0.7) (layers "F.Cu" "F.Paste" "F.Mask")
      (net 224 "/USB-C Interface /USB2C_RX1_C_P") (pintype "passive"))
    (pad "B12" smd rect locked (at -3 -3.21) (size 0.3 0.7) (layers "F.Cu" "F.Paste" "F.Mask")
      (net 1 "GND") (pintype "passive"))
    (pad "SH" thru_hole oval locked (at 4.49 2.95) (size 0.85 1.45) (drill oval 0.5 1.1) (layers *.Cu *.Mask)
      (net 1 "GND") (pintype "input"))
    (pad "SH" thru_hole oval locked (at 4.128 -3.001) (size 0.85 1.45) (drill oval 0.5 1.1) (layers *.Cu *.Mask)
      (net 1 "GND") (pintype "input"))
    (pad "SH" thru_hole oval locked (at -4.491 2.95) (size 0.85 1.45) (drill oval 0.5 1.1) (layers *.Cu *.Mask)
      (net 1 "GND") (pintype "input"))
    (pad "SH" thru_hole oval locked (at -4.13 -3.001) (size 0.85 1.45) (drill oval 0.5 1.1) (layers *.Cu *.Mask)
      (net 1 "GND") (pintype "input"))
  )

  (footprint "sa800u-baseboard-hw-footprints:USB-C_12401610E4_2A" (layer "F.Cu")
    (tedit 6215EC4A)
    (at 101.75 147.95)
    (property "Author" "Antmicro")
    (property "License" "Apache-2.0")
    (property "MPN" "12401598E4#2A")
    (property "Manufacturer" "Amphenol")
    (property "Sheetfile" "usb-c-interface.kicad_sch")
    (property "Sheetname" "USB-C Interface ")
    (attr smd)
    (fp_text reference "J3" (at 3.45 -5.62) (layer "F.SilkS")
      (effects (font (size 0.7 0.7) (thickness 0.15)) (justify left bottom))
    )
    (fp_text value "12401598E4_2A" (at 0 6.549) (layer "F.Fab")
      (effects (font (size 0.7 0.7) (thickness 0.15)) (justify left bottom))
    )
    (fp_text user "Author: Antmicro" (at -4.901 9.749) (layer "F.Fab") hide
      (effects (font (size 0.7 0.7) (thickness 0.15)) (justify left bottom))
    )
    (fp_text user "License: Apache-2.0" (at -4.901 10.948) (layer "F.Fab") hide
      (effects (font (size 0.7 0.7) (thickness 0.15)) (justify left bottom))
    )
    (fp_text user "${REFERENCE}" (at -4.901 8.55) (layer "F.Fab") hide
      (effects (font (size 0.7 0.7) (thickness 0.15)) (justify left bottom))
    )
    (fp_line (start 4.599 5.448) (end 4.099 5.448) (layer "F.SilkS") (width 0.15))
    (fp_line (start 4.599 -5.25) (end 4.599 -4.75) (layer "F.SilkS") (width 0.15))
    (fp_line (start -4.601 5.448) (end -4.601 4.948) (layer "F.SilkS") (width 0.15))
    (fp_line (start -4.601 -5.25) (end -4.1 -5.25) (layer "F.SilkS") (width 0.15))
    (fp_line (start -4.601 -5.25) (end -4.601 -4.75) (layer "F.SilkS") (width 0.15))
    (fp_line (start 4.599 -5.25) (end 4.099 -5.25) (layer "F.SilkS") (width 0.15))
    (fp_line (start -4.601 5.448) (end -4.1 5.448) (layer "F.SilkS") (width 0.15))
    (fp_line (start 4.599 5.448) (end 4.599 4.948) (layer "F.SilkS") (width 0.15))
    (fp_circle (center -3.101 -5.25) (end -3.052 -5.25) (layer "F.SilkS") (width 0.15) (fill solid))
    (fp_rect (start -4.92 -5.46) (end 4.9 5.44) (layer "F.CrtYd") (width 0.05) (fill none))
    (fp_line (start -4.491 5.339) (end 4.49 5.339) (layer "F.Fab") (width 0.15))
    (fp_line (start -4.491 -5.162) (end 4.49 -5.162) (layer "F.Fab") (width 0.15))
    (fp_line (start -4.491 -5.162) (end -4.491 5.339) (layer "F.Fab") (width 0.15))
    (fp_line (start 4.49 -5.162) (end 4.49 5.339) (layer "F.Fab") (width 0.15))
    (pad "" np_thru_hole circle (at -3.601 -4.25) (size 0.65 0.65) (drill 0.65) (layers *.Cu *.Mask))
    (pad "" np_thru_hole oval (at 3.6 -4.25) (size 0.95 0.65) (drill oval 0.95 0.65) (layers *.Cu *.Mask))
    (pad "A1" smd rect (at -2.75 -4.912) (size 0.3 0.7) (layers "F.Cu" "F.Paste" "F.Mask")
      (net 1 "GND") (pintype "passive"))
    (pad "A2" smd rect (at -2.25 -4.912) (size 0.3 0.7) (layers "F.Cu" "F.Paste" "F.Mask")
      (net 302 "/USB-C Interface /USB1C_TX0_C_P") (pintype "passive"))
    (pad "A3" smd rect (at -1.75 -4.912) (size 0.3 0.7) (layers "F.Cu" "F.Paste" "F.Mask")
      (net 303 "/USB-C Interface /USB1C_TX0_C_N") (pintype "passive"))
    (pad "A4" smd rect (at -1.25 -4.912) (size 0.3 0.7) (layers "F.Cu" "F.Paste" "F.Mask")
      (net 66 "USB_VBUS") (pintype "passive"))
    (pad "A5" smd rect (at -0.75 -4.912) (size 0.3 0.7) (layers "F.Cu" "F.Paste" "F.Mask")
      (net 326 "USB_CC1") (pintype "passive"))
    (pad "A6" smd rect (at -0.25 -4.912) (size 0.3 0.7) (layers "F.Cu" "F.Paste" "F.Mask")
      (net 321 "USB1_D_P") (pintype "passive"))
    (pad "A7" smd rect (at 0.247 -4.912) (size 0.3 0.7) (layers "F.Cu" "F.Paste" "F.Mask")
      (net 322 "USB1_D_N") (pintype "passive"))
    (pad "A8" smd rect (at 0.747 -4.912) (size 0.3 0.7) (layers "F.Cu" "F.Paste" "F.Mask")
      (net 330 "/USB-C Interface /USB1_SBU_N") (pintype "passive"))
    (pad "A9" smd rect (at 1.249 -4.912) (size 0.3 0.7) (layers "F.Cu" "F.Paste" "F.Mask")
      (net 66 "USB_VBUS") (pintype "passive"))
    (pad "A10" smd rect (at 1.749 -4.912) (size 0.3 0.7) (layers "F.Cu" "F.Paste" "F.Mask")
      (net 304 "/USB-C Interface /USB1C_RX1_C_N") (pintype "passive"))
    (pad "A11" smd rect (at 2.249 -4.912) (size 0.3 0.7) (layers "F.Cu" "F.Paste" "F.Mask")
      (net 305 "/USB-C Interface /USB1C_RX1_C_P") (pintype "passive"))
    (pad "A12" smd rect (at 2.749 -4.912) (size 0.3 0.7) (layers "F.Cu" "F.Paste" "F.Mask")
      (net 1 "GND") (pintype "passive"))
    (pad "B1" smd rect (at 2.499 -3.21) (size 0.3 0.7) (layers "F.Cu" "F.Paste" "F.Mask")
      (net 1 "GND") (pintype "passive"))
    (pad "B2" smd rect (at 1.999 -3.21) (size 0.3 0.7) (layers "F.Cu" "F.Paste" "F.Mask")
      (net 307 "/USB-C Interface /USB1C_TX1_C_P") (pintype "passive"))
    (pad "B3" smd rect (at 1.499 -3.21) (size 0.3 0.7) (layers "F.Cu" "F.Paste" "F.Mask")
      (net 306 "/USB-C Interface /USB1C_TX1_C_N") (pintype "passive"))
    (pad "B4" smd rect (at 0.997 -3.21) (size 0.3 0.7) (layers "F.Cu" "F.Paste" "F.Mask")
      (net 66 "USB_VBUS") (pintype "passive"))
    (pad "B5" smd rect (at 0.497 -3.21) (size 0.3 0.7) (layers "F.Cu" "F.Paste" "F.Mask")
      (net 327 "USB_CC2") (pintype "passive"))
    (pad "B6" smd rect (at 0 -3.21) (size 0.3 0.7) (layers "F.Cu" "F.Paste" "F.Mask")
      (net 321 "USB1_D_P") (pintype "passive"))
    (pad "B7" smd rect (at -0.5 -3.21) (size 0.3 0.7) (layers "F.Cu" "F.Paste" "F.Mask")
      (net 322 "USB1_D_N") (pintype "passive"))
    (pad "B8" smd rect (at -1 -3.21) (size 0.3 0.7) (layers "F.Cu" "F.Paste" "F.Mask")
      (net 331 "/USB-C Interface /USB1_SBU_P") (pintype "passive"))
    (pad "B9" smd rect (at -1.5 -3.21) (size 0.3 0.7) (layers "F.Cu" "F.Paste" "F.Mask")
      (net 66 "USB_VBUS") (pintype "passive"))
    (pad "B10" smd rect (at -2 -3.21) (size 0.3 0.7) (layers "F.Cu" "F.Paste" "F.Mask")
      (net 323 "/USB-C Interface /USB1C_RX0_C_N") (pintype "passive"))
    (pad "B11" smd rect (at -2.5 -3.21) (size 0.3 0.7) (layers "F.Cu" "F.Paste" "F.Mask")
      (net 308 "/USB-C Interface /USB1C_RX0_C_P") (pintype "passive"))
    (pad "B12" smd rect (at -3 -3.21) (size 0.3 0.7) (layers "F.Cu" "F.Paste" "F.Mask")
      (net 1 "GND") (pintype "passive"))
    (pad "SH" thru_hole oval (at 4.49 2.95) (size 0.85 1.45) (drill oval 0.5 1.1) (layers *.Cu *.Mask)
      (net 1 "GND") (pintype "input"))
    (pad "SH" thru_hole oval (at -4.491 2.95) (size 0.85 1.45) (drill oval 0.5 1.1) (layers *.Cu *.Mask)
      (net 1 "GND") (pintype "input"))
    (pad "SH" thru_hole oval (at 4.128 -3.001) (size 0.85 1.45) (drill oval 0.5 1.1) (layers *.Cu *.Mask)
      (net 1 "GND") (pintype "input"))
    (pad "SH" thru_hole oval (at -4.13 -3.001) (size 0.85 1.45) (drill oval 0.5 1.1) (layers *.Cu *.Mask)
      (net 1 "GND") (pintype "input"))
  )

  (footprint "sa800u-baseboard-hw-footprints:C_0402_1005Metric" (layer "F.Cu")
    (tedit 616D63CF)
    (at 132.9 138.9)
    (descr "Capacitor SMD 0402")
    (tags "capacitor SMD 0402")
    (property "Author" "Antmicro")
    (property "Dielectric" "X5R")
    (property "License" "Apache-2.0")
    (property "MPN" "GRM155R61H104KE14D")
    (property "Manufacturer" "Murata")
    (property "Sheetfile" "usb-c-interface.kicad_sch")
    (property "Sheetname" "USB-C Interface ")
    (property "Val" "100n")
    (property "Voltage" "50V")
    (attr smd)
    (fp_text reference "C67" (at -1.14 1.36) (layer "F.SilkS")
      (effects (font (size 0.7 0.7) (thickness 0.15)) (justify left bottom))
    )
    (fp_text value "C_100n_0402" (at 0 1.4) (layer "F.Fab")
      (effects (font (size 0.7 0.7) (thickness 0.15)) (justify left bottom))
    )
    (fp_text user "Author: Antmicro" (at -0.932 4.17) (layer "F.Fab") hide
      (effects (font (size 0.7 0.7) (thickness 0.15)) (justify left bottom))
    )
    (fp_text user "License: Apache-2.0" (at -0.932 5.17) (layer "F.Fab") hide
      (effects (font (size 0.7 0.7) (thickness 0.15)) (justify left bottom))
    )
    (fp_text user "${REFERENCE}" (at -0.932 3.168) (layer "F.Fab") hide
      (effects (font (size 0.7 0.7) (thickness 0.15)) (justify left bottom))
    )
    (fp_rect (start -0.94 -0.47) (end 0.94 0.47) (layer "F.CrtYd") (width 0.05) (fill none))
    (fp_rect (start -0.499 -0.249) (end 0.499 0.249) (layer "F.Fab") (width 0.15) (fill none))
    (pad "1" smd roundrect (at -0.484 0) (size 0.59 0.64) (layers "F.Cu" "F.Paste" "F.Mask") (roundrect_rratio 0.25)
      (net 352 "Net-(C67-Pad1)") (pintype "passive"))
    (pad "2" smd roundrect (at 0.484 0) (size 0.59 0.64) (layers "F.Cu" "F.Paste" "F.Mask") (roundrect_rratio 0.25)
      (net 1 "GND") (pintype "passive"))
  )

  (footprint "sa800u-baseboard-hw-footprints:C_0402_1005Metric" (layer "F.Cu")
    (tedit 616D63CF)
    (at 132.9 137.3)
    (descr "Capacitor SMD 0402")
    (tags "capacitor SMD 0402")
    (property "Author" "Antmicro")
    (property "Dielectric" "X5R")
    (property "License" "Apache-2.0")
    (property "MPN" "GRM155R61H104KE14D")
    (property "Manufacturer" "Murata")
    (property "Sheetfile" "usb-c-interface.kicad_sch")
    (property "Sheetname" "USB-C Interface ")
    (property "Val" "100n")
    (property "Voltage" "50V")
    (attr smd)
    (fp_text reference "C69" (at -1.11 -0.62) (layer "F.SilkS")
      (effects (font (size 0.7 0.7) (thickness 0.15)) (justify left bottom))
    )
    (fp_text value "C_100n_0402" (at 0 1.4) (layer "F.Fab")
      (effects (font (size 0.7 0.7) (thickness 0.15)) (justify left bottom))
    )
    (fp_text user "${REFERENCE}" (at -0.932 3.168) (layer "F.Fab") hide
      (effects (font (size 0.7 0.7) (thickness 0.15)) (justify left bottom))
    )
    (fp_text user "License: Apache-2.0" (at -0.932 5.17) (layer "F.Fab") hide
      (effects (font (size 0.7 0.7) (thickness 0.15)) (justify left bottom))
    )
    (fp_text user "Author: Antmicro" (at -0.932 4.17) (layer "F.Fab") hide
      (effects (font (size 0.7 0.7) (thickness 0.15)) (justify left bottom))
    )
    (fp_rect (start -0.94 -0.47) (end 0.94 0.47) (layer "F.CrtYd") (width 0.05) (fill none))
    (fp_rect (start -0.499 -0.249) (end 0.499 0.249) (layer "F.Fab") (width 0.15) (fill none))
    (pad "1" smd roundrect (at -0.484 0) (size 0.59 0.64) (layers "F.Cu" "F.Paste" "F.Mask") (roundrect_rratio 0.25)
      (net 228 "/USB-C Interface /5V0_DBG") (pintype "passive"))
    (pad "2" smd roundrect (at 0.484 0) (size 0.59 0.64) (layers "F.Cu" "F.Paste" "F.Mask") (roundrect_rratio 0.25)
      (net 1 "GND") (pintype "passive"))
  )

  (footprint "sa800u-baseboard-hw-footprints:D_SOD-323F" (layer "F.Cu")
    (tedit 60F16F6B)
    (at 124.2 134.6 90)
    (property "Author" "Antmicro")
    (property "License" "Apache-2.0")
    (property "MPN" "1N4148WS")
    (property "Manufacturer" "ON Semiconductor")
    (property "Sheetfile" "usb-c-interface.kicad_sch")
    (property "Sheetname" "USB-C Interface ")
    (attr smd)
    (fp_text reference "D6" (at -0.76 -1.07 90) (layer "F.SilkS")
      (effects (font (size 0.7 0.7) (thickness 0.15)) (justify left bottom))
    )
    (fp_text value "1N4148WS" (at -1.7 1.9 90) (layer "F.Fab")
      (effects (font (size 0.7 0.7) (thickness 0.15)) (justify left bottom))
    )
    (fp_text user "${REFERENCE}" (at -1.8 3.2 90) (layer "F.Fab") hide
      (effects (font (size 0.7 0.7) (thickness 0.15)) (justify left bottom))
    )
    (fp_text user "Author: Antmicro" (at -1.8 4.46 90) (layer "F.Fab") hide
      (effects (font (size 0.7 0.7) (thickness 0.15)) (justify left bottom))
    )
    (fp_text user "License: Apache-2.0" (at -1.8 5.8 90) (layer "F.Fab") hide
      (effects (font (size 0.7 0.7) (thickness 0.15)) (justify left bottom))
    )
    (fp_line (start 0.973 -0.75) (end 0.973 -0.45) (layer "F.SilkS") (width 0.15))
    (fp_line (start -0.5 -0.426) (end -0.5 0.424) (layer "F.SilkS") (width 0.15))
    (fp_line (start 0.973 0.748) (end 0.623 0.748) (layer "F.SilkS") (width 0.15))
    (fp_line (start 0.973 0.45) (end 0.973 0.748) (layer "F.SilkS") (width 0.15))
    (fp_line (start 0.623 -0.75) (end 0.973 -0.75) (layer "F.SilkS") (width 0.15))
    (fp_line (start -0.975 -0.75) (end -0.975 -0.45) (layer "F.SilkS") (width 0.15))
    (fp_line (start -0.625 0.748) (end -0.975 0.748) (layer "F.SilkS") (width 0.15))
    (fp_line (start -0.975 0.748) (end -0.975 0.45) (layer "F.SilkS") (width 0.15))
    (fp_line (start -0.625 -0.75) (end -0.975 -0.75) (layer "F.SilkS") (width 0.15))
    (fp_rect (start -1.6 -0.827) (end 1.599 0.825) (layer "F.CrtYd") (width 0.05) (fill none))
    (fp_line (start -0.85 -0.625) (end 0.848 -0.625) (layer "F.Fab") (width 0.15))
    (fp_line (start -0.85 0.623) (end 0.848 0.623) (layer "F.Fab") (width 0.15))
    (fp_line (start 0.848 -0.625) (end 0.848 0.623) (layer "F.Fab") (width 0.15))
    (fp_line (start -0.85 0.623) (end -0.85 -0.625) (layer "F.Fab") (width 0.15))
    (pad "A" smd roundrect (at 1.05 0 90) (size 0.8 0.6) (layers "F.Cu" "F.Paste" "F.Mask") (roundrect_rratio 0.15)
      (net 133 "5V_SYS") (pinfunction "A") (pintype "passive"))
    (pad "K" smd roundrect (at -1.051 0 90) (size 0.8 0.6) (layers "F.Cu" "F.Paste" "F.Mask") (roundrect_rratio 0.15)
      (net 228 "/USB-C Interface /5V0_DBG") (pinfunction "K") (pintype "passive"))
  )

  (footprint "sa800u-baseboard-hw-footprints:FB_0603_1608Metric" (layer "F.Cu")
    (tedit 618B9E9E)
    (at 126.3 140.95 180)
    (property "Author" "Antmicro")
    (property "License" "Apache-2.0")
    (property "MPN" "BLM18EG221SN1D")
    (property "Manufacturer" "Murata")
    (property "Sheetfile" "usb-c-interface.kicad_sch")
    (property "Sheetname" "USB-C Interface ")
    (attr smd)
    (fp_text reference "FB3" (at 3.35 -0.43 180) (layer "F.SilkS")
      (effects (font (size 0.7 0.7) (thickness 0.15)) (justify left bottom))
    )
    (fp_text value "FB_220Z_1A_0603" (at 0 1.5 180) (layer "F.Fab")
      (effects (font (size 0.7 0.7) (thickness 0.15)) (justify left bottom))
    )
    (fp_text user "Author: Antmicro" (at -1.653 3.162 180) (layer "F.Fab") hide
      (effects (font (size 0.7 0.7) (thickness 0.15)) (justify left bottom))
    )
    (fp_text user "${REFERENCE}" (at -1.653 4.6 180) (layer "F.Fab") hide
      (effects (font (size 0.7 0.7) (thickness 0.15)) (justify left bottom))
    )
    (fp_text user "License: Apache-2.0" (at -1.653 5.9 180) (layer "F.Fab") hide
      (effects (font (size 0.7 0.7) (thickness 0.15)) (justify left bottom))
    )
    (fp_line (start -0.196 -0.408) (end 0.193 -0.408) (layer "F.SilkS") (width 0.15))
    (fp_line (start -0.196 0.406) (end 0.193 0.406) (layer "F.SilkS") (width 0.15))
    (fp_rect (start -1.3 -0.6) (end 1.3 0.6) (layer "F.CrtYd") (width 0.05) (fill none))
    (fp_line (start -0.803 0.406) (end -0.803 -0.408) (layer "F.Fab") (width 0.15))
    (fp_line (start 0.8 -0.408) (end -0.803 -0.408) (layer "F.Fab") (width 0.15))
    (fp_line (start 0.8 0.406) (end -0.803 0.406) (layer "F.Fab") (width 0.15))
    (fp_line (start 0.8 -0.408) (end 0.8 0.406) (layer "F.Fab") (width 0.15))
    (pad "1" smd roundrect (at -0.891 0 180) (size 0.762 1.09) (layers "F.Cu" "F.Paste" "F.Mask") (roundrect_rratio 0.15)
      (net 253 "/USB-C Interface /DBG_VBUS") (pintype "passive"))
    (pad "2" smd roundrect (at 0.888 0 180) (size 0.762 1.09) (layers "F.Cu" "F.Paste" "F.Mask") (roundrect_rratio 0.15)
      (net 228 "/USB-C Interface /5V0_DBG") (pintype "passive"))
  )

  (footprint "sa800u-baseboard-hw-footprints:QFN-32-1EP_5x5mm" (layer "F.Cu")
    (tedit 5E53F9B0)
    (at 128.771 136.375)
    (property "Author" "Antmicro")
    (property "License" "Apache-2.0")
    (property "MPN" "FT232RQ-REEL")
    (property "Manufacturer" "FTDI")
    (property "Sheetfile" "usb-c-interface.kicad_sch")
    (property "Sheetname" "USB-C Interface ")
    (attr smd)
    (fp_text reference "U5" (at -3.671 -2.675) (layer "F.SilkS")
      (effects (font (size 0.7 0.7) (thickness 0.15)) (justify left bottom))
    )
    (fp_text value "FT232R_QFN" (at -4.94 3.91) (layer "F.Fab")
      (effects (font (size 0.7 0.7) (thickness 0.15)) (justify left bottom))
    )
    (fp_text user "License: Apache-2.0" (at -4.94 5.91) (layer "F.Fab") hide
      (effects (font (size 0.7 0.7) (thickness 0.15)) (justify left bottom))
    )
    (fp_text user "${REFERENCE}" (at -4.94 7.11) (layer "F.Fab") hide
      (effects (font (size 0.7 0.7) (thickness 0.15)) (justify left bottom))
    )
    (fp_text user "Author: Antmicro" (at -4.94 8.31) (layer "F.Fab") hide
      (effects (font (size 0.7 0.7) (thickness 0.15)) (justify left bottom))
    )
    (fp_line (start 2.58 -2.552) (end 2.177 -2.552) (layer "F.SilkS") (width 0.15))
    (fp_line (start 2.58 -2.552) (end 2.58 -2.149) (layer "F.SilkS") (width 0.15))
    (fp_line (start 2.58 2.648) (end 2.177 2.648) (layer "F.SilkS") (width 0.15))
    (fp_line (start -2.621 2.648) (end -2.621 2.249) (layer "F.SilkS") (width 0.15))
    (fp_line (start -2.222 -2.552) (end -2.621 -2.149) (layer "F.SilkS") (width 0.15))
    (fp_line (start -2.222 2.648) (end -2.621 2.648) (layer "F.SilkS") (width 0.15))
    (fp_line (start 2.58 2.249) (end 2.58 2.648) (layer "F.SilkS") (width 0.15))
    (fp_circle (center -3.3 -1.702) (end -3.25 -1.702) (layer "F.SilkS") (width 0.15) (fill solid))
    (fp_rect (start -3 -3) (end 2.999 2.999) (layer "F.CrtYd") (width 0.05) (fill none))
    (fp_line (start -2.5 -2.299) (end -2.299 -2.5) (layer "F.Fab") (width 0.15))
    (fp_rect (start -2.5 -2.5) (end 2.499 2.499) (layer "F.Fab") (width 0.15) (fill none))
    (pad "1" smd rect (at -2.496 -1.702 270) (size 0.28 0.85) (layers "F.Cu" "F.Paste" "F.Mask")
      (net 127 "1V8_DBG") (pinfunction "VCCIO") (pintype "power_in") (solder_mask_margin 0.07))
    (pad "2" smd rect (at -2.496 -1.2 270) (size 0.28 0.85) (layers "F.Cu" "F.Paste" "F.Mask")
      (net 130 "DBG_TXD") (pinfunction "RXD") (pintype "input") (solder_mask_margin 0.07))
    (pad "3" smd rect (at -2.496 -0.702 270) (size 0.28 0.85) (layers "F.Cu" "F.Paste" "F.Mask")
      (net 504 "unconnected-(U5-Pad3)") (pinfunction "RI#") (pintype "input+no_connect") (solder_mask_margin 0.07))
    (pad "4" smd rect (at -2.496 -0.202 270) (size 0.28 0.85) (layers "F.Cu" "F.Paste" "F.Mask")
      (net 1 "GND") (pinfunction "GND") (pintype "passive") (solder_mask_margin 0.07))
    (pad "5" smd rect (at -2.496 0.297 270) (size 0.28 0.85) (layers "F.Cu" "F.Paste" "F.Mask")
      (net 503 "unconnected-(U5-Pad5)") (pinfunction "NC") (pintype "no_connect") (solder_mask_margin 0.07))
    (pad "6" smd rect (at -2.496 0.8 270) (size 0.28 0.85) (layers "F.Cu" "F.Paste" "F.Mask")
      (net 502 "unconnected-(U5-Pad6)") (pinfunction "DSR#") (pintype "input+no_connect") (solder_mask_margin 0.07))
    (pad "7" smd rect (at -2.496 1.3 270) (size 0.28 0.85) (layers "F.Cu" "F.Paste" "F.Mask")
      (net 501 "unconnected-(U5-Pad7)") (pinfunction "DCD#") (pintype "input+no_connect") (solder_mask_margin 0.07))
    (pad "8" smd rect (at -2.496 1.8 270) (size 0.28 0.85) (layers "F.Cu" "F.Paste" "F.Mask")
      (net 500 "unconnected-(U5-Pad8)") (pinfunction "CTS#") (pintype "input+no_connect") (solder_mask_margin 0.07))
    (pad "9" smd rect (at -1.77 2.523 270) (size 0.85 0.28) (layers "F.Cu" "F.Paste" "F.Mask")
      (net 499 "unconnected-(U5-Pad9)") (pinfunction "CBUS4") (pintype "bidirectional+no_connect") (solder_mask_margin 0.07))
    (pad "10" smd rect (at -1.27 2.523 270) (size 0.85 0.28) (layers "F.Cu" "F.Paste" "F.Mask")
      (net 498 "unconnected-(U5-Pad10)") (pinfunction "CBUS2") (pintype "bidirectional+no_connect") (solder_mask_margin 0.07))
    (pad "11" smd rect (at -0.773 2.523 270) (size 0.85 0.28) (layers "F.Cu" "F.Paste" "F.Mask")
      (net 497 "unconnected-(U5-Pad11)") (pinfunction "CBUS3") (pintype "bidirectional+no_connect") (solder_mask_margin 0.07))
    (pad "12" smd rect (at -0.273 2.523 270) (size 0.85 0.28) (layers "F.Cu" "F.Paste" "F.Mask")
      (net 496 "unconnected-(U5-Pad12)") (pinfunction "NC") (pintype "no_connect") (solder_mask_margin 0.07))
    (pad "13" smd rect (at 0.229 2.523 270) (size 0.85 0.28) (layers "F.Cu" "F.Paste" "F.Mask")
      (net 495 "unconnected-(U5-Pad13)") (pinfunction "NC") (pintype "no_connect") (solder_mask_margin 0.07))
    (pad "14" smd rect (at 0.727 2.523 270) (size 0.85 0.28) (layers "F.Cu" "F.Paste" "F.Mask")
      (net 230 "/USB-C Interface /DBG_USB_D_P") (pinfunction "USBDP") (pintype "bidirectional") (solder_mask_margin 0.07))
    (pad "15" smd rect (at 1.229 2.523 270) (size 0.85 0.28) (layers "F.Cu" "F.Paste" "F.Mask")
      (net 229 "/USB-C Interface /DBG_USB_D_N") (pinfunction "USBDM") (pintype "bidirectional") (solder_mask_margin 0.07))
    (pad "16" smd rect (at 1.729 2.523 270) (size 0.85 0.28) (layers "F.Cu" "F.Paste" "F.Mask")
      (net 352 "Net-(C67-Pad1)") (pinfunction "3V3OUT") (pintype "output") (solder_mask_margin 0.07))
    (pad "17" smd rect (at 2.455 1.8 270) (size 0.28 0.85) (layers "F.Cu" "F.Paste" "F.Mask")
      (net 1 "GND") (pinfunction "GND") (pintype "power_in") (solder_mask_margin 0.07))
    (pad "18" smd rect (at 2.455 1.3 270) (size 0.28 0.85) (layers "F.Cu" "F.Paste" "F.Mask")
      (net 494 "unconnected-(U5-Pad18)") (pinfunction "RESET#") (pintype "input+no_connect") (solder_mask_margin 0.07))
    (pad "19" smd rect (at 2.455 0.8 270) (size 0.28 0.85) (layers "F.Cu" "F.Paste" "F.Mask")
      (net 228 "/USB-C Interface /5V0_DBG") (pinfunction "VCC") (pintype "power_in") (solder_mask_margin 0.07))
    (pad "20" smd rect (at 2.455 0.297 270) (size 0.28 0.85) (layers "F.Cu" "F.Paste" "F.Mask")
      (net 1 "GND") (pinfunction "GND") (pintype "passive") (solder_mask_margin 0.07))
    (pad "21" smd rect (at 2.455 -0.202 270) (size 0.28 0.85) (layers "F.Cu" "F.Paste" "F.Mask")
      (net 493 "unconnected-(U5-Pad21)") (pinfunction "CBUS1") (pintype "bidirectional+no_connect") (solder_mask_margin 0.07))
    (pad "22" smd rect (at 2.455 -0.702 270) (size 0.28 0.85) (layers "F.Cu" "F.Paste" "F.Mask")
      (net 492 "unconnected-(U5-Pad22)") (pinfunction "CBUS0") (pintype "bidirectional+no_connect") (solder_mask_margin 0.07))
    (pad "23" smd rect (at 2.455 -1.2 270) (size 0.28 0.85) (layers "F.Cu" "F.Paste" "F.Mask")
      (net 491 "unconnected-(U5-Pad23)") (pinfunction "NC") (pintype "no_connect") (solder_mask_margin 0.07))
    (pad "24" smd rect (at 2.455 -1.702 270) (size 0.28 0.85) (layers "F.Cu" "F.Paste" "F.Mask")
      (net 1 "GND") (pinfunction "AGND") (pintype "power_in") (solder_mask_margin 0.07))
    (pad "25" smd rect (at 1.729 -2.427 270) (size 0.85 0.28) (layers "F.Cu" "F.Paste" "F.Mask")
      (net 490 "unconnected-(U5-Pad25)") (pinfunction "NC") (pintype "no_connect") (solder_mask_margin 0.07))
    (pad "26" smd rect (at 1.229 -2.427 270) (size 0.85 0.28) (layers "F.Cu" "F.Paste" "F.Mask")
      (net 1 "GND") (pinfunction "TEST") (pintype "input") (solder_mask_margin 0.07))
    (pad "27" smd rect (at 0.727 -2.427 270) (size 0.85 0.28) (layers "F.Cu" "F.Paste" "F.Mask")
      (net 489 "unconnected-(U5-Pad27)") (pinfunction "OSCI") (pintype "input+no_connect") (solder_mask_margin 0.07))
    (pad "28" smd rect (at 0.229 -2.427 270) (size 0.85 0.28) (layers "F.Cu" "F.Paste" "F.Mask")
      (net 488 "unconnected-(U5-Pad28)") (pinfunction "OSCO") (pintype "output+no_connect") (solder_mask_margin 0.07))
    (pad "29" smd rect (at -0.273 -2.427 270) (size 0.85 0.28) (layers "F.Cu" "F.Paste" "F.Mask")
      (net 487 "unconnected-(U5-Pad29)") (pinfunction "NC") (pintype "no_connect") (solder_mask_margin 0.07))
    (pad "30" smd rect (at -0.773 -2.427 270) (size 0.85 0.28) (layers "F.Cu" "F.Paste" "F.Mask")
      (net 129 "DBG_RXD") (pinfunction "TXD") (pintype "output") (solder_mask_margin 0.07))
    (pad "31" smd rect (at -1.27 -2.427 270) (size 0.85 0.28) (layers "F.Cu" "F.Paste" "F.Mask")
      (net 486 "unconnected-(U5-Pad31)") (pinfunction "DTR#") (pintype "output+no_connect") (solder_mask_margin 0.07))
    (pad "32" smd rect (at -1.77 -2.427 270) (size 0.85 0.28) (layers "F.Cu" "F.Paste" "F.Mask")
      (net 485 "unconnected-(U5-Pad32)") (pinfunction "RTS#") (pintype "output+no_connect") (solder_mask_margin 0.07))
    (pad "33" smd rect (at -0.022 0.049 270) (size 3.45 3.45) (layers "F.Cu" "F.Paste" "F.Mask")
      (net 1 "GND") (pinfunction "EP") (pintype "unspecified"))
  )

  (footprint "sa800u-baseboard-hw-footprints:USB-C_12401610E4_2A" locked (layer "F.Cu")
    (tedit 6215EC4A)
    (at 129.75 147.95)
    (property "Author" "Antmicro")
    (property "License" "Apache-2.0")
    (property "MPN" "12401598E4#2A")
    (property "Manufacturer" "Amphenol")
    (property "Sheetfile" "usb-c-interface.kicad_sch")
    (property "Sheetname" "USB-C Interface ")
    (attr smd)
    (fp_text reference "J5" (at 3.42 -5.58) (layer "F.SilkS")
      (effects (font (size 0.7 0.7) (thickness 0.15)) (justify left bottom))
    )
    (fp_text value "12401598E4_2A" (at 0 6.549) (layer "F.Fab")
      (effects (font (size 0.7 0.7) (thickness 0.15)) (justify left bottom))
    )
    (fp_text user "${REFERENCE}" (at -4.901 8.55) (layer "F.Fab") hide
      (effects (font (size 0.7 0.7) (thickness 0.15)) (justify left bottom))
    )
    (fp_text user "License: Apache-2.0" (at -4.901 10.948) (layer "F.Fab") hide
      (effects (font (size 0.7 0.7) (thickness 0.15)) (justify left bottom))
    )
    (fp_text user "Author: Antmicro" (at -4.901 9.749) (layer "F.Fab") hide
      (effects (font (size 0.7 0.7) (thickness 0.15)) (justify left bottom))
    )
    (fp_line (start 4.599 5.448) (end 4.099 5.448) (layer "F.SilkS") (width 0.15))
    (fp_line (start 4.599 -5.25) (end 4.099 -5.25) (layer "F.SilkS") (width 0.15))
    (fp_line (start -4.601 5.448) (end -4.1 5.448) (layer "F.SilkS") (width 0.15))
    (fp_line (start 4.599 5.448) (end 4.599 4.948) (layer "F.SilkS") (width 0.15))
    (fp_line (start -4.601 -5.25) (end -4.601 -4.75) (layer "F.SilkS") (width 0.15))
    (fp_line (start -4.601 -5.25) (end -4.1 -5.25) (layer "F.SilkS") (width 0.15))
    (fp_line (start -4.601 5.448) (end -4.601 4.948) (layer "F.SilkS") (width 0.15))
    (fp_line (start 4.599 -5.25) (end 4.599 -4.75) (layer "F.SilkS") (width 0.15))
    (fp_circle (center -3.101 -5.25) (end -3.052 -5.25) (layer "F.SilkS") (width 0.15) (fill solid))
    (fp_rect (start -4.92 -5.46) (end 4.9 5.44) (layer "F.CrtYd") (width 0.05) (fill none))
    (fp_line (start -4.491 5.339) (end 4.49 5.339) (layer "F.Fab") (width 0.15))
    (fp_line (start -4.491 -5.162) (end 4.49 -5.162) (layer "F.Fab") (width 0.15))
    (fp_line (start 4.49 -5.162) (end 4.49 5.339) (layer "F.Fab") (width 0.15))
    (fp_line (start -4.491 -5.162) (end -4.491 5.339) (layer "F.Fab") (width 0.15))
    (pad "" np_thru_hole circle locked (at -3.601 -4.25) (size 0.65 0.65) (drill 0.65) (layers *.Cu *.Mask))
    (pad "" np_thru_hole oval locked (at 3.6 -4.25) (size 0.95 0.65) (drill oval 0.95 0.65) (layers *.Cu *.Mask))
    (pad "A1" smd rect locked (at -2.75 -4.912) (size 0.3 0.7) (layers "F.Cu" "F.Paste" "F.Mask")
      (net 1 "GND") (pintype "passive"))
    (pad "A2" smd rect locked (at -2.25 -4.912) (size 0.3 0.7) (layers "F.Cu" "F.Paste" "F.Mask")
      (net 438 "unconnected-(J5-PadA2)") (pintype "passive+no_connect"))
    (pad "A3" smd rect locked (at -1.75 -4.912) (size 0.3 0.7) (layers "F.Cu" "F.Paste" "F.Mask")
      (net 437 "unconnected-(J5-PadA3)") (pintype "passive+no_connect"))
    (pad "A4" smd rect locked (at -1.25 -4.912) (size 0.3 0.7) (layers "F.Cu" "F.Paste" "F.Mask")
      (net 253 "/USB-C Interface /DBG_VBUS") (pintype "passive"))
    (pad "A5" smd rect locked (at -0.75 -4.912) (size 0.3 0.7) (layers "F.Cu" "F.Paste" "F.Mask")
      (net 436 "unconnected-(J5-PadA5)") (pintype "passive+no_connect"))
    (pad "A6" smd rect locked (at -0.25 -4.912) (size 0.3 0.7) (layers "F.Cu" "F.Paste" "F.Mask")
      (net 230 "/USB-C Interface /DBG_USB_D_P") (pintype "passive"))
    (pad "A7" smd rect locked (at 0.247 -4.912) (size 0.3 0.7) (layers "F.Cu" "F.Paste" "F.Mask")
      (net 229 "/USB-C Interface /DBG_USB_D_N") (pintype "passive"))
    (pad "A8" smd rect locked (at 0.747 -4.912) (size 0.3 0.7) (layers "F.Cu" "F.Paste" "F.Mask")
      (net 435 "unconnected-(J5-PadA8)") (pintype "passive+no_connect"))
    (pad "A9" smd rect locked (at 1.249 -4.912) (size 0.3 0.7) (layers "F.Cu" "F.Paste" "F.Mask")
      (net 253 "/USB-C Interface /DBG_VBUS") (pintype "passive"))
    (pad "A10" smd rect locked (at 1.749 -4.912) (size 0.3 0.7) (layers "F.Cu" "F.Paste" "F.Mask")
      (net 434 "unconnected-(J5-PadA10)") (pintype "passive+no_connect"))
    (pad "A11" smd rect locked (at 2.249 -4.912) (size 0.3 0.7) (layers "F.Cu" "F.Paste" "F.Mask")
      (net 433 "unconnected-(J5-PadA11)") (pintype "passive+no_connect"))
    (pad "A12" smd rect locked (at 2.749 -4.912) (size 0.3 0.7) (layers "F.Cu" "F.Paste" "F.Mask")
      (net 1 "GND") (pintype "passive"))
    (pad "B1" smd rect locked (at 2.499 -3.21) (size 0.3 0.7) (layers "F.Cu" "F.Paste" "F.Mask")
      (net 1 "GND") (pintype "passive"))
    (pad "B2" smd rect locked (at 1.999 -3.21) (size 0.3 0.7) (layers "F.Cu" "F.Paste" "F.Mask")
      (net 432 "unconnected-(J5-PadB2)") (pintype "passive+no_connect"))
    (pad "B3" smd rect locked (at 1.499 -3.21) (size 0.3 0.7) (layers "F.Cu" "F.Paste" "F.Mask")
      (net 431 "unconnected-(J5-PadB3)") (pintype "passive+no_connect"))
    (pad "B4" smd rect locked (at 0.997 -3.21) (size 0.3 0.7) (layers "F.Cu" "F.Paste" "F.Mask")
      (net 253 "/USB-C Interface /DBG_VBUS") (pintype "passive"))
    (pad "B5" smd rect locked (at 0.497 -3.21) (size 0.3 0.7) (layers "F.Cu" "F.Paste" "F.Mask")
      (net 430 "unconnected-(J5-PadB5)") (pintype "passive+no_connect"))
    (pad "B6" smd rect locked (at 0 -3.21) (size 0.3 0.7) (layers "F.Cu" "F.Paste" "F.Mask")
      (net 230 "/USB-C Interface /DBG_USB_D_P") (pintype "passive"))
    (pad "B7" smd rect locked (at -0.5 -3.21) (size 0.3 0.7) (layers "F.Cu" "F.Paste" "F.Mask")
      (net 229 "/USB-C Interface /DBG_USB_D_N") (pintype "passive"))
    (pad "B8" smd rect locked (at -1 -3.21) (size 0.3 0.7) (layers "F.Cu" "F.Paste" "F.Mask")
      (net 429 "unconnected-(J5-PadB8)") (pintype "passive+no_connect"))
    (pad "B9" smd rect locked (at -1.5 -3.21) (size 0.3 0.7) (layers "F.Cu" "F.Paste" "F.Mask")
      (net 253 "/USB-C Interface /DBG_VBUS") (pintype "passive"))
    (pad "B10" smd rect locked (at -2 -3.21) (size 0.3 0.7) (layers "F.Cu" "F.Paste" "F.Mask")
      (net 428 "unconnected-(J5-PadB10)") (pintype "passive+no_connect"))
    (pad "B11" smd rect locked (at -2.5 -3.21) (size 0.3 0.7) (layers "F.Cu" "F.Paste" "F.Mask")
      (net 427 "unconnected-(J5-PadB11)") (pintype "passive+no_connect"))
    (pad "B12" smd rect locked (at -3 -3.21) (size 0.3 0.7) (layers "F.Cu" "F.Paste" "F.Mask")
      (net 1 "GND") (pintype "passive"))
    (pad "SH" thru_hole oval locked (at -4.13 -3.001) (size 0.85 1.45) (drill oval 0.5 1.1) (layers *.Cu *.Mask)
      (net 1 "GND") (pintype "input"))
    (pad "SH" thru_hole oval locked (at -4.491 2.95) (size 0.85 1.45) (drill oval 0.5 1.1) (layers *.Cu *.Mask)
      (net 1 "GND") (pintype "input"))
    (pad "SH" thru_hole oval locked (at 4.128 -3.001) (size 0.85 1.45) (drill oval 0.5 1.1) (layers *.Cu *.Mask)
      (net 1 "GND") (pintype "input"))
    (pad "SH" thru_hole oval locked (at 4.49 2.95) (size 0.85 1.45) (drill oval 0.5 1.1) (layers *.Cu *.Mask)
      (net 1 "GND") (pintype "input"))
  )

  (footprint "sa800u-baseboard-hw-footprints:Nexperia_DFN-10_2.5x1mm_P0.5mm" (layer "F.Cu")
    (tedit 6215DC23)
    (at 129 141 180)
    (property "Author" "Antmicro")
    (property "License" "Apache-2.0")
    (property "MPN" "PUSB3F96X")
    (property "Manufacturer" "Nexperia")
    (property "Sheetfile" "usb-c-interface.kicad_sch")
    (property "Sheetname" "USB-C Interface ")
    (attr smd)
    (fp_text reference "D11" (at -2.29 -1 270) (layer "F.SilkS")
      (effects (font (size 0.7 0.7) (thickness 0.15)) (justify left bottom))
    )
    (fp_text value "PUSB3F96X_PASS" (at -0.016 1.705 180) (layer "F.Fab")
      (effects (font (size 0.7 0.7) (thickness 0.15)) (justify left bottom))
    )
    (fp_text user "${REFERENCE}" (at -1.367 3.704 180) (layer "F.Fab") hide
      (effects (font (size 0.7 0.7) (thickness 0.15)) (justify left bottom))
    )
    (fp_text user "Author: Antmicro" (at -1.367 4.905 180) (layer "F.Fab") hide
      (effects (font (size 0.7 0.7) (thickness 0.15)) (justify left bottom))
    )
    (fp_text user "License: Apache-2.0" (at -1.367 6.105 180) (layer "F.Fab") hide
      (effects (font (size 0.7 0.7) (thickness 0.15)) (justify left bottom))
    )
    (fp_line (start -1.266 -0.396) (end -1.266 0.405) (layer "F.SilkS") (width 0.15))
    (fp_line (start 1.233 0.405) (end 1.233 -0.396) (layer "F.SilkS") (width 0.15))
    (fp_circle (center -1.317 0.704) (end -1.266 0.704) (layer "F.SilkS") (width 0.15) (fill solid))
    (fp_rect (start -1.4 -0.7) (end 1.4 0.7) (layer "F.CrtYd") (width 0.05) (fill none))
    (pad "1" smd rect (at -1.016 0.392 180) (size 0.2 0.475) (layers "F.Cu" "F.Paste" "F.Mask")
      (net 229 "/USB-C Interface /DBG_USB_D_N") (pinfunction "CH1") (pintype "passive"))
    (pad "2" smd rect (at -0.517 0.392 180) (size 0.2 0.475) (layers "F.Cu" "F.Paste" "F.Mask")
      (net 230 "/USB-C Interface /DBG_USB_D_P") (pinfunction "CH2") (pintype "passive"))
    (pad "3" smd rect (at -0.016 0.392 180) (size 0.2 0.475) (layers "F.Cu" "F.Paste" "F.Mask")
      (net 1 "GND") (pinfunction "GND") (pintype "passive"))
    (pad "4" smd rect (at 0.482 0.392 180) (size 0.2 0.475) (layers "F.Cu" "F.Paste" "F.Mask")
      (net 253 "/USB-C Interface /DBG_VBUS") (pinfunction "CH3") (pintype "passive"))
    (pad "5" smd rect (at 0.982 0.392 180) (size 0.2 0.475) (layers "F.Cu" "F.Paste" "F.Mask")
      (net 253 "/USB-C Interface /DBG_VBUS") (pinfunction "CH4") (pintype "passive"))
    (pad "6" smd rect (at 0.982 -0.383) (size 0.2 0.475) (layers "F.Cu" "F.Paste" "F.Mask")
      (net 253 "/USB-C Interface /DBG_VBUS") (pinfunction "CH4") (pintype "passive"))
    (pad "7" smd rect (at 0.482 -0.383) (size 0.2 0.475) (layers "F.Cu" "F.Paste" "F.Mask")
      (net 253 "/USB-C Interface /DBG_VBUS") (pinfunction "CH3") (pintype "passive"))
    (pad "8" smd rect (at -0.016 -0.383) (size 0.2 0.475) (layers "F.Cu" "F.Paste" "F.Mask")
      (net 1 "GND") (pinfunction "GND") (pintype "passive"))
    (pad "9" smd rect (at -0.517 -0.383) (size 0.2 0.475) (layers "F.Cu" "F.Paste" "F.Mask")
      (net 230 "/USB-C Interface /DBG_USB_D_P") (pinfunction "CH2") (pintype "passive"))
    (pad "10" smd rect (at -1.016 -0.383) (size 0.2 0.475) (layers "F.Cu" "F.Paste" "F.Mask")
      (net 229 "/USB-C Interface /DBG_USB_D_N") (pinfunction "CH1") (pintype "passive"))
  )

  (footprint "sa800u-baseboard-hw-footprints:C_0402_1005Metric" (layer "F.Cu")
    (tedit 616D63CF)
    (at 111.59 93.8 90)
    (descr "Capacitor SMD 0402")
    (tags "capacitor SMD 0402")
    (property "Author" "Antmicro")
    (property "Dielectric" "X5R")
    (property "License" "Apache-2.0")
    (property "MPN" "GRM155R61H104KE14D")
    (property "Manufacturer" "Murata")
    (property "Sheetfile" "camera-interface.kicad_sch")
    (property "Sheetname" "Camera Interface")
    (property "Val" "100n")
    (property "Voltage" "50V")
    (attr smd)
    (fp_text reference "C110" (at -3.69 0.41 90) (layer "F.SilkS")
      (effects (font (size 0.7 0.7) (thickness 0.15)) (justify left bottom))
    )
    (fp_text value "C_100n_0402" (at 0 1.4 90) (layer "F.Fab")
      (effects (font (size 0.7 0.7) (thickness 0.15)) (justify left bottom))
    )
    (fp_text user "${REFERENCE}" (at -0.932 3.168 90) (layer "F.Fab") hide
      (effects (font (size 0.7 0.7) (thickness 0.15)) (justify left bottom))
    )
    (fp_text user "Author: Antmicro" (at -0.932 4.17 90) (layer "F.Fab") hide
      (effects (font (size 0.7 0.7) (thickness 0.15)) (justify left bottom))
    )
    (fp_text user "License: Apache-2.0" (at -0.932 5.17 90) (layer "F.Fab") hide
      (effects (font (size 0.7 0.7) (thickness 0.15)) (justify left bottom))
    )
    (fp_rect (start -0.94 -0.47) (end 0.94 0.47) (layer "F.CrtYd") (width 0.05) (fill none))
    (fp_rect (start -0.499 -0.249) (end 0.499 0.249) (layer "F.Fab") (width 0.15) (fill none))
    (pad "1" smd roundrect (at -0.484 0 90) (size 0.59 0.64) (layers "F.Cu" "F.Paste" "F.Mask") (roundrect_rratio 0.25)
      (net 231 "/Camera Interface/3V3_CAM") (pintype "passive"))
    (pad "2" smd roundrect (at 0.484 0 90) (size 0.59 0.64) (layers "F.Cu" "F.Paste" "F.Mask") (roundrect_rratio 0.25)
      (net 1 "GND") (pintype "passive"))
  )

  (footprint "sa800u-baseboard-hw-footprints:XSON-8_1x1.95mm_P0.5mm" (layer "F.Cu")
    (tedit 5DCD5522)
    (at 110.3 94.3)
    (property "Author" "Antmicro")
    (property "License" "Apache-2.0")
    (property "MPN" "NTS0102GT")
    (property "Manufacturer" "NXP")
    (property "Sheetfile" "camera-interface.kicad_sch")
    (property "Sheetname" "Camera Interface")
    (attr smd)
    (fp_text reference "U14" (at -3.07 2.1) (layer "F.SilkS")
      (effects (font (size 0.7 0.7) (thickness 0.15)) (justify left bottom))
    )
    (fp_text value "NTS0102_XSON" (at 0 2.2) (layer "F.Fab")
      (effects (font (size 0.7 0.7) (thickness 0.15)) (justify left bottom))
    )
    (fp_text user "License: Apache-2.0" (at -0.527 8.306) (layer "F.Fab") hide
      (effects (font (size 0.7 0.7) (thickness 0.15)) (justify left bottom))
    )
    (fp_text user "Author: Antmicro" (at -0.527 7.105) (layer "F.Fab") hide
      (effects (font (size 0.7 0.7) (thickness 0.15)) (justify left bottom))
    )
    (fp_text user "${REFERENCE}" (at -0.527 5.905) (layer "F.Fab") hide
      (effects (font (size 0.7 0.7) (thickness 0.15)) (justify left bottom))
    )
    (fp_line (start 0.5 1.1) (end -0.5 1.1) (layer "F.SilkS") (width 0.15))
    (fp_line (start -0.5 -1.1) (end 0.5 -1.1) (layer "F.SilkS") (width 0.15))
    (fp_circle (center -0.7 -0.95) (end -0.651 -0.95) (layer "F.SilkS") (width 0.15) (fill none))
    (fp_rect (start -0.8 -1.2) (end 0.8 1.2) (layer "F.CrtYd") (width 0.05) (fill none))
    (fp_line (start 0.5305 1) (end -0.5305 1) (layer "F.Fab") (width 0.15))
    (fp_line (start -0.5305 -1.001) (end 0.5305 -1.001) (layer "F.Fab") (width 0.15))
    (fp_line (start -0.5305 1) (end -0.5305 -1.001) (layer "F.Fab") (width 0.15))
    (fp_line (start 0.5305 -1.001) (end 0.5305 1) (layer "F.Fab") (width 0.15))
    (pad "1" smd rect (at -0.33 -0.75) (size 0.5 0.31) (layers "F.Cu" "F.Paste" "F.Mask")
      (net 296 "/Camera Interface/CCI0_I2C_SDA_3V3") (pinfunction "B_{2}") (pintype "bidirectional"))
    (pad "2" smd rect (at -0.33 -0.25) (size 0.5 0.31) (layers "F.Cu" "F.Paste" "F.Mask")
      (net 1 "GND") (pinfunction "GND") (pintype "power_in"))
    (pad "3" smd rect (at -0.33 0.25) (size 0.5 0.31) (layers "F.Cu" "F.Paste" "F.Mask")
      (net 139 "LVS1A_1V8") (pinfunction "VCC_{A}") (pintype "power_in"))
    (pad "4" smd rect (at -0.33 0.75) (size 0.5 0.31) (layers "F.Cu" "F.Paste" "F.Mask")
      (net 43 "CCI0_I2C_SDA") (pinfunction "A_{2}") (pintype "bidirectional"))
    (pad "5" smd rect (at 0.33 0.75 180) (size 0.5 0.31) (layers "F.Cu" "F.Paste" "F.Mask")
      (net 42 "CCI0_I2C_SCL") (pinfunction "A_{1}") (pintype "bidirectional"))
    (pad "6" smd rect (at 0.33 0.25 180) (size 0.5 0.31) (layers "F.Cu" "F.Paste" "F.Mask")
      (net 139 "LVS1A_1V8") (pinfunction "OE") (pintype "input"))
    (pad "7" smd rect (at 0.33 -0.25 180) (size 0.5 0.31) (layers "F.Cu" "F.Paste" "F.Mask")
      (net 231 "/Camera Interface/3V3_CAM") (pinfunction "VCC_{B}") (pintype "power_in"))
    (pad "8" smd rect (at 0.33 -0.75 180) (size 0.5 0.31) (layers "F.Cu" "F.Paste" "F.Mask")
      (net 294 "/Camera Interface/CCI0_I2C_SCL_3V3") (pinfunction "B_{1}") (pintype "bidirectional"))
  )

  (footprint "sa800u-baseboard-hw-footprints:XSON-8_1x1.95mm_P0.5mm" (layer "F.Cu")
    (tedit 5DCD5522)
    (at 113.83 94.3)
    (property "Author" "Antmicro")
    (property "License" "Apache-2.0")
    (property "MPN" "NTS0102GT")
    (property "Manufacturer" "NXP")
    (property "Sheetfile" "camera-interface.kicad_sch")
    (property "Sheetname" "Camera Interface")
    (attr smd)
    (fp_text reference "U13" (at 0.46 1.48) (layer "F.SilkS")
      (effects (font (size 0.7 0.7) (thickness 0.15)) (justify left bottom))
    )
    (fp_text value "NTS0102_XSON" (at 0 2.2) (layer "F.Fab")
      (effects (font (size 0.7 0.7) (thickness 0.15)) (justify left bottom))
    )
    (fp_text user "${REFERENCE}" (at -0.527 5.905) (layer "F.Fab") hide
      (effects (font (size 0.7 0.7) (thickness 0.15)) (justify left bottom))
    )
    (fp_text user "Author: Antmicro" (at -0.527 7.105) (layer "F.Fab") hide
      (effects (font (size 0.7 0.7) (thickness 0.15)) (justify left bottom))
    )
    (fp_text user "License: Apache-2.0" (at -0.527 8.306) (layer "F.Fab") hide
      (effects (font (size 0.7 0.7) (thickness 0.15)) (justify left bottom))
    )
    (fp_line (start 0.5 1.1) (end -0.5 1.1) (layer "F.SilkS") (width 0.15))
    (fp_line (start -0.5 -1.1) (end 0.5 -1.1) (layer "F.SilkS") (width 0.15))
    (fp_circle (center -0.7 -0.95) (end -0.651 -0.95) (layer "F.SilkS") (width 0.15) (fill none))
    (fp_rect (start -0.8 -1.2) (end 0.8 1.2) (layer "F.CrtYd") (width 0.05) (fill none))
    (fp_line (start -0.5305 -1.001) (end 0.5305 -1.001) (layer "F.Fab") (width 0.15))
    (fp_line (start 0.5305 -1.001) (end 0.5305 1) (layer "F.Fab") (width 0.15))
    (fp_line (start -0.5305 1) (end -0.5305 -1.001) (layer "F.Fab") (width 0.15))
    (fp_line (start 0.5305 1) (end -0.5305 1) (layer "F.Fab") (width 0.15))
    (pad "1" smd rect (at -0.33 -0.75) (size 0.5 0.31) (layers "F.Cu" "F.Paste" "F.Mask")
      (net 295 "/Camera Interface/CCI1_I2C_SDA_3V3") (pinfunction "B_{2}") (pintype "bidirectional"))
    (pad "2" smd rect (at -0.33 -0.25) (size 0.5 0.31) (layers "F.Cu" "F.Paste" "F.Mask")
      (net 1 "GND") (pinfunction "GND") (pintype "power_in"))
    (pad "3" smd rect (at -0.33 0.25) (size 0.5 0.31) (layers "F.Cu" "F.Paste" "F.Mask")
      (net 139 "LVS1A_1V8") (pinfunction "VCC_{A}") (pintype "power_in"))
    (pad "4" smd rect (at -0.33 0.75) (size 0.5 0.31) (layers "F.Cu" "F.Paste" "F.Mask")
      (net 45 "CCI1_I2C_SDA") (pinfunction "A_{2}") (pintype "bidirectional"))
    (pad "5" smd rect (at 0.33 0.75 180) (size 0.5 0.31) (layers "F.Cu" "F.Paste" "F.Mask")
      (net 44 "CCI1_I2C_SCL") (pinfunction "A_{1}") (pintype "bidirectional"))
    (pad "6" smd rect (at 0.33 0.25 180) (size 0.5 0.31) (layers "F.Cu" "F.Paste" "F.Mask")
      (net 139 "LVS1A_1V8") (pinfunction "OE") (pintype "input"))
    (pad "7" smd rect (at 0.33 -0.25 180) (size 0.5 0.31) (layers "F.Cu" "F.Paste" "F.Mask")
      (net 231 "/Camera Interface/3V3_CAM") (pinfunction "VCC_{B}") (pintype "power_in"))
    (pad "8" smd rect (at 0.33 -0.75 180) (size 0.5 0.31) (layers "F.Cu" "F.Paste" "F.Mask")
      (net 293 "/Camera Interface/CCI1_I2C_SCL_3V3") (pinfunction "B_{1}") (pintype "bidirectional"))
  )

  (footprint "sa800u-baseboard-hw-footprints:C_0402_1005Metric" (layer "F.Cu")
    (tedit 616D63CF)
    (at 109.02 93.8 90)
    (descr "Capacitor SMD 0402")
    (tags "capacitor SMD 0402")
    (property "Author" "Antmicro")
    (property "Dielectric" "X5R")
    (property "License" "Apache-2.0")
    (property "MPN" "GRM155R61H104KE14D")
    (property "Manufacturer" "Murata")
    (property "Sheetfile" "camera-interface.kicad_sch")
    (property "Sheetname" "Camera Interface")
    (property "Val" "100n")
    (property "Voltage" "50V")
    (attr smd)
    (fp_text reference "C107" (at -1.75 -0.65 90) (layer "F.SilkS")
      (effects (font (size 0.7 0.7) (thickness 0.15)) (justify left bottom))
    )
    (fp_text value "C_100n_0402" (at 0 1.4 90) (layer "F.Fab")
      (effects (font (size 0.7 0.7) (thickness 0.15)) (justify left bottom))
    )
    (fp_text user "${REFERENCE}" (at -0.932 3.168 90) (layer "F.Fab") hide
      (effects (font (size 0.7 0.7) (thickness 0.15)) (justify left bottom))
    )
    (fp_text user "Author: Antmicro" (at -0.932 4.17 90) (layer "F.Fab") hide
      (effects (font (size 0.7 0.7) (thickness 0.15)) (justify left bottom))
    )
    (fp_text user "License: Apache-2.0" (at -0.932 5.17 90) (layer "F.Fab") hide
      (effects (font (size 0.7 0.7) (thickness 0.15)) (justify left bottom))
    )
    (fp_rect (start -0.94 -0.47) (end 0.94 0.47) (layer "F.CrtYd") (width 0.05) (fill none))
    (fp_rect (start -0.499 -0.249) (end 0.499 0.249) (layer "F.Fab") (width 0.15) (fill none))
    (pad "1" smd roundrect (at -0.484 0 90) (size 0.59 0.64) (layers "F.Cu" "F.Paste" "F.Mask") (roundrect_rratio 0.25)
      (net 139 "LVS1A_1V8") (pintype "passive"))
    (pad "2" smd roundrect (at 0.484 0 90) (size 0.59 0.64) (layers "F.Cu" "F.Paste" "F.Mask") (roundrect_rratio 0.25)
      (net 1 "GND") (pintype "passive"))
  )

  (footprint "sa800u-baseboard-hw-footprints:C_0402_1005Metric" (layer "F.Cu")
    (tedit 616D63CF)
    (at 112.55 93.8 90)
    (descr "Capacitor SMD 0402")
    (tags "capacitor SMD 0402")
    (property "Author" "Antmicro")
    (property "Dielectric" "X5R")
    (property "License" "Apache-2.0")
    (property "MPN" "GRM155R61H104KE14D")
    (property "Manufacturer" "Murata")
    (property "Sheetfile" "camera-interface.kicad_sch")
    (property "Sheetname" "Camera Interface")
    (property "Val" "100n")
    (property "Voltage" "50V")
    (attr smd)
    (fp_text reference "C106" (at -3.69 0.31 90) (layer "F.SilkS")
      (effects (font (size 0.7 0.7) (thickness 0.15)) (justify left bottom))
    )
    (fp_text value "C_100n_0402" (at 0 1.4 90) (layer "F.Fab")
      (effects (font (size 0.7 0.7) (thickness 0.15)) (justify left bottom))
    )
    (fp_text user "License: Apache-2.0" (at -0.932 5.17 90) (layer "F.Fab") hide
      (effects (font (size 0.7 0.7) (thickness 0.15)) (justify left bottom))
    )
    (fp_text user "${REFERENCE}" (at -0.932 3.168 90) (layer "F.Fab") hide
      (effects (font (size 0.7 0.7) (thickness 0.15)) (justify left bottom))
    )
    (fp_text user "Author: Antmicro" (at -0.932 4.17 90) (layer "F.Fab") hide
      (effects (font (size 0.7 0.7) (thickness 0.15)) (justify left bottom))
    )
    (fp_rect (start -0.94 -0.47) (end 0.94 0.47) (layer "F.CrtYd") (width 0.05) (fill none))
    (fp_rect (start -0.499 -0.249) (end 0.499 0.249) (layer "F.Fab") (width 0.15) (fill none))
    (pad "1" smd roundrect (at -0.484 0 90) (size 0.59 0.64) (layers "F.Cu" "F.Paste" "F.Mask") (roundrect_rratio 0.25)
      (net 139 "LVS1A_1V8") (pintype "passive"))
    (pad "2" smd roundrect (at 0.484 0 90) (size 0.59 0.64) (layers "F.Cu" "F.Paste" "F.Mask") (roundrect_rratio 0.25)
      (net 1 "GND") (pintype "passive"))
  )

  (footprint "sa800u-baseboard-hw-footprints:R_0402_1005Metric" (layer "F.Cu")
    (tedit 5FD9C158)
    (at 114.3 91.85 90)
    (descr "Resistor SMD 0402")
    (tags "resistor SMD 0402")
    (property "Author" "Antmicro")
    (property "License" "Apache-2.0")
    (property "MPN" "CR0402-FX-2001GLF")
    (property "Manufacturer" "Bourns")
    (property "Sheetfile" "camera-interface.kicad_sch")
    (property "Sheetname" "Camera Interface")
    (property "Tolerance" "1%")
    (property "Val" "2k")
    (attr smd)
    (fp_text reference "R86" (at -1.01 1.17 90) (layer "F.SilkS")
      (effects (font (size 0.7 0.7) (thickness 0.15)) (justify left bottom))
    )
    (fp_text value "R_2k_0402" (at 0 1.4 90) (layer "F.Fab")
      (effects (font (size 0.7 0.7) (thickness 0.15)) (justify left bottom))
    )
    (fp_text user "${REFERENCE}" (at -0.95 3.168 90) (layer "F.Fab") hide
      (effects (font (size 0.7 0.7) (thickness 0.15)) (justify left bottom))
    )
    (fp_text user "Author: Antmicro" (at -0.95 4.169 90) (layer "F.Fab") hide
      (effects (font (size 0.7 0.7) (thickness 0.15)) (justify left bottom))
    )
    (fp_text user "License: Apache-2.0" (at -0.95 5.169 90) (layer "F.Fab") hide
      (effects (font (size 0.7 0.7) (thickness 0.15)) (justify left bottom))
    )
    (fp_rect (start -0.93 -0.47) (end 0.93 0.47) (layer "F.CrtYd") (width 0.05) (fill none))
    (fp_rect (start -0.5 -0.25) (end 0.5 0.25) (layer "F.Fab") (width 0.15) (fill none))
    (pad "1" smd roundrect (at -0.485 0 90) (size 0.59 0.64) (layers "F.Cu" "F.Paste" "F.Mask") (roundrect_rratio 0.25)
      (net 293 "/Camera Interface/CCI1_I2C_SCL_3V3") (pintype "passive"))
    (pad "2" smd roundrect (at 0.485 0 90) (size 0.59 0.64) (layers "F.Cu" "F.Paste" "F.Mask") (roundrect_rratio 0.25)
      (net 231 "/Camera Interface/3V3_CAM") (pintype "passive"))
  )

  (footprint "sa800u-baseboard-hw-footprints:R_0402_1005Metric" (layer "F.Cu")
    (tedit 5FD9C158)
    (at 113.3 91.85 90)
    (descr "Resistor SMD 0402")
    (tags "resistor SMD 0402")
    (property "Author" "Antmicro")
    (property "License" "Apache-2.0")
    (property "MPN" "CR0402-FX-2001GLF")
    (property "Manufacturer" "Bourns")
    (property "Sheetfile" "camera-interface.kicad_sch")
    (property "Sheetname" "Camera Interface")
    (property "Tolerance" "1%")
    (property "Val" "2k")
    (attr smd)
    (fp_text reference "R88" (at -1.05 -0.57 90) (layer "F.SilkS")
      (effects (font (size 0.7 0.7) (thickness 0.15)) (justify left bottom))
    )
    (fp_text value "R_2k_0402" (at 0 1.4 90) (layer "F.Fab")
      (effects (font (size 0.7 0.7) (thickness 0.15)) (justify left bottom))
    )
    (fp_text user "License: Apache-2.0" (at -0.95 5.169 90) (layer "F.Fab") hide
      (effects (font (size 0.7 0.7) (thickness 0.15)) (justify left bottom))
    )
    (fp_text user "Author: Antmicro" (at -0.95 4.169 90) (layer "F.Fab") hide
      (effects (font (size 0.7 0.7) (thickness 0.15)) (justify left bottom))
    )
    (fp_text user "${REFERENCE}" (at -0.95 3.168 90) (layer "F.Fab") hide
      (effects (font (size 0.7 0.7) (thickness 0.15)) (justify left bottom))
    )
    (fp_rect (start -0.93 -0.47) (end 0.93 0.47) (layer "F.CrtYd") (width 0.05) (fill none))
    (fp_rect (start -0.5 -0.25) (end 0.5 0.25) (layer "F.Fab") (width 0.15) (fill none))
    (pad "1" smd roundrect (at -0.485 0 90) (size 0.59 0.64) (layers "F.Cu" "F.Paste" "F.Mask") (roundrect_rratio 0.25)
      (net 295 "/Camera Interface/CCI1_I2C_SDA_3V3") (pintype "passive"))
    (pad "2" smd roundrect (at 0.485 0 90) (size 0.59 0.64) (layers "F.Cu" "F.Paste" "F.Mask") (roundrect_rratio 0.25)
      (net 231 "/Camera Interface/3V3_CAM") (pintype "passive"))
  )

  (footprint "sa800u-baseboard-hw-footprints:R_0402_1005Metric" (layer "F.Cu")
    (tedit 5FD9C158)
    (at 109.8 91.85 90)
    (descr "Resistor SMD 0402")
    (tags "resistor SMD 0402")
    (property "Author" "Antmicro")
    (property "License" "Apache-2.0")
    (property "MPN" "CR0402-FX-2001GLF")
    (property "Manufacturer" "Bourns")
    (property "Sheetfile" "camera-interface.kicad_sch")
    (property "Sheetname" "Camera Interface")
    (property "Tolerance" "1%")
    (property "Val" "2k")
    (attr smd)
    (fp_text reference "R89" (at -0.94 -1.65 90) (layer "F.SilkS")
      (effects (font (size 0.7 0.7) (thickness 0.15)) (justify left bottom))
    )
    (fp_text value "R_2k_0402" (at 0 1.4 90) (layer "F.Fab")
      (effects (font (size 0.7 0.7) (thickness 0.15)) (justify left bottom))
    )
    (fp_text user "${REFERENCE}" (at -0.95 3.168 90) (layer "F.Fab") hide
      (effects (font (size 0.7 0.7) (thickness 0.15)) (justify left bottom))
    )
    (fp_text user "License: Apache-2.0" (at -0.95 5.169 90) (layer "F.Fab") hide
      (effects (font (size 0.7 0.7) (thickness 0.15)) (justify left bottom))
    )
    (fp_text user "Author: Antmicro" (at -0.95 4.169 90) (layer "F.Fab") hide
      (effects (font (size 0.7 0.7) (thickness 0.15)) (justify left bottom))
    )
    (fp_rect (start -0.93 -0.47) (end 0.93 0.47) (layer "F.CrtYd") (width 0.05) (fill none))
    (fp_rect (start -0.5 -0.25) (end 0.5 0.25) (layer "F.Fab") (width 0.15) (fill none))
    (pad "1" smd roundrect (at -0.485 0 90) (size 0.59 0.64) (layers "F.Cu" "F.Paste" "F.Mask") (roundrect_rratio 0.25)
      (net 296 "/Camera Interface/CCI0_I2C_SDA_3V3") (pintype "passive"))
    (pad "2" smd roundrect (at 0.485 0 90) (size 0.59 0.64) (layers "F.Cu" "F.Paste" "F.Mask") (roundrect_rratio 0.25)
      (net 231 "/Camera Interface/3V3_CAM") (pintype "passive"))
  )

  (footprint "sa800u-baseboard-hw-footprints:R_0402_1005Metric" (layer "F.Cu")
    (tedit 5FD9C158)
    (at 131.1 122.3 -90)
    (descr "Resistor SMD 0402")
    (tags "resistor SMD 0402")
    (property "Author" "Antmicro")
    (property "License" "Apache-2.0")
    (property "MPN" "CR0402-FX-2201GLF")
    (property "Manufacturer" "Bourns")
    (property "Sheetfile" "usb-c-interface.kicad_sch")
    (property "Sheetname" "USB-C Interface ")
    (property "Tolerance" "1%")
    (property "Val" "2k2")
    (attr smd)
    (fp_text reference "R62" (at 1.03 0.56 -90) (layer "F.SilkS")
      (effects (font (size 0.7 0.7) (thickness 0.15)) (justify left bottom))
    )
    (fp_text value "R_2k2_0402" (at 0 1.4 -90) (layer "F.Fab")
      (effects (font (size 0.7 0.7) (thickness 0.15)) (justify left bottom))
    )
    (fp_text user "Author: Antmicro" (at -0.95 4.169 -90) (layer "F.Fab") hide
      (effects (font (size 0.7 0.7) (thickness 0.15)) (justify left bottom))
    )
    (fp_text user "${REFERENCE}" (at -0.95 3.168 -90) (layer "F.Fab") hide
      (effects (font (size 0.7 0.7) (thickness 0.15)) (justify left bottom))
    )
    (fp_text user "License: Apache-2.0" (at -0.95 5.169 -90) (layer "F.Fab") hide
      (effects (font (size 0.7 0.7) (thickness 0.15)) (justify left bottom))
    )
    (fp_rect (start -0.93 -0.47) (end 0.93 0.47) (layer "F.CrtYd") (width 0.05) (fill none))
    (fp_rect (start -0.5 -0.25) (end 0.5 0.25) (layer "F.Fab") (width 0.15) (fill none))
    (pad "1" smd roundrect (at -0.485 0 270) (size 0.59 0.64) (layers "F.Cu" "F.Paste" "F.Mask") (roundrect_rratio 0.25)
      (net 93 "SBU_SW_OE") (pintype "passive"))
    (pad "2" smd roundrect (at 0.485 0 270) (size 0.59 0.64) (layers "F.Cu" "F.Paste" "F.Mask") (roundrect_rratio 0.25)
      (net 132 "VREG_S4A_1V8") (pintype "passive"))
  )

  (footprint "sa800u-baseboard-hw-footprints:R_0402_1005Metric" (layer "F.Cu")
    (tedit 5FD9C158)
    (at 93.1 139.8 90)
    (descr "Resistor SMD 0402")
    (tags "resistor SMD 0402")
    (property "Author" "Antmicro")
    (property "License" "Apache-2.0")
    (property "MPN" "CR0402-FX-1003GLF")
    (property "Manufacturer" "Bourns")
    (property "Sheetfile" "usb-c-interface.kicad_sch")
    (property "Sheetname" "USB-C Interface ")
    (property "Tolerance" "1%")
    (property "Val" "100k")
    (attr smd)
    (fp_text reference "R58" (at 0.84 0.36 90) (layer "F.SilkS")
      (effects (font (size 0.7 0.7) (thickness 0.15)) (justify left bottom))
    )
    (fp_text value "R_100k_0402" (at 0 1.4 90) (layer "F.Fab")
      (effects (font (size 0.7 0.7) (thickness 0.15)) (justify left bottom))
    )
    (fp_text user "${REFERENCE}" (at -0.95 3.168 90) (layer "F.Fab") hide
      (effects (font (size 0.7 0.7) (thickness 0.15)) (justify left bottom))
    )
    (fp_text user "License: Apache-2.0" (at -0.95 5.169 90) (layer "F.Fab") hide
      (effects (font (size 0.7 0.7) (thickness 0.15)) (justify left bottom))
    )
    (fp_text user "Author: Antmicro" (at -0.95 4.169 90) (layer "F.Fab") hide
      (effects (font (size 0.7 0.7) (thickness 0.15)) (justify left bottom))
    )
    (fp_rect (start -0.93 -0.47) (end 0.93 0.47) (layer "F.CrtYd") (width 0.05) (fill none))
    (fp_rect (start -0.5 -0.25) (end 0.5 0.25) (layer "F.Fab") (width 0.15) (fill none))
    (pad "1" smd roundrect (at -0.485 0 90) (size 0.59 0.64) (layers "F.Cu" "F.Paste" "F.Mask") (roundrect_rratio 0.25)
      (net 328 "/USB-C Interface /USB_SBU_NP_N") (pintype "passive"))
    (pad "2" smd roundrect (at 0.485 0 90) (size 0.59 0.64) (layers "F.Cu" "F.Paste" "F.Mask") (roundrect_rratio 0.25)
      (net 1 "GND") (pintype "passive"))
  )

  (footprint "sa800u-baseboard-hw-footprints:R_0402_1005Metric" (layer "F.Cu")
    (tedit 5FD9C158)
    (at 96.1 139.8 90)
    (descr "Resistor SMD 0402")
    (tags "resistor SMD 0402")
    (property "Author" "Antmicro")
    (property "License" "Apache-2.0")
    (property "MPN" "CR0402-FX-1003GLF")
    (property "Manufacturer" "Bourns")
    (property "Sheetfile" "usb-c-interface.kicad_sch")
    (property "Sheetname" "USB-C Interface ")
    (property "Tolerance" "1%")
    (property "Val" "100k")
    (attr smd)
    (fp_text reference "R57" (at 0.87 0.43 90) (layer "F.SilkS")
      (effects (font (size 0.7 0.7) (thickness 0.15)) (justify left bottom))
    )
    (fp_text value "R_100k_0402" (at 0 1.4 90) (layer "F.Fab")
      (effects (font (size 0.7 0.7) (thickness 0.15)) (justify left bottom))
    )
    (fp_text user "License: Apache-2.0" (at -0.95 5.169 90) (layer "F.Fab") hide
      (effects (font (size 0.7 0.7) (thickness 0.15)) (justify left bottom))
    )
    (fp_text user "Author: Antmicro" (at -0.95 4.169 90) (layer "F.Fab") hide
      (effects (font (size 0.7 0.7) (thickness 0.15)) (justify left bottom))
    )
    (fp_text user "${REFERENCE}" (at -0.95 3.168 90) (layer "F.Fab") hide
      (effects (font (size 0.7 0.7) (thickness 0.15)) (justify left bottom))
    )
    (fp_rect (start -0.93 -0.47) (end 0.93 0.47) (layer "F.CrtYd") (width 0.05) (fill none))
    (fp_rect (start -0.5 -0.25) (end 0.5 0.25) (layer "F.Fab") (width 0.15) (fill none))
    (pad "1" smd roundrect (at -0.485 0 90) (size 0.59 0.64) (layers "F.Cu" "F.Paste" "F.Mask") (roundrect_rratio 0.25)
      (net 329 "/USB-C Interface /USB_SBU_NP_P") (pintype "passive"))
    (pad "2" smd roundrect (at 0.485 0 90) (size 0.59 0.64) (layers "F.Cu" "F.Paste" "F.Mask") (roundrect_rratio 0.25)
      (net 131 "3V3_SYS") (pintype "passive"))
  )

  (footprint "sa800u-baseboard-hw-footprints:C_0402_1005Metric" (layer "F.Cu")
    (tedit 616D63CF)
    (at 94.1 139.8 -90)
    (descr "Capacitor SMD 0402")
    (tags "capacitor SMD 0402")
    (property "Author" "Antmicro")
    (property "Dielectric" "X5R")
    (property "License" "Apache-2.0")
    (property "MPN" "GRM155R61H104KE14D")
    (property "Manufacturer" "Murata")
    (property "Sheetfile" "usb-c-interface.kicad_sch")
    (property "Sheetname" "USB-C Interface ")
    (property "Val" "100n")
    (property "Voltage" "50V")
    (attr smd)
    (fp_text reference "C61" (at -0.87 -0.38 -90) (layer "F.SilkS")
      (effects (font (size 0.7 0.7) (thickness 0.15)) (justify left bottom))
    )
    (fp_text value "C_100n_0402" (at 0 1.4 -90) (layer "F.Fab")
      (effects (font (size 0.7 0.7) (thickness 0.15)) (justify left bottom))
    )
    (fp_text user "Author: Antmicro" (at -0.932 4.17 -90) (layer "F.Fab") hide
      (effects (font (size 0.7 0.7) (thickness 0.15)) (justify left bottom))
    )
    (fp_text user "${REFERENCE}" (at -0.932 3.168 -90) (layer "F.Fab") hide
      (effects (font (size 0.7 0.7) (thickness 0.15)) (justify left bottom))
    )
    (fp_text user "License: Apache-2.0" (at -0.932 5.17 -90) (layer "F.Fab") hide
      (effects (font (size 0.7 0.7) (thickness 0.15)) (justify left bottom))
    )
    (fp_rect (start -0.94 -0.47) (end 0.94 0.47) (layer "F.CrtYd") (width 0.05) (fill none))
    (fp_rect (start -0.499 -0.249) (end 0.499 0.249) (layer "F.Fab") (width 0.15) (fill none))
    (pad "1" smd roundrect (at -0.484 0 270) (size 0.59 0.64) (layers "F.Cu" "F.Paste" "F.Mask") (roundrect_rratio 0.25)
      (net 10 "EDP_AUX_N") (pintype "passive"))
    (pad "2" smd roundrect (at 0.484 0 270) (size 0.59 0.64) (layers "F.Cu" "F.Paste" "F.Mask") (roundrect_rratio 0.25)
      (net 328 "/USB-C Interface /USB_SBU_NP_N") (pintype "passive"))
  )

  (footprint "sa800u-baseboard-hw-footprints:C_0402_1005Metric" (layer "F.Cu")
    (tedit 616D63CF)
    (at 94.7 145.8 -90)
    (descr "Capacitor SMD 0402")
    (tags "capacitor SMD 0402")
    (property "Author" "Antmicro")
    (property "Dielectric" "")
    (property "License" "Apache-2.0")
    (property "MPN" "C1005X6S1A105K050BC")
    (property "Manufacturer" "TDK")
    (property "Sheetfile" "usb-c-interface.kicad_sch")
    (property "Sheetname" "USB-C Interface ")
    (property "Val" "1u")
    (property "Voltage" "")
    (attr smd)
    (fp_text reference "C66" (at 1.1 -1.23 -90) (layer "F.SilkS")
      (effects (font (size 0.7 0.7) (thickness 0.15)) (justify left bottom))
    )
    (fp_text value "C_1u_0402" (at 0 1.4 -90) (layer "F.Fab")
      (effects (font (size 0.7 0.7) (thickness 0.15)) (justify left bottom))
    )
    (fp_text user "${REFERENCE}" (at -0.932 3.168 -90) (layer "F.Fab") hide
      (effects (font (size 0.7 0.7) (thickness 0.15)) (justify left bottom))
    )
    (fp_text user "Author: Antmicro" (at -0.932 4.17 -90) (layer "F.Fab") hide
      (effects (font (size 0.7 0.7) (thickness 0.15)) (justify left bottom))
    )
    (fp_text user "License: Apache-2.0" (at -0.932 5.17 -90) (layer "F.Fab") hide
      (effects (font (size 0.7 0.7) (thickness 0.15)) (justify left bottom))
    )
    (fp_rect (start -0.94 -0.47) (end 0.94 0.47) (layer "F.CrtYd") (width 0.05) (fill none))
    (fp_rect (start -0.499 -0.249) (end 0.499 0.249) (layer "F.Fab") (width 0.15) (fill none))
    (pad "1" smd roundrect (at -0.484 0 270) (size 0.59 0.64) (layers "F.Cu" "F.Paste" "F.Mask") (roundrect_rratio 0.25)
      (net 131 "3V3_SYS") (pintype "passive"))
    (pad "2" smd roundrect (at 0.484 0 270) (size 0.59 0.64) (layers "F.Cu" "F.Paste" "F.Mask") (roundrect_rratio 0.25)
      (net 1 "GND") (pintype "passive"))
  )

  (footprint "sa800u-baseboard-hw-footprints:C_0402_1005Metric" (layer "F.Cu")
    (tedit 616D63CF)
    (at 95.1 139.8 -90)
    (descr "Capacitor SMD 0402")
    (tags "capacitor SMD 0402")
    (property "Author" "Antmicro")
    (property "Dielectric" "X5R")
    (property "License" "Apache-2.0")
    (property "MPN" "GRM155R61H104KE14D")
    (property "Manufacturer" "Murata")
    (property "Sheetfile" "usb-c-interface.kicad_sch")
    (property "Sheetname" "USB-C Interface ")
    (property "Val" "100n")
    (property "Voltage" "50V")
    (attr smd)
    (fp_text reference "C60" (at -0.87 -0.39 -90) (layer "F.SilkS")
      (effects (font (size 0.7 0.7) (thickness 0.15)) (justify left bottom))
    )
    (fp_text value "C_100n_0402" (at 0 1.4 -90) (layer "F.Fab")
      (effects (font (size 0.7 0.7) (thickness 0.15)) (justify left bottom))
    )
    (fp_text user "License: Apache-2.0" (at -0.932 5.17 -90) (layer "F.Fab") hide
      (effects (font (size 0.7 0.7) (thickness 0.15)) (justify left bottom))
    )
    (fp_text user "${REFERENCE}" (at -0.932 3.168 -90) (layer "F.Fab") hide
      (effects (font (size 0.7 0.7) (thickness 0.15)) (justify left bottom))
    )
    (fp_text user "Author: Antmicro" (at -0.932 4.17 -90) (layer "F.Fab") hide
      (effects (font (size 0.7 0.7) (thickness 0.15)) (justify left bottom))
    )
    (fp_rect (start -0.94 -0.47) (end 0.94 0.47) (layer "F.CrtYd") (width 0.05) (fill none))
    (fp_rect (start -0.499 -0.249) (end 0.499 0.249) (layer "F.Fab") (width 0.15) (fill none))
    (pad "1" smd roundrect (at -0.484 0 270) (size 0.59 0.64) (layers "F.Cu" "F.Paste" "F.Mask") (roundrect_rratio 0.25)
      (net 11 "EDP_AUX_P") (pintype "passive"))
    (pad "2" smd roundrect (at 0.484 0 270) (size 0.59 0.64) (layers "F.Cu" "F.Paste" "F.Mask") (roundrect_rratio 0.25)
      (net 329 "/USB-C Interface /USB_SBU_NP_P") (pintype "passive"))
  )

  (footprint "sa800u-baseboard-hw-footprints:XQFN-10-1.4x1.8mm_P0.4mm" (layer "F.Cu")
    (tedit 6206D50C)
    (at 94.8 142.9 180)
    (property "Author" "Antmicro")
    (property "License" "Apache-2.0")
    (property "MPN" "NX3DV42GU,115")
    (property "Manufacturer" "NXP")
    (property "Sheetfile" "usb-c-interface.kicad_sch")
    (property "Sheetname" "USB-C Interface ")
    (attr smd)
    (fp_text reference "U7" (at -0.43 1.18 180) (layer "F.SilkS")
      (effects (font (size 0.7 0.7) (thickness 0.15)) (justify left bottom))
    )
    (fp_text value "NX3DV42GU" (at 0 2.3 180) (layer "F.Fab")
      (effects (font (size 0.7 0.7) (thickness 0.15)) (justify left bottom))
    )
    (fp_text user "Author: Antmicro" (at -1.2 6.299 180) (layer "F.Fab") hide
      (effects (font (size 0.7 0.7) (thickness 0.15)) (justify left bottom))
    )
    (fp_text user "License: Apache-2.0" (at -1.2 7.499 180) (layer "F.Fab") hide
      (effects (font (size 0.7 0.7) (thickness 0.15)) (justify left bottom))
    )
    (fp_text user "${REFERENCE}" (at -1.2 5.099 180) (layer "F.Fab") hide
      (effects (font (size 0.7 0.7) (thickness 0.15)) (justify left bottom))
    )
    (fp_line (start -0.802 0.998) (end -0.652 0.998) (layer "F.SilkS") (width 0.15))
    (fp_line (start 0.8 -1) (end 0.8 -0.5) (layer "F.SilkS") (width 0.15))
    (fp_line (start 0.8 0.998) (end 0.65 0.998) (layer "F.SilkS") (width 0.15))
    (fp_line (start -0.802 -1) (end -0.61 -1) (layer "F.SilkS") (width 0.15))
    (fp_line (start -0.802 0.998) (end -0.802 0.498) (layer "F.SilkS") (width 0.15))
    (fp_line (start 0.8 0.498) (end 0.8 0.998) (layer "F.SilkS") (width 0.15))
    (fp_line (start 0.8 -1) (end 0.65 -1) (layer "F.SilkS") (width 0.15))
    (fp_circle (center -1 -0.5) (end -0.95 -0.5) (layer "F.SilkS") (width 0.15) (fill solid))
    (fp_rect (start -1.1 -1.35) (end 1.1 1.35) (layer "F.CrtYd") (width 0.05) (fill none))
    (fp_line (start -0.6 -0.951) (end -0.75 -0.802) (layer "F.Fab") (width 0.15))
    (fp_line (start 0.748 -0.951) (end -0.6 -0.951) (layer "F.Fab") (width 0.15))
    (fp_line (start -0.75 0.949) (end -0.75 -0.802) (layer "F.Fab") (width 0.15))
    (fp_line (start 0.748 -0.951) (end 0.748 0.949) (layer "F.Fab") (width 0.15))
    (fp_line (start -0.75 0.949) (end 0.748 0.949) (layer "F.Fab") (width 0.15))
    (pad "1" smd rect (at -0.677 -0.202 270) (size 0.25 0.8) (drill (offset 0 0.05)) (layers "F.Cu" "F.Paste" "F.Mask")
      (net 330 "/USB-C Interface /USB1_SBU_N") (pinfunction "D+") (pintype "bidirectional"))
    (pad "2" smd rect (at -0.677 0.2 270) (size 0.25 0.7) (layers "F.Cu" "F.Paste" "F.Mask")
      (net 331 "/USB-C Interface /USB1_SBU_P") (pinfunction "D-") (pintype "bidirectional"))
    (pad "3" smd rect (at -0.402 0.925 180) (size 0.25 0.7) (layers "F.Cu" "F.Paste" "F.Mask")
      (net 1 "GND") (pinfunction "GND") (pintype "power_in"))
    (pad "4" smd rect (at 0 0.925 180) (size 0.25 0.7) (layers "F.Cu" "F.Paste" "F.Mask")
      (net 329 "/USB-C Interface /USB_SBU_NP_P") (pinfunction "HSD1-") (pintype "bidirectional"))
    (pad "5" smd rect (at 0.4 0.925 180) (size 0.25 0.7) (layers "F.Cu" "F.Paste" "F.Mask")
      (net 328 "/USB-C Interface /USB_SBU_NP_N") (pinfunction "HSD1+") (pintype "bidirectional"))
    (pad "6" smd rect (at 0.675 0.2 270) (size 0.25 0.7) (layers "F.Cu" "F.Paste" "F.Mask")
      (net 329 "/USB-C Interface /USB_SBU_NP_P") (pinfunction "HSD2-") (pintype "bidirectional"))
    (pad "7" smd rect (at 0.675 -0.202 270) (size 0.25 0.7) (layers "F.Cu" "F.Paste" "F.Mask")
      (net 328 "/USB-C Interface /USB_SBU_NP_N") (pinfunction "HSD2+") (pintype "bidirectional"))
    (pad "8" smd rect (at 0.4 -0.927 180) (size 0.25 0.7) (layers "F.Cu" "F.Paste" "F.Mask")
      (net 93 "SBU_SW_OE") (pinfunction "~{OE}") (pintype "input"))
    (pad "9" smd rect (at 0 -0.927 180) (size 0.25 0.7) (layers "F.Cu" "F.Paste" "F.Mask")
      (net 131 "3V3_SYS") (pinfunction "VCC") (pintype "power_in"))
    (pad "10" smd rect (at -0.402 -0.927 180) (size 0.25 0.7) (layers "F.Cu" "F.Paste" "F.Mask")
      (net 98 "SBU_SW_SEL") (pinfunction "SEL") (pintype "input"))
  )

  (footprint "sa800u-baseboard-hw-footprints:L_Murata_025020_0605Metric" (layer "F.Cu")
    (tedit 61AA2C4F)
    (at 152 118.5)
    (property "Author" "Antmicro")
    (property "License" "Apache-2.0")
    (property "MPN" "NFP0QHB242HS2D")
    (property "Manufacturer" "Murata")
    (property "Sheetfile" "lcm.kicad_sch")
    (property "Sheetname" "LCM")
    (attr smd)
    (fp_text reference "L11" (at -0.99 -0.72) (layer "F.SilkS")
      (effects (font (size 0.7 0.7) (thickness 0.15)) (justify left bottom))
    )
    (fp_text value "NFP0QHB242HS2D" (at 0 1.55) (layer "F.Fab")
      (effects (font (size 0.7 0.7) (thickness 0.15)) (justify left bottom))
    )
    (fp_text user "Author: Antmicro" (at -1.027 4.605) (layer "F.Fab") hide
      (effects (font (size 0.7 0.7) (thickness 0.15)) (justify left bottom))
    )
    (fp_text user "License: Apache-2.0" (at -1.027 5.805) (layer "F.Fab") hide
      (effects (font (size 0.7 0.7) (thickness 0.15)) (justify left bottom))
    )
    (fp_text user "${REFERENCE}" (at -1.027 3.406) (layer "F.Fab") hide
      (effects (font (size 0.7 0.7) (thickness 0.15)) (justify left bottom))
    )
    (fp_line (start 0.276 -0.45) (end -0.276 -0.45) (layer "F.SilkS") (width 0.15))
    (fp_line (start -0.276 0.45) (end 0.276 0.45) (layer "F.SilkS") (width 0.15))
    (fp_circle (center -0.5 -0.5) (end -0.449 -0.5) (layer "F.SilkS") (width 0.15) (fill solid))
    (fp_rect (start -0.5 -0.6) (end 0.5 0.6) (layer "F.CrtYd") (width 0.05) (fill none))
    (fp_line (start -0.277 -0.351) (end -0.277 0.349) (layer "F.Fab") (width 0.15))
    (fp_line (start 0.275 -0.351) (end -0.277 -0.351) (layer "F.Fab") (width 0.15))
    (fp_line (start -0.277 0.349) (end 0.275 0.349) (layer "F.Fab") (width 0.15))
    (fp_line (start 0.275 0.349) (end 0.275 -0.351) (layer "F.Fab") (width 0.15))
    (pad "1" smd rect (at -0.25 -0.24) (size 0.3 0.23) (layers "F.Cu" "F.Paste" "F.Mask")
      (net 318 "/LCM/DSI_LN3_L_N") (pinfunction "1") (pintype "passive"))
    (pad "2" smd rect (at 0.248 -0.24) (size 0.3 0.23) (layers "F.Cu" "F.Paste" "F.Mask")
      (net 90 "DSI0_LN3_N") (pinfunction "2") (pintype "passive"))
    (pad "3" smd rect (at 0.248 0.239) (size 0.3 0.23) (layers "F.Cu" "F.Paste" "F.Mask")
      (net 89 "DSI0_LN3_P") (pinfunction "3") (pintype "passive"))
    (pad "4" smd rect (at -0.25 0.239) (size 0.3 0.23) (layers "F.Cu" "F.Paste" "F.Mask")
      (net 317 "/LCM/DSI_LN3_L_P") (pinfunction "4") (pintype "passive"))
  )

  (footprint "sa800u-baseboard-hw-footprints:C_0402_1005Metric" (layer "F.Cu")
    (tedit 616D63CF)
    (at 112.85 109.4 180)
    (descr "Capacitor SMD 0402")
    (tags "capacitor SMD 0402")
    (property "Author" "Antmicro")
    (property "Dielectric" "X5R")
    (property "License" "Apache-2.0")
    (property "MPN" "GRM155R61H104KE14D")
    (property "Manufacturer" "Murata")
    (property "Sheetfile" "other-interfaces.kicad_sch")
    (property "Sheetname" "Other Interfaces")
    (property "Val" "100n")
    (property "Voltage" "50V")
    (attr smd)
    (fp_text reference "C117" (at 1.86 -1.33 180) (layer "F.SilkS")
      (effects (font (size 0.7 0.7) (thickness 0.15)) (justify left bottom))
    )
    (fp_text value "C_100n_0402" (at 0 1.4 180) (layer "F.Fab")
      (effects (font (size 0.7 0.7) (thickness 0.15)) (justify left bottom))
    )
    (fp_text user "License: Apache-2.0" (at -0.932 5.17 180) (layer "F.Fab") hide
      (effects (font (size 0.7 0.7) (thickness 0.15)) (justify left bottom))
    )
    (fp_text user "${REFERENCE}" (at -0.932 3.168 180) (layer "F.Fab") hide
      (effects (font (size 0.7 0.7) (thickness 0.15)) (justify left bottom))
    )
    (fp_text user "Author: Antmicro" (at -0.932 4.17 180) (layer "F.Fab") hide
      (effects (font (size 0.7 0.7) (thickness 0.15)) (justify left bottom))
    )
    (fp_rect (start -0.94 -0.47) (end 0.94 0.47) (layer "F.CrtYd") (width 0.05) (fill none))
    (fp_rect (start -0.499 -0.249) (end 0.499 0.249) (layer "F.Fab") (width 0.15) (fill none))
    (pad "1" smd roundrect (at -0.484 0 180) (size 0.59 0.64) (layers "F.Cu" "F.Paste" "F.Mask") (roundrect_rratio 0.25)
      (net 132 "VREG_S4A_1V8") (pintype "passive"))
    (pad "2" smd roundrect (at 0.484 0 180) (size 0.59 0.64) (layers "F.Cu" "F.Paste" "F.Mask") (roundrect_rratio 0.25)
      (net 1 "GND") (pintype "passive"))
  )

  (footprint "sa800u-baseboard-hw-footprints:C_0402_1005Metric" (layer "F.Cu")
    (tedit 616D63CF)
    (at 114.75 109.4)
    (descr "Capacitor SMD 0402")
    (tags "capacitor SMD 0402")
    (property "Author" "Antmicro")
    (property "Dielectric" "X5R")
    (property "License" "Apache-2.0")
    (property "MPN" "GRM155R61H104KE14D")
    (property "Manufacturer" "Murata")
    (property "Sheetfile" "other-interfaces.kicad_sch")
    (property "Sheetname" "Other Interfaces")
    (property "Val" "100n")
    (property "Voltage" "50V")
    (attr smd)
    (fp_text reference "C120" (at -1.05 1.29) (layer "F.SilkS")
      (effects (font (size 0.7 0.7) (thickness 0.15)) (justify left bottom))
    )
    (fp_text value "C_100n_0402" (at 0 1.4) (layer "F.Fab")
      (effects (font (size 0.7 0.7) (thickness 0.15)) (justify left bottom))
    )
    (fp_text user "License: Apache-2.0" (at -0.932 5.17) (layer "F.Fab") hide
      (effects (font (size 0.7 0.7) (thickness 0.15)) (justify left bottom))
    )
    (fp_text user "Author: Antmicro" (at -0.932 4.17) (layer "F.Fab") hide
      (effects (font (size 0.7 0.7) (thickness 0.15)) (justify left bottom))
    )
    (fp_text user "${REFERENCE}" (at -0.932 3.168) (layer "F.Fab") hide
      (effects (font (size 0.7 0.7) (thickness 0.15)) (justify left bottom))
    )
    (fp_rect (start -0.94 -0.47) (end 0.94 0.47) (layer "F.CrtYd") (width 0.05) (fill none))
    (fp_rect (start -0.499 -0.249) (end 0.499 0.249) (layer "F.Fab") (width 0.15) (fill none))
    (pad "1" smd roundrect (at -0.484 0) (size 0.59 0.64) (layers "F.Cu" "F.Paste" "F.Mask") (roundrect_rratio 0.25)
      (net 131 "3V3_SYS") (pintype "passive"))
    (pad "2" smd roundrect (at 0.484 0) (size 0.59 0.64) (layers "F.Cu" "F.Paste" "F.Mask") (roundrect_rratio 0.25)
      (net 1 "GND") (pintype "passive"))
  )

  (footprint "sa800u-baseboard-hw-footprints:BM04B-SRSS-TB-LF-SN" (layer "F.Cu")
    (tedit 616FBFD6)
    (at 146.2 85.9 -90)
    (property "Author" "Antmicro")
    (property "License" "Apache-2.0")
    (property "MPN" "BM04B-SRSS-TB(LF)(SN) ")
    (property "Manufacturer" "JST")
    (property "Sheetfile" "other-interfaces.kicad_sch")
    (property "Sheetname" "Other Interfaces")
    (attr smd)
    (fp_text reference "J9" (at 3.49 1.47 -90) (layer "F.SilkS")
      (effects (font (size 0.7 0.7) (thickness 0.15)) (justify left bottom))
    )
    (fp_text value "BM04B-SRSS-TB-LF-SN" (at 0.0508 3.302 -90) (layer "F.Fab")
      (effects (font (size 0.7 0.7) (thickness 0.15)) (justify left bottom))
    )
    (fp_text user "Author: Antmicro" (at -3.65 5.302 -90) (layer "F.Fab") hide
      (effects (font (size 0.7 0.7) (thickness 0.15)) (justify left bottom))
    )
    (fp_text user "License: Apache-2.0" (at -3.65 7.702 -90) (layer "F.Fab") hide
      (effects (font (size 0.7 0.7) (thickness 0.15)) (justify left bottom))
    )
    (fp_text user "${REFERENCE}" (at -3.65 6.502 -90) (layer "F.Fab") hide
      (effects (font (size 0.7 0.7) (thickness 0.15)) (justify left bottom))
    )
    (fp_line (start -1.7005 -1.8495) (end 1.7015 -1.8495) (layer "F.SilkS") (width 0.15))
    (fp_line (start -2.999 0.1765) (end -2.999 1.0505) (layer "F.SilkS") (width 0.15))
    (fp_line (start 2.9995 0.1765) (end 2.9995 1.0505) (layer "F.SilkS") (width 0.15))
    (fp_line (start -2.999 1.0505) (end -2.201 1.0505) (layer "F.SilkS") (width 0.15))
    (fp_line (start 2.9995 1.0505) (end 2.2015 1.0505) (layer "F.SilkS") (width 0.15))
    (fp_circle (center -2.1 2.1) (end -2.049 2.1) (layer "F.SilkS") (width 0.15) (fill solid))
    (fp_line (start -3.6495 2.3805) (end -3.6495 -2.1839) (layer "F.CrtYd") (width 0.05))
    (fp_line (start 3.6505 -2.1839) (end 3.6505 2.3805) (layer "F.CrtYd") (width 0.05))
    (fp_line (start 3.6505 2.3805) (end -3.6495 2.3805) (layer "F.CrtYd") (width 0.05))
    (fp_line (start -3.6495 -2.1839) (end 3.6505 -2.1839) (layer "F.CrtYd") (width 0.05))
    (fp_line (start 3.008 1.7785) (end -1.991 1.7785) (layer "F.Fab") (width 0.15))
    (fp_line (start -2.9995 -1.8495) (end 2.9995 -1.8495) (layer "F.Fab") (width 0.15))
    (fp_line (start 2.9995 -1.8495) (end 3.008 1.7785) (layer "F.Fab") (width 0.15))
    (fp_line (start -1.991 1.7785) (end -2.9995 0.9657) (layer "F.Fab") (width 0.15))
    (fp_line (start -2.9995 1.0165) (end -2.9995 -1.8495) (layer "F.Fab") (width 0.15))
    (pad "1" smd rect (at -1.4995 1.3765 270) (size 0.6 1.55) (layers "F.Cu" "F.Paste" "F.Mask")
      (net 1 "GND") (pinfunction "Pin_1") (pintype "passive"))
    (pad "2" smd rect (at -0.5015 1.3765 270) (size 0.6 1.55) (layers "F.Cu" "F.Paste" "F.Mask")
      (net 131 "3V3_SYS") (pinfunction "Pin_2") (pintype "passive"))
    (pad "3" smd rect (at 0.4995 1.3765 270) (size 0.6 1.55) (layers "F.Cu" "F.Paste" "F.Mask")
      (net 338 "/Other Interfaces/I2C10_SDA_3V3") (pinfunction "Pin_3") (pintype "passive"))
    (pad "4" smd rect (at 1.4995 1.3765 270) (size 0.6 1.55) (layers "F.Cu" "F.Paste" "F.Mask")
      (net 337 "/Other Interfaces/I2C10_SCL_3V3") (pinfunction "Pin_4") (pintype "passive"))
    (pad "MP" smd rect (at 2.8005 -1.1485 270) (size 1.2 1.8) (layers "F.Cu" "F.Paste" "F.Mask")
      (net 661 "unconnected-(J9-PadMP)") (pinfunction "MP") (pintype "passive+no_connect"))
    (pad "MP" smd rect (at -2.7995 -1.1485 270) (size 1.2 1.8) (layers "F.Cu" "F.Paste" "F.Mask")
      (net 661 "unconnected-(J9-PadMP)") (pinfunction "MP") (pintype "passive+no_connect"))
  )

  (footprint "sa800u-baseboard-hw-footprints:R_0402_1005Metric" (layer "F.Cu")
    (tedit 5FD9C158)
    (at 116.2 108.2)
    (descr "Resistor SMD 0402")
    (tags "resistor SMD 0402")
    (property "Author" "Antmicro")
    (property "License" "Apache-2.0")
    (property "MPN" "CR0402-FX-2001GLF")
    (property "Manufacturer" "Bourns")
    (property "Sheetfile" "other-interfaces.kicad_sch")
    (property "Sheetname" "Other Interfaces")
    (property "Tolerance" "1%")
    (property "Val" "2k")
    (attr smd)
    (fp_text reference "R103" (at 0.81 0.07) (layer "F.SilkS")
      (effects (font (size 0.7 0.7) (thickness 0.15)) (justify left bottom))
    )
    (fp_text value "R_2k_0402" (at 0 1.4) (layer "F.Fab")
      (effects (font (size 0.7 0.7) (thickness 0.15)) (justify left bottom))
    )
    (fp_text user "License: Apache-2.0" (at -0.95 5.169) (layer "F.Fab") hide
      (effects (font (size 0.7 0.7) (thickness 0.15)) (justify left bottom))
    )
    (fp_text user "${REFERENCE}" (at -0.95 3.168) (layer "F.Fab") hide
      (effects (font (size 0.7 0.7) (thickness 0.15)) (justify left bottom))
    )
    (fp_text user "Author: Antmicro" (at -0.95 4.169) (layer "F.Fab") hide
      (effects (font (size 0.7 0.7) (thickness 0.15)) (justify left bottom))
    )
    (fp_rect (start -0.93 -0.47) (end 0.93 0.47) (layer "F.CrtYd") (width 0.05) (fill none))
    (fp_rect (start -0.5 -0.25) (end 0.5 0.25) (layer "F.Fab") (width 0.15) (fill none))
    (pad "1" smd roundrect (at -0.485 0) (size 0.59 0.64) (layers "F.Cu" "F.Paste" "F.Mask") (roundrect_rratio 0.25)
      (net 337 "/Other Interfaces/I2C10_SCL_3V3") (pintype "passive"))
    (pad "2" smd roundrect (at 0.485 0) (size 0.59 0.64) (layers "F.Cu" "F.Paste" "F.Mask") (roundrect_rratio 0.25)
      (net 131 "3V3_SYS") (pintype "passive"))
  )

  (footprint "sa800u-baseboard-hw-footprints:R_0402_1005Metric" (layer "F.Cu")
    (tedit 5FD9C158)
    (at 116.2 107.2)
    (descr "Resistor SMD 0402")
    (tags "resistor SMD 0402")
    (property "Author" "Antmicro")
    (property "License" "Apache-2.0")
    (property "MPN" "CR0402-FX-2001GLF")
    (property "Manufacturer" "Bourns")
    (property "Sheetfile" "other-interfaces.kicad_sch")
    (property "Sheetname" "Other Interfaces")
    (property "Tolerance" "1%")
    (property "Val" "2k")
    (attr smd)
    (fp_text reference "R104" (at 0.81 0.07) (layer "F.SilkS")
      (effects (font (size 0.7 0.7) (thickness 0.15)) (justify left bottom))
    )
    (fp_text value "R_2k_0402" (at 0 1.4) (layer "F.Fab")
      (effects (font (size 0.7 0.7) (thickness 0.15)) (justify left bottom))
    )
    (fp_text user "${REFERENCE}" (at -0.95 3.168) (layer "F.Fab") hide
      (effects (font (size 0.7 0.7) (thickness 0.15)) (justify left bottom))
    )
    (fp_text user "Author: Antmicro" (at -0.95 4.169) (layer "F.Fab") hide
      (effects (font (size 0.7 0.7) (thickness 0.15)) (justify left bottom))
    )
    (fp_text user "License: Apache-2.0" (at -0.95 5.169) (layer "F.Fab") hide
      (effects (font (size 0.7 0.7) (thickness 0.15)) (justify left bottom))
    )
    (fp_rect (start -0.93 -0.47) (end 0.93 0.47) (layer "F.CrtYd") (width 0.05) (fill none))
    (fp_rect (start -0.5 -0.25) (end 0.5 0.25) (layer "F.Fab") (width 0.15) (fill none))
    (pad "1" smd roundrect (at -0.485 0) (size 0.59 0.64) (layers "F.Cu" "F.Paste" "F.Mask") (roundrect_rratio 0.25)
      (net 338 "/Other Interfaces/I2C10_SDA_3V3") (pintype "passive"))
    (pad "2" smd roundrect (at 0.485 0) (size 0.59 0.64) (layers "F.Cu" "F.Paste" "F.Mask") (roundrect_rratio 0.25)
      (net 131 "3V3_SYS") (pintype "passive"))
  )

  (footprint "sa800u-baseboard-hw-footprints:XSON-8_1x1.95mm_P0.5mm" (layer "F.Cu")
    (tedit 5DCD5522)
    (at 113.8 107.7 -90)
    (property "Author" "Antmicro")
    (property "License" "Apache-2.0")
    (property "MPN" "NTS0102GT")
    (property "Manufacturer" "NXP")
    (property "Sheetfile" "other-interfaces.kicad_sch")
    (property "Sheetname" "Other Interfaces")
    (attr smd)
    (fp_text reference "U16" (at 0.99 1.4 90) (layer "F.SilkS")
      (effects (font (size 0.7 0.7) (thickness 0.15)) (justify left bottom))
    )
    (fp_text value "NTS0102_XSON" (at 0 2.2 -90) (layer "F.Fab")
      (effects (font (size 0.7 0.7) (thickness 0.15)) (justify left bottom))
    )
    (fp_text user "License: Apache-2.0" (at -0.527 8.306 -90) (layer "F.Fab") hide
      (effects (font (size 0.7 0.7) (thickness 0.15)) (justify left bottom))
    )
    (fp_text user "Author: Antmicro" (at -0.527 7.105 -90) (layer "F.Fab") hide
      (effects (font (size 0.7 0.7) (thickness 0.15)) (justify left bottom))
    )
    (fp_text user "${REFERENCE}" (at -0.527 5.905 -90) (layer "F.Fab") hide
      (effects (font (size 0.7 0.7) (thickness 0.15)) (justify left bottom))
    )
    (fp_line (start 0.5 1.1) (end -0.5 1.1) (layer "F.SilkS") (width 0.15))
    (fp_line (start -0.5 -1.1) (end 0.5 -1.1) (layer "F.SilkS") (width 0.15))
    (fp_circle (center -0.7 -0.95) (end -0.651 -0.95) (layer "F.SilkS") (width 0.15) (fill none))
    (fp_rect (start -0.8 -1.2) (end 0.8 1.2) (layer "F.CrtYd") (width 0.05) (fill none))
    (fp_line (start -0.5305 1) (end -0.5305 -1.001) (layer "F.Fab") (width 0.15))
    (fp_line (start 0.5305 1) (end -0.5305 1) (layer "F.Fab") (width 0.15))
    (fp_line (start 0.5305 -1.001) (end 0.5305 1) (layer "F.Fab") (width 0.15))
    (fp_line (start -0.5305 -1.001) (end 0.5305 -1.001) (layer "F.Fab") (width 0.15))
    (pad "1" smd rect (at -0.33 -0.75 270) (size 0.5 0.31) (layers "F.Cu" "F.Paste" "F.Mask")
      (net 338 "/Other Interfaces/I2C10_SDA_3V3") (pinfunction "B_{2}") (pintype "bidirectional"))
    (pad "2" smd rect (at -0.33 -0.25 270) (size 0.5 0.31) (layers "F.Cu" "F.Paste" "F.Mask")
      (net 1 "GND") (pinfunction "GND") (pintype "power_in"))
    (pad "3" smd rect (at -0.33 0.25 270) (size 0.5 0.31) (layers "F.Cu" "F.Paste" "F.Mask")
      (net 132 "VREG_S4A_1V8") (pinfunction "VCC_{A}") (pintype "power_in"))
    (pad "4" smd rect (at -0.33 0.75 270) (size 0.5 0.31) (layers "F.Cu" "F.Paste" "F.Mask")
      (net 151 "I2C10_SDA") (pinfunction "A_{2}") (pintype "bidirectional"))
    (pad "5" smd rect (at 0.33 0.75 90) (size 0.5 0.31) (layers "F.Cu" "F.Paste" "F.Mask")
      (net 150 "I2C10_SCL") (pinfunction "A_{1}") (pintype "bidirectional"))
    (pad "6" smd rect (at 0.33 0.25 90) (size 0.5 0.31) (layers "F.Cu" "F.Paste" "F.Mask")
      (net 132 "VREG_S4A_1V8") (pinfunction "OE") (pintype "input"))
    (pad "7" smd rect (at 0.33 -0.25 90) (size 0.5 0.31) (layers "F.Cu" "F.Paste" "F.Mask")
      (net 131 "3V3_SYS") (pinfunction "VCC_{B}") (pintype "power_in"))
    (pad "8" smd rect (at 0.33 -0.75 90) (size 0.5 0.31) (layers "F.Cu" "F.Paste" "F.Mask")
      (net 337 "/Other Interfaces/I2C10_SCL_3V3") (pinfunction "B_{1}") (pintype "bidirectional"))
  )

  (footprint "sa800u-baseboard-hw-footprints:R_0402_1005Metric" (layer "F.Cu")
    (tedit 5FD9C158)
    (at 122.8 106.8)
    (descr "Resistor SMD 0402")
    (tags "resistor SMD 0402")
    (property "Author" "Antmicro")
    (property "License" "Apache-2.0")
    (property "MPN" "CR0402-FX-2001GLF")
    (property "Manufacturer" "Bourns")
    (property "Sheetfile" "lcm.kicad_sch")
    (property "Sheetname" "LCM")
    (property "Tolerance" "1%")
    (property "Val" "2k")
    (attr smd)
    (fp_text reference "R68" (at 0.79 0.39) (layer "F.SilkS")
      (effects (font (size 0.7 0.7) (thickness 0.15)) (justify left bottom))
    )
    (fp_text value "R_2k_0402" (at 0 1.4) (layer "F.Fab")
      (effects (font (size 0.7 0.7) (thickness 0.15)) (justify left bottom))
    )
    (fp_text user "License: Apache-2.0" (at -0.95 5.169) (layer "F.Fab") hide
      (effects (font (size 0.7 0.7) (thickness 0.15)) (justify left bottom))
    )
    (fp_text user "Author: Antmicro" (at -0.95 4.169) (layer "F.Fab") hide
      (effects (font (size 0.7 0.7) (thickness 0.15)) (justify left bottom))
    )
    (fp_text user "${REFERENCE}" (at -0.95 3.168) (layer "F.Fab") hide
      (effects (font (size 0.7 0.7) (thickness 0.15)) (justify left bottom))
    )
    (fp_rect (start -0.93 -0.47) (end 0.93 0.47) (layer "F.CrtYd") (width 0.05) (fill none))
    (fp_rect (start -0.5 -0.25) (end 0.5 0.25) (layer "F.Fab") (width 0.15) (fill none))
    (pad "1" smd roundrect (at -0.485 0) (size 0.59 0.64) (layers "F.Cu" "F.Paste" "F.Mask") (roundrect_rratio 0.25)
      (net 149 "/LCM/TP_I2C_SDA_3V3") (pintype "passive"))
    (pad "2" smd roundrect (at 0.485 0) (size 0.59 0.64) (layers "F.Cu" "F.Paste" "F.Mask") (roundrect_rratio 0.25)
      (net 131 "3V3_SYS") (pintype "passive"))
  )

  (footprint "sa800u-baseboard-hw-footprints:R_0402_1005Metric" (layer "F.Cu")
    (tedit 5FD9C158)
    (at 113.3 96.75 -90)
    (descr "Resistor SMD 0402")
    (tags "resistor SMD 0402")
    (property "Author" "Antmicro")
    (property "License" "Apache-2.0")
    (property "MPN" "CR0402-FX-2001GLF")
    (property "Manufacturer" "Bourns")
    (property "Sheetfile" "camera-interface.kicad_sch")
    (property "Sheetname" "Camera Interface")
    (property "Tolerance" "1%")
    (property "Val" "2k")
    (attr smd)
    (fp_text reference "R80" (at 3.05 -0.35 -90) (layer "F.SilkS")
      (effects (font (size 0.7 0.7) (thickness 0.15)) (justify left bottom))
    )
    (fp_text value "R_2k_0402" (at 0 1.4 -90) (layer "F.Fab")
      (effects (font (size 0.7 0.7) (thickness 0.15)) (justify left bottom))
    )
    (fp_text user "License: Apache-2.0" (at -0.95 5.169 -90) (layer "F.Fab") hide
      (effects (font (size 0.7 0.7) (thickness 0.15)) (justify left bottom))
    )
    (fp_text user "${REFERENCE}" (at -0.95 3.168 -90) (layer "F.Fab") hide
      (effects (font (size 0.7 0.7) (thickness 0.15)) (justify left bottom))
    )
    (fp_text user "Author: Antmicro" (at -0.95 4.169 -90) (layer "F.Fab") hide
      (effects (font (size 0.7 0.7) (thickness 0.15)) (justify left bottom))
    )
    (fp_rect (start -0.93 -0.47) (end 0.93 0.47) (layer "F.CrtYd") (width 0.05) (fill none))
    (fp_rect (start -0.5 -0.25) (end 0.5 0.25) (layer "F.Fab") (width 0.15) (fill none))
    (pad "1" smd roundrect (at -0.485 0 270) (size 0.59 0.64) (layers "F.Cu" "F.Paste" "F.Mask") (roundrect_rratio 0.25)
      (net 45 "CCI1_I2C_SDA") (pintype "passive"))
    (pad "2" smd roundrect (at 0.485 0 270) (size 0.59 0.64) (layers "F.Cu" "F.Paste" "F.Mask") (roundrect_rratio 0.25)
      (net 139 "LVS1A_1V8") (pintype "passive"))
  )

  (footprint "sa800u-baseboard-hw-footprints:R_0402_1005Metric" (layer "F.Cu")
    (tedit 5FD9C158)
    (at 109.8 96.75 -90)
    (descr "Resistor SMD 0402")
    (tags "resistor SMD 0402")
    (property "Author" "Antmicro")
    (property "License" "Apache-2.0")
    (property "MPN" "CR0402-FX-2001GLF")
    (property "Manufacturer" "Bourns")
    (property "Sheetfile" "camera-interface.kicad_sch")
    (property "Sheetname" "Camera Interface")
    (property "Tolerance" "1%")
    (property "Val" "2k")
    (attr smd)
    (fp_text reference "R81" (at 3.05 -0.36 -90) (layer "F.SilkS")
      (effects (font (size 0.7 0.7) (thickness 0.15)) (justify left bottom))
    )
    (fp_text value "R_2k_0402" (at 0 1.4 -90) (layer "F.Fab")
      (effects (font (size 0.7 0.7) (thickness 0.15)) (justify left bottom))
    )
    (fp_text user "License: Apache-2.0" (at -0.95 5.169 -90) (layer "F.Fab") hide
      (effects (font (size 0.7 0.7) (thickness 0.15)) (justify left bottom))
    )
    (fp_text user "Author: Antmicro" (at -0.95 4.169 -90) (layer "F.Fab") hide
      (effects (font (size 0.7 0.7) (thickness 0.15)) (justify left bottom))
    )
    (fp_text user "${REFERENCE}" (at -0.95 3.168 -90) (layer "F.Fab") hide
      (effects (font (size 0.7 0.7) (thickness 0.15)) (justify left bottom))
    )
    (fp_rect (start -0.93 -0.47) (end 0.93 0.47) (layer "F.CrtYd") (width 0.05) (fill none))
    (fp_rect (start -0.5 -0.25) (end 0.5 0.25) (layer "F.Fab") (width 0.15) (fill none))
    (pad "1" smd roundrect (at -0.485 0 270) (size 0.59 0.64) (layers "F.Cu" "F.Paste" "F.Mask") (roundrect_rratio 0.25)
      (net 43 "CCI0_I2C_SDA") (pintype "passive"))
    (pad "2" smd roundrect (at 0.485 0 270) (size 0.59 0.64) (layers "F.Cu" "F.Paste" "F.Mask") (roundrect_rratio 0.25)
      (net 139 "LVS1A_1V8") (pintype "passive"))
  )

  (footprint "sa800u-baseboard-hw-footprints:R_0402_1005Metric" (layer "F.Cu")
    (tedit 5FD9C158)
    (at 114.3 96.75 -90)
    (descr "Resistor SMD 0402")
    (tags "resistor SMD 0402")
    (property "Author" "Antmicro")
    (property "License" "Apache-2.0")
    (property "MPN" "CR0402-FX-2001GLF")
    (property "Manufacturer" "Bourns")
    (property "Sheetfile" "camera-interface.kicad_sch")
    (property "Sheetname" "Camera Interface")
    (property "Tolerance" "1%")
    (property "Val" "2k")
    (attr smd)
    (fp_text reference "R82" (at 3.05 -0.35 -90) (layer "F.SilkS")
      (effects (font (size 0.7 0.7) (thickness 0.15)) (justify left bottom))
    )
    (fp_text value "R_2k_0402" (at 0 1.4 -90) (layer "F.Fab")
      (effects (font (size 0.7 0.7) (thickness 0.15)) (justify left bottom))
    )
    (fp_text user "Author: Antmicro" (at -0.95 4.169 -90) (layer "F.Fab") hide
      (effects (font (size 0.7 0.7) (thickness 0.15)) (justify left bottom))
    )
    (fp_text user "${REFERENCE}" (at -0.95 3.168 -90) (layer "F.Fab") hide
      (effects (font (size 0.7 0.7) (thickness 0.15)) (justify left bottom))
    )
    (fp_text user "License: Apache-2.0" (at -0.95 5.169 -90) (layer "F.Fab") hide
      (effects (font (size 0.7 0.7) (thickness 0.15)) (justify left bottom))
    )
    (fp_rect (start -0.93 -0.47) (end 0.93 0.47) (layer "F.CrtYd") (width 0.05) (fill none))
    (fp_rect (start -0.5 -0.25) (end 0.5 0.25) (layer "F.Fab") (width 0.15) (fill none))
    (pad "1" smd roundrect (at -0.485 0 270) (size 0.59 0.64) (layers "F.Cu" "F.Paste" "F.Mask") (roundrect_rratio 0.25)
      (net 44 "CCI1_I2C_SCL") (pintype "passive"))
    (pad "2" smd roundrect (at 0.485 0 270) (size 0.59 0.64) (layers "F.Cu" "F.Paste" "F.Mask") (roundrect_rratio 0.25)
      (net 139 "LVS1A_1V8") (pintype "passive"))
  )

  (footprint "sa800u-baseboard-hw-footprints:R_0402_1005Metric" (layer "F.Cu")
    (tedit 5FD9C158)
    (at 110.8 96.75 -90)
    (descr "Resistor SMD 0402")
    (tags "resistor SMD 0402")
    (property "Author" "Antmicro")
    (property "License" "Apache-2.0")
    (property "MPN" "CR0402-FX-2001GLF")
    (property "Manufacturer" "Bourns")
    (property "Sheetfile" "camera-interface.kicad_sch")
    (property "Sheetname" "Camera Interface")
    (property "Tolerance" "1%")
    (property "Val" "2k")
    (attr smd)
    (fp_text reference "R83" (at 3.05 -0.36 -90) (layer "F.SilkS")
      (effects (font (size 0.7 0.7) (thickness 0.15)) (justify left bottom))
    )
    (fp_text value "R_2k_0402" (at 0 1.4 -90) (layer "F.Fab")
      (effects (font (size 0.7 0.7) (thickness 0.15)) (justify left bottom))
    )
    (fp_text user "${REFERENCE}" (at -0.95 3.168 -90) (layer "F.Fab") hide
      (effects (font (size 0.7 0.7) (thickness 0.15)) (justify left bottom))
    )
    (fp_text user "Author: Antmicro" (at -0.95 4.169 -90) (layer "F.Fab") hide
      (effects (font (size 0.7 0.7) (thickness 0.15)) (justify left bottom))
    )
    (fp_text user "License: Apache-2.0" (at -0.95 5.169 -90) (layer "F.Fab") hide
      (effects (font (size 0.7 0.7) (thickness 0.15)) (justify left bottom))
    )
    (fp_rect (start -0.93 -0.47) (end 0.93 0.47) (layer "F.CrtYd") (width 0.05) (fill none))
    (fp_rect (start -0.5 -0.25) (end 0.5 0.25) (layer "F.Fab") (width 0.15) (fill none))
    (pad "1" smd roundrect (at -0.485 0 270) (size 0.59 0.64) (layers "F.Cu" "F.Paste" "F.Mask") (roundrect_rratio 0.25)
      (net 42 "CCI0_I2C_SCL") (pintype "passive"))
    (pad "2" smd roundrect (at 0.485 0 270) (size 0.59 0.64) (layers "F.Cu" "F.Paste" "F.Mask") (roundrect_rratio 0.25)
      (net 139 "LVS1A_1V8") (pintype "passive"))
  )

  (footprint "sa800u-baseboard-hw-footprints:XSON-8_1x1.95mm_P0.5mm" (layer "F.Cu")
    (tedit 5DCD5522)
    (at 120.895 108.6)
    (property "Author" "Antmicro")
    (property "License" "Apache-2.0")
    (property "MPN" "NTS0102GT")
    (property "Manufacturer" "NXP")
    (property "Sheetfile" "lcm.kicad_sch")
    (property "Sheetname" "LCM")
    (attr smd)
    (fp_text reference "U10" (at -1.125 -1.29) (layer "F.SilkS")
      (effects (font (size 0.7 0.7) (thickness 0.15)) (justify left bottom))
    )
    (fp_text value "NTS0102_XSON" (at 0 2.2) (layer "F.Fab")
      (effects (font (size 0.7 0.7) (thickness 0.15)) (justify left bottom))
    )
    (fp_text user "License: Apache-2.0" (at -0.527 8.306) (layer "F.Fab") hide
      (effects (font (size 0.7 0.7) (thickness 0.15)) (justify left bottom))
    )
    (fp_text user "${REFERENCE}" (at -0.527 5.905) (layer "F.Fab") hide
      (effects (font (size 0.7 0.7) (thickness 0.15)) (justify left bottom))
    )
    (fp_text user "Author: Antmicro" (at -0.527 7.105) (layer "F.Fab") hide
      (effects (font (size 0.7 0.7) (thickness 0.15)) (justify left bottom))
    )
    (fp_line (start 0.5 1.1) (end -0.5 1.1) (layer "F.SilkS") (width 0.15))
    (fp_line (start -0.5 -1.1) (end 0.5 -1.1) (layer "F.SilkS") (width 0.15))
    (fp_circle (center -0.7 -0.95) (end -0.651 -0.95) (layer "F.SilkS") (width 0.15) (fill none))
    (fp_rect (start -0.8 -1.2) (end 0.8 1.2) (layer "F.CrtYd") (width 0.05) (fill none))
    (fp_line (start -0.5305 1) (end -0.5305 -1.001) (layer "F.Fab") (width 0.15))
    (fp_line (start -0.5305 -1.001) (end 0.5305 -1.001) (layer "F.Fab") (width 0.15))
    (fp_line (start 0.5305 -1.001) (end 0.5305 1) (layer "F.Fab") (width 0.15))
    (fp_line (start 0.5305 1) (end -0.5305 1) (layer "F.Fab") (width 0.15))
    (pad "1" smd rect (at -0.33 -0.75) (size 0.5 0.31) (layers "F.Cu" "F.Paste" "F.Mask")
      (net 149 "/LCM/TP_I2C_SDA_3V3") (pinfunction "B_{2}") (pintype "bidirectional"))
    (pad "2" smd rect (at -0.33 -0.25) (size 0.5 0.31) (layers "F.Cu" "F.Paste" "F.Mask")
      (net 1 "GND") (pinfunction "GND") (pintype "power_in"))
    (pad "3" smd rect (at -0.33 0.25) (size 0.5 0.31) (layers "F.Cu" "F.Paste" "F.Mask")
      (net 139 "LVS1A_1V8") (pinfunction "VCC_{A}") (pintype "power_in"))
    (pad "4" smd rect (at -0.33 0.75) (size 0.5 0.31) (layers "F.Cu" "F.Paste" "F.Mask")
      (net 82 "TP_I2C_SDA") (pinfunction "A_{2}") (pintype "bidirectional"))
    (pad "5" smd rect (at 0.33 0.75 180) (size 0.5 0.31) (layers "F.Cu" "F.Paste" "F.Mask")
      (net 81 "TP_I2C_SCL") (pinfunction "A_{1}") (pintype "bidirectional"))
    (pad "6" smd rect (at 0.33 0.25 180) (size 0.5 0.31) (layers "F.Cu" "F.Paste" "F.Mask")
      (net 139 "LVS1A_1V8") (pinfunction "OE") (pintype "input"))
    (pad "7" smd rect (at 0.33 -0.25 180) (size 0.5 0.31) (layers "F.Cu" "F.Paste" "F.Mask")
      (net 131 "3V3_SYS") (pinfunction "VCC_{B}") (pintype "power_in"))
    (pad "8" smd rect (at 0.33 -0.75 180) (size 0.5 0.31) (layers "F.Cu" "F.Paste" "F.Mask")
      (net 148 "/LCM/TP_I2C_SCL_3V3") (pinfunction "B_{1}") (pintype "bidirectional"))
  )

  (footprint "sa800u-baseboard-hw-footprints:R_0402_1005Metric" (layer "F.Cu")
    (tedit 5FD9C158)
    (at 115 120.3)
    (descr "Resistor SMD 0402")
    (tags "resistor SMD 0402")
    (property "Author" "Antmicro")
    (property "License" "Apache-2.0")
    (property "MPN" "CR0402-FX-4701GLF")
    (property "Manufacturer" "Bourns")
    (property "Sheetfile" "som.kicad_sch")
    (property "Sheetname" "SoM")
    (property "Tolerance" "1%")
    (property "Val" "4k7")
    (attr smd)
    (fp_text reference "R72" (at 0.94 0.34) (layer "F.SilkS")
      (effects (font (size 0.7 0.7) (thickness 0.15)) (justify left bottom))
    )
    (fp_text value "R_4k7_0402" (at 0 1.4) (layer "F.Fab")
      (effects (font (size 0.7 0.7) (thickness 0.15)) (justify left bottom))
    )
    (fp_text user "${REFERENCE}" (at -0.95 3.168) (layer "F.Fab") hide
      (effects (font (size 0.7 0.7) (thickness 0.15)) (justify left bottom))
    )
    (fp_text user "License: Apache-2.0" (at -0.95 5.169) (layer "F.Fab") hide
      (effects (font (size 0.7 0.7) (thickness 0.15)) (justify left bottom))
    )
    (fp_text user "Author: Antmicro" (at -0.95 4.169) (layer "F.Fab") hide
      (effects (font (size 0.7 0.7) (thickness 0.15)) (justify left bottom))
    )
    (fp_rect (start -0.93 -0.47) (end 0.93 0.47) (layer "F.CrtYd") (width 0.05) (fill none))
    (fp_rect (start -0.5 -0.25) (end 0.5 0.25) (layer "F.Fab") (width 0.15) (fill none))
    (pad "1" smd roundrect (at -0.485 0) (size 0.59 0.64) (layers "F.Cu" "F.Paste" "F.Mask") (roundrect_rratio 0.25)
      (net 150 "I2C10_SCL") (pintype "passive"))
    (pad "2" smd roundrect (at 0.485 0) (size 0.59 0.64) (layers "F.Cu" "F.Paste" "F.Mask") (roundrect_rratio 0.25)
      (net 132 "VREG_S4A_1V8") (pintype "passive"))
  )

  (footprint "sa800u-baseboard-hw-footprints:R_0402_1005Metric" (layer "F.Cu")
    (tedit 5FD9C158)
    (at 115 121.3)
    (descr "Resistor SMD 0402")
    (tags "resistor SMD 0402")
    (property "Author" "Antmicro")
    (property "License" "Apache-2.0")
    (property "MPN" "CR0402-FX-4701GLF")
    (property "Manufacturer" "Bourns")
    (property "Sheetfile" "som.kicad_sch")
    (property "Sheetname" "SoM")
    (property "Tolerance" "1%")
    (property "Val" "4k7")
    (attr smd)
    (fp_text reference "R71" (at 0.94 0.34) (layer "F.SilkS")
      (effects (font (size 0.7 0.7) (thickness 0.15)) (justify left bottom))
    )
    (fp_text value "R_4k7_0402" (at 0 1.4) (layer "F.Fab")
      (effects (font (size 0.7 0.7) (thickness 0.15)) (justify left bottom))
    )
    (fp_text user "${REFERENCE}" (at -0.95 3.168) (layer "F.Fab") hide
      (effects (font (size 0.7 0.7) (thickness 0.15)) (justify left bottom))
    )
    (fp_text user "License: Apache-2.0" (at -0.95 5.169) (layer "F.Fab") hide
      (effects (font (size 0.7 0.7) (thickness 0.15)) (justify left bottom))
    )
    (fp_text user "Author: Antmicro" (at -0.95 4.169) (layer "F.Fab") hide
      (effects (font (size 0.7 0.7) (thickness 0.15)) (justify left bottom))
    )
    (fp_rect (start -0.93 -0.47) (end 0.93 0.47) (layer "F.CrtYd") (width 0.05) (fill none))
    (fp_rect (start -0.5 -0.25) (end 0.5 0.25) (layer "F.Fab") (width 0.15) (fill none))
    (pad "1" smd roundrect (at -0.485 0) (size 0.59 0.64) (layers "F.Cu" "F.Paste" "F.Mask") (roundrect_rratio 0.25)
      (net 151 "I2C10_SDA") (pintype "passive"))
    (pad "2" smd roundrect (at 0.485 0) (size 0.59 0.64) (layers "F.Cu" "F.Paste" "F.Mask") (roundrect_rratio 0.25)
      (net 132 "VREG_S4A_1V8") (pintype "passive"))
  )

  (footprint "sa800u-baseboard-hw-footprints:R_0402_1005Metric" (layer "F.Cu")
    (tedit 5FD9C158)
    (at 78.45 124.4 90)
    (descr "Resistor SMD 0402")
    (tags "resistor SMD 0402")
    (property "Author" "Antmicro")
    (property "License" "Apache-2.0")
    (property "MPN" "CR0402-FX-3902GLF")
    (property "Manufacturer" "Bourns")
    (property "Sheetfile" "psu.kicad_sch")
    (property "Sheetname" "PSU")
    (property "Tolerance" "1%")
    (property "Val" "39k")
    (attr smd)
    (fp_text reference "R109" (at -8.35 0.17 90) (layer "F.SilkS")
      (effects (font (size 0.7 0.7) (thickness 0.15)) (justify left bottom))
    )
    (fp_text value "R_39k_0402" (at 0 1.4 90) (layer "F.Fab")
      (effects (font (size 0.7 0.7) (thickness 0.15)) (justify left bottom))
    )
    (fp_text user "${REFERENCE}" (at -0.95 3.168 90) (layer "F.Fab") hide
      (effects (font (size 0.7 0.7) (thickness 0.15)) (justify left bottom))
    )
    (fp_text user "Author: Antmicro" (at -0.95 4.169 90) (layer "F.Fab") hide
      (effects (font (size 0.7 0.7) (thickness 0.15)) (justify left bottom))
    )
    (fp_text user "License: Apache-2.0" (at -0.95 5.169 90) (layer "F.Fab") hide
      (effects (font (size 0.7 0.7) (thickness 0.15)) (justify left bottom))
    )
    (fp_rect (start -0.93 -0.47) (end 0.93 0.47) (layer "F.CrtYd") (width 0.05) (fill none))
    (fp_rect (start -0.5 -0.25) (end 0.5 0.25) (layer "F.Fab") (width 0.15) (fill none))
    (pad "1" smd roundrect (at -0.485 0 90) (size 0.59 0.64) (layers "F.Cu" "F.Paste" "F.Mask") (roundrect_rratio 0.25)
      (net 401 "Net-(R108-Pad2)") (pintype "passive"))
    (pad "2" smd roundrect (at 0.485 0 90) (size 0.59 0.64) (layers "F.Cu" "F.Paste" "F.Mask") (roundrect_rratio 0.25)
      (net 128 "Net-(R109-Pad2)") (pintype "passive"))
  )

  (footprint "sa800u-baseboard-hw-footprints:R_0402_1005Metric" (layer "F.Cu")
    (tedit 5FD9C158)
    (at 79.9 124.9 180)
    (descr "Resistor SMD 0402")
    (tags "resistor SMD 0402")
    (property "Author" "Antmicro")
    (property "License" "Apache-2.0")
    (property "MPN" "CR0402-FX-2003GLF")
    (property "Manufacturer" "Bourns")
    (property "Sheetfile" "psu.kicad_sch")
    (property "Sheetname" "PSU")
    (property "Tolerance" "1%")
    (property "Val" "200k")
    (attr smd)
    (fp_text reference "R108" (at 1.24 -6.23 180) (layer "F.SilkS")
      (effects (font (size 0.7 0.7) (thickness 0.15)) (justify left bottom))
    )
    (fp_text value "R_200k_0402" (at 0 1.4 180) (layer "F.Fab")
      (effects (font (size 0.7 0.7) (thickness 0.15)) (justify left bottom))
    )
    (fp_text user "Author: Antmicro" (at -0.95 4.169 180) (layer "F.Fab") hide
      (effects (font (size 0.7 0.7) (thickness 0.15)) (justify left bottom))
    )
    (fp_text user "${REFERENCE}" (at -0.95 3.168 180) (layer "F.Fab") hide
      (effects (font (size 0.7 0.7) (thickness 0.15)) (justify left bottom))
    )
    (fp_text user "License: Apache-2.0" (at -0.95 5.169 180) (layer "F.Fab") hide
      (effects (font (size 0.7 0.7) (thickness 0.15)) (justify left bottom))
    )
    (fp_rect (start -0.93 -0.47) (end 0.93 0.47) (layer "F.CrtYd") (width 0.05) (fill none))
    (fp_rect (start -0.5 -0.25) (end 0.5 0.25) (layer "F.Fab") (width 0.15) (fill none))
    (pad "1" smd roundrect (at -0.485 0 180) (size 0.59 0.64) (layers "F.Cu" "F.Paste" "F.Mask") (roundrect_rratio 0.25)
      (net 142 "PD_VDD") (pintype "passive"))
    (pad "2" smd roundrect (at 0.485 0 180) (size 0.59 0.64) (layers "F.Cu" "F.Paste" "F.Mask") (roundrect_rratio 0.25)
      (net 401 "Net-(R108-Pad2)") (pintype "passive"))
  )

  (footprint "sa800u-baseboard-hw-footprints:R_0402_1005Metric" (layer "F.Cu")
    (tedit 5FD9C158)
    (at 78.45 126.4 90)
    (descr "Resistor SMD 0402")
    (tags "resistor SMD 0402")
    (property "Author" "Antmicro")
    (property "License" "Apache-2.0")
    (property "MPN" "CR0402-FX-3902GLF")
    (property "Manufacturer" "Bourns")
    (property "Sheetfile" "psu.kicad_sch")
    (property "Sheetname" "PSU")
    (property "Tolerance" "1%")
    (property "Val" "39k")
    (attr smd)
    (fp_text reference "R113" (at -9.02 0.19 90) (layer "F.SilkS")
      (effects (font (size 0.7 0.7) (thickness 0.15)) (justify left bottom))
    )
    (fp_text value "R_39k_0402" (at 0 1.4 90) (layer "F.Fab")
      (effects (font (size 0.7 0.7) (thickness 0.15)) (justify left bottom))
    )
    (fp_text user "${REFERENCE}" (at -0.95 3.168 90) (layer "F.Fab") hide
      (effects (font (size 0.7 0.7) (thickness 0.15)) (justify left bottom))
    )
    (fp_text user "Author: Antmicro" (at -0.95 4.169 90) (layer "F.Fab") hide
      (effects (font (size 0.7 0.7) (thickness 0.15)) (justify left bottom))
    )
    (fp_text user "License: Apache-2.0" (at -0.95 5.169 90) (layer "F.Fab") hide
      (effects (font (size 0.7 0.7) (thickness 0.15)) (justify left bottom))
    )
    (fp_rect (start -0.93 -0.47) (end 0.93 0.47) (layer "F.CrtYd") (width 0.05) (fill none))
    (fp_rect (start -0.5 -0.25) (end 0.5 0.25) (layer "F.Fab") (width 0.15) (fill none))
    (pad "1" smd roundrect (at -0.485 0 90) (size 0.59 0.64) (layers "F.Cu" "F.Paste" "F.Mask") (roundrect_rratio 0.25)
      (net 402 "Net-(R112-Pad2)") (pintype "passive"))
    (pad "2" smd roundrect (at 0.485 0 90) (size 0.59 0.64) (layers "F.Cu" "F.Paste" "F.Mask") (roundrect_rratio 0.25)
      (net 403 "Net-(R113-Pad2)") (pintype "passive"))
  )

  (footprint "sa800u-baseboard-hw-footprints:R_0402_1005Metric" (layer "F.Cu")
    (tedit 5FD9C158)
    (at 79.9 122.9 180)
    (descr "Resistor SMD 0402")
    (tags "resistor SMD 0402")
    (property "Author" "Antmicro")
    (property "License" "Apache-2.0")
    (property "MPN" "CR0402-FX-2003GLF")
    (property "Manufacturer" "Bourns")
    (property "Sheetfile" "psu.kicad_sch")
    (property "Sheetname" "PSU")
    (property "Tolerance" "1%")
    (property "Val" "200k")
    (attr smd)
    (fp_text reference "R105" (at 1.21 -6.31 180) (layer "F.SilkS")
      (effects (font (size 0.7 0.7) (thickness 0.15)) (justify left bottom))
    )
    (fp_text value "R_200k_0402" (at 0 1.4 180) (layer "F.Fab")
      (effects (font (size 0.7 0.7) (thickness 0.15)) (justify left bottom))
    )
    (fp_text user "${REFERENCE}" (at -0.95 3.168 180) (layer "F.Fab") hide
      (effects (font (size 0.7 0.7) (thickness 0.15)) (justify left bottom))
    )
    (fp_text user "Author: Antmicro" (at -0.95 4.169 180) (layer "F.Fab") hide
      (effects (font (size 0.7 0.7) (thickness 0.15)) (justify left bottom))
    )
    (fp_text user "License: Apache-2.0" (at -0.95 5.169 180) (layer "F.Fab") hide
      (effects (font (size 0.7 0.7) (thickness 0.15)) (justify left bottom))
    )
    (fp_rect (start -0.93 -0.47) (end 0.93 0.47) (layer "F.CrtYd") (width 0.05) (fill none))
    (fp_rect (start -0.5 -0.25) (end 0.5 0.25) (layer "F.Fab") (width 0.15) (fill none))
    (pad "1" smd roundrect (at -0.485 0 180) (size 0.59 0.64) (layers "F.Cu" "F.Paste" "F.Mask") (roundrect_rratio 0.25)
      (net 136 "5V_POE") (pintype "passive"))
    (pad "2" smd roundrect (at 0.485 0 180) (size 0.59 0.64) (layers "F.Cu" "F.Paste" "F.Mask") (roundrect_rratio 0.25)
      (net 399 "Net-(R105-Pad2)") (pintype "passive"))
  )

  (footprint "sa800u-baseboard-hw-footprints:R_0402_1005Metric" (layer "F.Cu")
    (tedit 5FD9C158)
    (at 79.9 126.9 180)
    (descr "Resistor SMD 0402")
    (tags "resistor SMD 0402")
    (property "Author" "Antmicro")
    (property "License" "Apache-2.0")
    (property "MPN" "CR0402-FX-2003GLF")
    (property "Manufacturer" "Bourns")
    (property "Sheetfile" "psu.kicad_sch")
    (property "Sheetname" "PSU")
    (property "Tolerance" "1%")
    (property "Val" "200k")
    (attr smd)
    (fp_text reference "R112" (at 1.25 -6.22 180) (layer "F.SilkS")
      (effects (font (size 0.7 0.7) (thickness 0.15)) (justify left bottom))
    )
    (fp_text value "R_200k_0402" (at 0 1.4 180) (layer "F.Fab")
      (effects (font (size 0.7 0.7) (thickness 0.15)) (justify left bottom))
    )
    (fp_text user "${REFERENCE}" (at -0.95 3.168 180) (layer "F.Fab") hide
      (effects (font (size 0.7 0.7) (thickness 0.15)) (justify left bottom))
    )
    (fp_text user "License: Apache-2.0" (at -0.95 5.169 180) (layer "F.Fab") hide
      (effects (font (size 0.7 0.7) (thickness 0.15)) (justify left bottom))
    )
    (fp_text user "Author: Antmicro" (at -0.95 4.169 180) (layer "F.Fab") hide
      (effects (font (size 0.7 0.7) (thickness 0.15)) (justify left bottom))
    )
    (fp_rect (start -0.93 -0.47) (end 0.93 0.47) (layer "F.CrtYd") (width 0.05) (fill none))
    (fp_rect (start -0.5 -0.25) (end 0.5 0.25) (layer "F.Fab") (width 0.15) (fill none))
    (pad "1" smd roundrect (at -0.485 0 180) (size 0.59 0.64) (layers "F.Cu" "F.Paste" "F.Mask") (roundrect_rratio 0.25)
      (net 152 "/PSU/AUX_VDD") (pintype "passive"))
    (pad "2" smd roundrect (at 0.485 0 180) (size 0.59 0.64) (layers "F.Cu" "F.Paste" "F.Mask") (roundrect_rratio 0.25)
      (net 402 "Net-(R112-Pad2)") (pintype "passive"))
  )

  (footprint "sa800u-baseboard-hw-footprints:R_0402_1005Metric" (layer "F.Cu")
    (tedit 5FD9C158)
    (at 78.45 122.4 90)
    (descr "Resistor SMD 0402")
    (tags "resistor SMD 0402")
    (property "Author" "Antmicro")
    (property "License" "Apache-2.0")
    (property "MPN" "CR0402-FX-3902GLF")
    (property "Manufacturer" "Bourns")
    (property "Sheetfile" "psu.kicad_sch")
    (property "Sheetname" "PSU")
    (property "Tolerance" "1%")
    (property "Val" "39k")
    (attr smd)
    (fp_text reference "R106" (at -7.66 0.21 90) (layer "F.SilkS")
      (effects (font (size 0.7 0.7) (thickness 0.15)) (justify left bottom))
    )
    (fp_text value "R_39k_0402" (at 0 1.4 90) (layer "F.Fab")
      (effects (font (size 0.7 0.7) (thickness 0.15)) (justify left bottom))
    )
    (fp_text user "${REFERENCE}" (at -0.95 3.168 90) (layer "F.Fab") hide
      (effects (font (size 0.7 0.7) (thickness 0.15)) (justify left bottom))
    )
    (fp_text user "License: Apache-2.0" (at -0.95 5.169 90) (layer "F.Fab") hide
      (effects (font (size 0.7 0.7) (thickness 0.15)) (justify left bottom))
    )
    (fp_text user "Author: Antmicro" (at -0.95 4.169 90) (layer "F.Fab") hide
      (effects (font (size 0.7 0.7) (thickness 0.15)) (justify left bottom))
    )
    (fp_rect (start -0.93 -0.47) (end 0.93 0.47) (layer "F.CrtYd") (width 0.05) (fill none))
    (fp_rect (start -0.5 -0.25) (end 0.5 0.25) (layer "F.Fab") (width 0.15) (fill none))
    (pad "1" smd roundrect (at -0.485 0 90) (size 0.59 0.64) (layers "F.Cu" "F.Paste" "F.Mask") (roundrect_rratio 0.25)
      (net 399 "Net-(R105-Pad2)") (pintype "passive"))
    (pad "2" smd roundrect (at 0.485 0 90) (size 0.59 0.64) (layers "F.Cu" "F.Paste" "F.Mask") (roundrect_rratio 0.25)
      (net 400 "Net-(R106-Pad2)") (pintype "passive"))
  )

  (footprint "sa800u-baseboard-hw-footprints:R_0402_1005Metric" (layer "F.Cu")
    (tedit 5FD9C158)
    (at 76.95 127.55)
    (descr "Resistor SMD 0402")
    (tags "resistor SMD 0402")
    (property "Author" "Antmicro")
    (property "License" "Apache-2.0")
    (property "MPN" "CR0402-FX-2553GLF")
    (property "Manufacturer" "Bourns")
    (property "Sheetfile" "psu.kicad_sch")
    (property "Sheetname" "PSU")
    (property "Tolerance" "1%")
    (property "Val" "255k")
    (attr smd)
    (fp_text reference "R117" (at -3.68 0.38) (layer "F.SilkS")
      (effects (font (size 0.7 0.7) (thickness 0.15)) (justify left bottom))
    )
    (fp_text value "R_255k_0402" (at 0 1.4) (layer "F.Fab")
      (effects (font (size 0.7 0.7) (thickness 0.15)) (justify left bottom))
    )
    (fp_text user "Author: Antmicro" (at -0.95 4.169) (layer "F.Fab") hide
      (effects (font (size 0.7 0.7) (thickness 0.15)) (justify left bottom))
    )
    (fp_text user "${REFERENCE}" (at -0.95 3.168) (layer "F.Fab") hide
      (effects (font (size 0.7 0.7) (thickness 0.15)) (justify left bottom))
    )
    (fp_text user "License: Apache-2.0" (at -0.95 5.169) (layer "F.Fab") hide
      (effects (font (size 0.7 0.7) (thickness 0.15)) (justify left bottom))
    )
    (fp_rect (start -0.93 -0.47) (end 0.93 0.47) (layer "F.CrtYd") (width 0.05) (fill none))
    (fp_rect (start -0.5 -0.25) (end 0.5 0.25) (layer "F.Fab") (width 0.15) (fill none))
    (pad "1" smd roundrect (at -0.485 0) (size 0.59 0.64) (layers "F.Cu" "F.Paste" "F.Mask") (roundrect_rratio 0.25)
      (net 404 "Net-(R117-Pad1)") (pintype "passive"))
    (pad "2" smd roundrect (at 0.485 0) (size 0.59 0.64) (layers "F.Cu" "F.Paste" "F.Mask") (roundrect_rratio 0.25)
      (net 1 "GND") (pintype "passive"))
  )

  (footprint "sa800u-baseboard-hw-footprints:QFN-24-1EP_4x4mm_EP2.1x2.1mm" (layer "F.Cu")
    (tedit 5DC5F6A3)
    (at 75.25 124.4 180)
    (descr "QFN, 24 Pin")
    (tags "QFN NoLead")
    (property "Author" "Antmicro")
    (property "License" "Apache-2.0")
    (property "MPN" "LTC4417IUF#TRPBF")
    (property "Manufacturer" "Analog Devices")
    (property "Sheetfile" "psu.kicad_sch")
    (property "Sheetname" "PSU")
    (attr smd)
    (fp_text reference "U17" (at 4.34 -2.47 180) (layer "F.SilkS")
      (effects (font (size 0.7 0.7) (thickness 0.15)) (justify left bottom))
    )
    (fp_text value "LTC4417_QFN" (at 0 3.4 180) (layer "F.Fab")
      (effects (font (size 0.7 0.7) (thickness 0.15)) (justify left bottom))
    )
    (fp_text user "Author: Antmicro" (at -2.503 7.8 180) (layer "F.Fab") hide
      (effects (font (size 0.7 0.7) (thickness 0.15)) (justify left bottom))
    )
    (fp_text user "${REFERENCE}" (at -2.503 5.4 180) (layer "F.Fab") hide
      (effects (font (size 0.7 0.7) (thickness 0.15)) (justify left bottom))
    )
    (fp_text user "License: Apache-2.0" (at -2.503 6.6 180) (layer "F.Fab") hide
      (effects (font (size 0.7 0.7) (thickness 0.15)) (justify left bottom))
    )
    (fp_line (start -1.635 2.108) (end -2.11 2.108) (layer "F.SilkS") (width 0.15))
    (fp_line (start 2.108 2.108) (end 2.108 1.634) (layer "F.SilkS") (width 0.15))
    (fp_line (start 1.634 -2.11) (end 2.108 -2.11) (layer "F.SilkS") (width 0.15))
    (fp_line (start -2.11 -1.636) (end -2.11 -2.11) (layer "F.SilkS") (width 0.15))
    (fp_line (start 2.108 -2.11) (end 2.108 -1.635) (layer "F.SilkS") (width 0.15))
    (fp_line (start -2.11 2.108) (end -2.11 1.634) (layer "F.SilkS") (width 0.15))
    (fp_line (start -1.635 -2.11) (end -2.11 -2.11) (layer "F.SilkS") (width 0.15))
    (fp_line (start 1.634 2.108) (end 2.108 2.108) (layer "F.SilkS") (width 0.15))
    (fp_circle (center -2.3 -2.3) (end -2.25 -2.3) (layer "F.SilkS") (width 0.15) (fill solid))
    (fp_rect (start -2.503 -2.503) (end 2.5 2.5) (layer "F.CrtYd") (width 0.05) (fill none))
    (fp_line (start 1.999 1.999) (end -2 1.999) (layer "F.Fab") (width 0.15))
    (fp_line (start 1.999 -2) (end 1.999 1.999) (layer "F.Fab") (width 0.15))
    (fp_line (start -2 1.999) (end -2 -1) (layer "F.Fab") (width 0.15))
    (fp_line (start -1 -2) (end 1.999 -2) (layer "F.Fab") (width 0.15))
    (fp_line (start -2 -1) (end -1 -2) (layer "F.Fab") (width 0.15))
    (pad "" smd roundrect (at -0.5 -0.5 180) (size 0.8 0.8) (layers "F.Paste") (roundrect_rratio 0.238095))
    (pad "" smd roundrect (at 0.5 -0.5 180) (size 0.8 0.8) (layers "F.Paste") (roundrect_rratio 0.238095))
    (pad "" smd roundrect (at -0.5 0.5 180) (size 0.8 0.8) (layers "F.Paste") (roundrect_rratio 0.238095))
    (pad "" smd roundrect (at 0.5 0.5 180) (size 0.8 0.8) (layers "F.Paste") (roundrect_rratio 0.238095))
    (pad "1" smd roundrect (at -1.938 -1.25 180) (size 0.825 0.25) (layers "F.Cu" "F.Paste" "F.Mask") (roundrect_rratio 0.25)
      (net 402 "Net-(R112-Pad2)") (pinfunction "UV1") (pintype "input"))
    (pad "2" smd roundrect (at -1.938 -0.75 180) (size 0.825 0.25) (layers "F.Cu" "F.Paste" "F.Mask") (roundrect_rratio 0.25)
      (net 403 "Net-(R113-Pad2)") (pinfunction "OV1") (pintype "input"))
    (pad "3" smd roundrect (at -1.938 -0.25 180) (size 0.825 0.25) (layers "F.Cu" "F.Paste" "F.Mask") (roundrect_rratio 0.25)
      (net 401 "Net-(R108-Pad2)") (pinfunction "UV2") (pintype "input"))
    (pad "4" smd roundrect (at -1.938 0.248 180) (size 0.825 0.25) (layers "F.Cu" "F.Paste" "F.Mask") (roundrect_rratio 0.25)
      (net 128 "Net-(R109-Pad2)") (pinfunction "OV2") (pintype "input"))
    (pad "5" smd roundrect (at -1.938 0.748 180) (size 0.825 0.25) (layers "F.Cu" "F.Paste" "F.Mask") (roundrect_rratio 0.25)
      (net 399 "Net-(R105-Pad2)") (pinfunction "UV3") (pintype "input"))
    (pad "6" smd roundrect (at -1.938 1.249 180) (size 0.825 0.25) (layers "F.Cu" "F.Paste" "F.Mask") (roundrect_rratio 0.25)
      (net 400 "Net-(R106-Pad2)") (pinfunction "OV3") (pintype "input"))
    (pad "7" smd roundrect (at -1.25 1.937 180) (size 0.25 0.825) (layers "F.Cu" "F.Paste" "F.Mask") (roundrect_rratio 0.25)
      (net 339 "/PSU/AUX_VALID") (pinfunction "~{VALID1}") (pintype "output"))
    (pad "8" smd roundrect (at -0.75 1.937 180) (size 0.25 0.825) (layers "F.Cu" "F.Paste" "F.Mask") (roundrect_rratio 0.25)
      (net 341 "/PSU/USB_PD_VALID") (pinfunction "~{VALID2}") (pintype "output"))
    (pad "9" smd roundrect (at -0.25 1.937 180) (size 0.25 0.825) (layers "F.Cu" "F.Paste" "F.Mask") (roundrect_rratio 0.25)
      (net 340 "/PSU/POE_VALID") (pinfunction "~{VALID3}") (pintype "output"))
    (pad "10" smd roundrect (at 0.248 1.937 180) (size 0.25 0.825) (layers "F.Cu" "F.Paste" "F.Mask") (roundrect_rratio 0.25)
      (net 1 "GND") (pinfunction "GND") (pintype "power_in"))
    (pad "11" smd roundrect (at 0.748 1.937 180) (size 0.25 0.825) (layers "F.Cu" "F.Paste" "F.Mask") (roundrect_rratio 0.25)
      (net 659 "unconnected-(U17-Pad11)") (pinfunction "CAS") (pintype "output+no_connect"))
    (pad "12" smd roundrect (at 1.249 1.937 180) (size 0.25 0.825) (layers "F.Cu" "F.Paste" "F.Mask") (roundrect_rratio 0.25)
      (net 74 "VDD") (pinfunction "VOUT") (pintype "output"))
    (pad "13" smd roundrect (at 1.937 1.249 180) (size 0.825 0.25) (layers "F.Cu" "F.Paste" "F.Mask") (roundrect_rratio 0.25)
      (net 367 "/PSU/G3") (pinfunction "G3") (pintype "output"))
    (pad "14" smd roundrect (at 1.937 0.748 180) (size 0.825 0.25) (layers "F.Cu" "F.Paste" "F.Mask") (roundrect_rratio 0.25)
      (net 159 "/PSU/VS3") (pinfunction "VS3") (pintype "unspecified"))
    (pad "15" smd roundrect (at 1.937 0.248 180) (size 0.825 0.25) (layers "F.Cu" "F.Paste" "F.Mask") (roundrect_rratio 0.25)
      (net 355 "/PSU/G2") (pinfunction "G2") (pintype "output"))
    (pad "16" smd roundrect (at 1.937 -0.25 180) (size 0.825 0.25) (layers "F.Cu" "F.Paste" "F.Mask") (roundrect_rratio 0.25)
      (net 158 "/PSU/VS2") (pinfunction "VS2") (pintype "unspecified"))
    (pad "17" smd roundrect (at 1.937 -0.75 180) (size 0.825 0.25) (layers "F.Cu" "F.Paste" "F.Mask") (roundrect_rratio 0.25)
      (net 354 "/PSU/G1") (pinfunction "G1") (pintype "output"))
    (pad "18" smd roundrect (at 1.937 -1.25 180) (size 0.825 0.25) (layers "F.Cu" "F.Paste" "F.Mask") (roundrect_rratio 0.25)
      (net 157 "/PSU/VS1") (pinfunction "VS1") (pintype "unspecified"))
    (pad "19" smd roundrect (at 1.249 -1.938 180) (size 0.25 0.825) (layers "F.Cu" "F.Paste" "F.Mask") (roundrect_rratio 0.25)
      (net 136 "5V_POE") (pinfunction "V3") (pintype "input"))
    (pad "20" smd roundrect (at 0.748 -1.938 180) (size 0.25 0.825) (layers "F.Cu" "F.Paste" "F.Mask") (roundrect_rratio 0.25)
      (net 142 "PD_VDD") (pinfunction "V2") (pintype "input"))
    (pad "21" smd roundrect (at 0.248 -1.938 180) (size 0.25 0.825) (layers "F.Cu" "F.Paste" "F.Mask") (roundrect_rratio 0.25)
      (net 152 "/PSU/AUX_VDD") (pinfunction "V1") (pintype "input"))
    (pad "22" smd roundrect (at -0.25 -1.938 180) (size 0.25 0.825) (layers "F.Cu" "F.Paste" "F.Mask") (roundrect_rratio 0.25)
      (net 658 "unconnected-(U17-Pad22)") (pinfunction "EN") (pintype "input+no_connect"))
    (pad "23" smd roundrect (at -0.75 -1.938 180) (size 0.25 0.825) (layers "F.Cu" "F.Paste" "F.Mask") (roundrect_rratio 0.25)
      (net 657 "unconnected-(U17-Pad23)") (pinfunction "~{SHDN}") (pintype "input+no_connect"))
    (pad "24" smd roundrect (at -1.25 -1.938 180) (size 0.25 0.825) (layers "F.Cu" "F.Paste" "F.Mask") (roundrect_rratio 0.25)
      (net 404 "Net-(R117-Pad1)") (pinfunction "HYS") (pintype "input"))
    (pad "25" smd rect (at 0 0 180) (size 2.1 2.1) (layers "F.Cu" "F.Mask")
      (net 1 "GND") (pinfunction "EPAD") (pintype "unspecified"))
  )

  (footprint "sa800u-baseboard-hw-footprints:R_0402_1005Metric" (layer "F.Cu")
    (tedit 5FD9C158)
    (at 90.75 130.5)
    (descr "Resistor SMD 0402")
    (tags "resistor SMD 0402")
    (property "Author" "Antmicro")
    (property "License" "Apache-2.0")
    (property "MPN" "CR0402-FX-2701GLF")
    (property "Manufacturer" "Bourns")
    (property "Sheetfile" "usb-pd.kicad_sch")
    (property "Sheetname" "USB-PD")
    (property "Tolerance" "1%")
    (property "Val" "2k7")
    (attr smd)
    (fp_text reference "R174" (at -3.56 0.31) (layer "F.SilkS")
      (effects (font (size 0.7 0.7) (thickness 0.15)) (justify left bottom))
    )
    (fp_text value "R_2k7_0402" (at 0 1.4) (layer "F.Fab")
      (effects (font (size 0.7 0.7) (thickness 0.15)) (justify left bottom))
    )
    (fp_text user "${REFERENCE}" (at -0.95 3.168) (layer "F.Fab") hide
      (effects (font (size 0.7 0.7) (thickness 0.15)) (justify left bottom))
    )
    (fp_text user "License: Apache-2.0" (at -0.95 5.169) (layer "F.Fab") hide
      (effects (font (size 0.7 0.7) (thickness 0.15)) (justify left bottom))
    )
    (fp_text user "Author: Antmicro" (at -0.95 4.169) (layer "F.Fab") hide
      (effects (font (size 0.7 0.7) (thickness 0.15)) (justify left bottom))
    )
    (fp_rect (start -0.93 -0.47) (end 0.93 0.47) (layer "F.CrtYd") (width 0.05) (fill none))
    (fp_rect (start -0.5 -0.25) (end 0.5 0.25) (layer "F.Fab") (width 0.15) (fill none))
    (pad "1" smd roundrect (at -0.485 0) (size 0.59 0.64) (layers "F.Cu" "F.Paste" "F.Mask") (roundrect_rratio 0.25)
      (net 142 "PD_VDD") (pintype "passive"))
    (pad "2" smd roundrect (at 0.485 0) (size 0.59 0.64) (layers "F.Cu" "F.Paste" "F.Mask") (roundrect_rratio 0.25)
      (net 383 "Net-(D36-Pad4)") (pintype "passive"))
  )

  (footprint "sa800u-baseboard-hw-footprints:R_0402_1005Metric" (layer "F.Cu")
    (tedit 5FD9C158)
    (at 90.75 131.55)
    (descr "Resistor SMD 0402")
    (tags "resistor SMD 0402")
    (property "Author" "Antmicro")
    (property "License" "Apache-2.0")
    (property "MPN" "CR0402-FX-7500GLF")
    (property "Manufacturer" "Bourns")
    (property "Sheetfile" "usb-pd.kicad_sch")
    (property "Sheetname" "USB-PD")
    (property "Tolerance" "1%")
    (property "Val" "750R")
    (attr smd)
    (fp_text reference "R173" (at -3.56 0.31) (layer "F.SilkS")
      (effects (font (size 0.7 0.7) (thickness 0.15)) (justify left bottom))
    )
    (fp_text value "R_750R_0402" (at 0 1.4) (layer "F.Fab")
      (effects (font (size 0.7 0.7) (thickness 0.15)) (justify left bottom))
    )
    (fp_text user "${REFERENCE}" (at -0.95 3.168) (layer "F.Fab") hide
      (effects (font (size 0.7 0.7) (thickness 0.15)) (justify left bottom))
    )
    (fp_text user "Author: Antmicro" (at -0.95 4.169) (layer "F.Fab") hide
      (effects (font (size 0.7 0.7) (thickness 0.15)) (justify left bottom))
    )
    (fp_text user "License: Apache-2.0" (at -0.95 5.169) (layer "F.Fab") hide
      (effects (font (size 0.7 0.7) (thickness 0.15)) (justify left bottom))
    )
    (fp_rect (start -0.93 -0.47) (end 0.93 0.47) (layer "F.CrtYd") (width 0.05) (fill none))
    (fp_rect (start -0.5 -0.25) (end 0.5 0.25) (layer "F.Fab") (width 0.15) (fill none))
    (pad "1" smd roundrect (at -0.485 0) (size 0.59 0.64) (layers "F.Cu" "F.Paste" "F.Mask") (roundrect_rratio 0.25)
      (net 133 "5V_SYS") (pintype "passive"))
    (pad "2" smd roundrect (at 0.485 0) (size 0.59 0.64) (layers "F.Cu" "F.Paste" "F.Mask") (roundrect_rratio 0.25)
      (net 382 "Net-(D36-Pad5)") (pintype "passive"))
  )

  (footprint "sa800u-baseboard-hw-footprints:PLCC6_3.5x3.7mm" (layer "F.Cu")
    (tedit 6215DBD2)
    (at 94.3 131.6 180)
    (property "Author" "Antmicro")
    (property "License" "Apache-2.0")
    (property "MPN" "ASMB-TTF0-0A20B")
    (property "Manufacturer" "Broadcom")
    (property "Sheetfile" "usb-pd.kicad_sch")
    (property "Sheetname" "USB-PD")
    (attr smd)
    (fp_text reference "D36" (at 0.22 -2.74 180) (layer "F.SilkS")
      (effects (font (size 0.7 0.7) (thickness 0.15)) (justify left bottom))
    )
    (fp_text value "ASMB-TTF0-0A20B" (at 0 -2.5 180) (layer "F.Fab")
      (effects (font (size 0.7 0.7) (thickness 0.15)) (justify left bottom))
    )
    (fp_text user "License: Apache-2.0" (at -2.5 8.573 180) (layer "F.Fab") hide
      (effects (font (size 0.7 0.7) (thickness 0.15)) (justify left bottom))
    )
    (fp_text user "${REFERENCE}" (at -2.5 4.974 180) (layer "F.Fab") hide
      (effects (font (size 0.7 0.7) (thickness 0.15)) (justify left bottom))
    )
    (fp_text user "Author: Antmicro" (at -2.5 6.174 180) (layer "F.Fab") hide
      (effects (font (size 0.7 0.7) (thickness 0.15)) (justify left bottom))
    )
    (fp_line (start -1.851 -1.696) (end 1.85 -1.696) (layer "F.SilkS") (width 0.15))
    (fp_line (start 1.85 1.804) (end -1.851 1.804) (layer "F.SilkS") (width 0.15))
    (fp_line (start -0.5 0.053) (end 0.348 -0.446) (layer "F.SilkS") (width 0.15))
    (fp_line (start 1.85 -1.696) (end 1.85 -1.496) (layer "F.SilkS") (width 0.15))
    (fp_line (start 1.85 1.804) (end 1.85 1.604) (layer "F.SilkS") (width 0.15))
    (fp_line (start -1.851 -1.696) (end -1.851 -1.496) (layer "F.SilkS") (width 0.15))
    (fp_line (start -0.5 -0.446) (end -0.5 0.552) (layer "F.SilkS") (width 0.15))
    (fp_line (start -1.805 -1.647) (end -1.754 -1.647) (layer "F.SilkS") (width 0.15))
    (fp_line (start -1.851 1.804) (end -1.851 1.604) (layer "F.SilkS") (width 0.15))
    (fp_line (start 0.348 0.552) (end -0.5 0.002) (layer "F.SilkS") (width 0.15))
    (fp_line (start 0.348 -0.446) (end 0.348 0.552) (layer "F.SilkS") (width 0.15))
    (fp_line (start -1.851 -1.496) (end -1.651 -1.7) (layer "F.SilkS") (width 0.15))
    (fp_line (start -2.4 -1.696) (end -2.4 1.804) (layer "F.SilkS") (width 0.15))
    (fp_circle (center -2.15 -1.65) (end -2.1 -1.65) (layer "F.SilkS") (width 0.15) (fill solid))
    (fp_rect (start -2.4 -2) (end 2.4 2.05) (layer "F.CrtYd") (width 0.05) (fill none))
    (fp_line (start -1.601 -1.7) (end -1.855 -1.47) (layer "F.Fab") (width 0.15))
    (fp_line (start -1.855 -1.47) (end -1.855 1.804) (layer "F.Fab") (width 0.15))
    (fp_line (start 1.854 1.804) (end -1.855 1.804) (layer "F.Fab") (width 0.15))
    (fp_line (start 1.854 -1.7) (end -1.601 -1.7) (layer "F.Fab") (width 0.15))
    (fp_line (start 1.854 -1.7) (end 1.854 1.804) (layer "F.Fab") (width 0.15))
    (pad "1" smd rect (at -1.5 -0.996 180) (size 1.6 0.7) (layers "F.Cu" "F.Paste" "F.Mask")
      (net 169 "/USB-PD/STUSB4500_PWR_OK2") (pinfunction "1") (pintype "passive"))
    (pad "2" smd rect (at -1.5 0.053 180) (size 1.6 0.7) (layers "F.Cu" "F.Paste" "F.Mask")
      (net 170 "/USB-PD/STUSB4500_PWR_OK3") (pinfunction "2") (pintype "passive"))
    (pad "3" smd rect (at -1.5 1.104 180) (size 1.6 0.7) (layers "F.Cu" "F.Paste" "F.Mask")
      (net 1 "GND") (pinfunction "3") (pintype "passive"))
    (pad "4" smd rect (at 1.499 1.104 180) (size 1.6 0.7) (layers "F.Cu" "F.Paste" "F.Mask")
      (net 383 "Net-(D36-Pad4)") (pinfunction "4") (pintype "passive"))
    (pad "5" smd rect (at 1.499 0.053 180) (size 1.6 0.7) (layers "F.Cu" "F.Paste" "F.Mask")
      (net 382 "Net-(D36-Pad5)") (pinfunction "5") (pintype "passive"))
    (pad "6" smd rect (at 1.499 -0.996 180) (size 1.6 0.7) (layers "F.Cu" "F.Paste" "F.Mask")
      (net 381 "Net-(D36-Pad6)") (pinfunction "6") (pintype "passive"))
  )

  (footprint "sa800u-baseboard-hw-footprints:R_0402_1005Metric" (layer "F.Cu")
    (tedit 5FD9C158)
    (at 79.9 121.9)
    (descr "Resistor SMD 0402")
    (tags "resistor SMD 0402")
    (property "Author" "Antmicro")
    (property "License" "Apache-2.0")
    (property "MPN" "CR0402-FX-1372GLF")
    (property "Manufacturer" "Bourns")
    (property "Sheetfile" "psu.kicad_sch")
    (property "Sheetname" "PSU")
    (property "Tolerance" "1%")
    (property "Val" "13k7")
    (attr smd)
    (fp_text reference "R107" (at -1.22 6.34) (layer "F.SilkS")
      (effects (font (size 0.7 0.7) (thickness 0.15)) (justify left bottom))
    )
    (fp_text value "R_13k7_0402" (at 0 1.4) (layer "F.Fab")
      (effects (font (size 0.7 0.7) (thickness 0.15)) (justify left bottom))
    )
    (fp_text user "${REFERENCE}" (at -0.95 3.168) (layer "F.Fab") hide
      (effects (font (size 0.7 0.7) (thickness 0.15)) (justify left bottom))
    )
    (fp_text user "License: Apache-2.0" (at -0.95 5.169) (layer "F.Fab") hide
      (effects (font (size 0.7 0.7) (thickness 0.15)) (justify left bottom))
    )
    (fp_text user "Author: Antmicro" (at -0.95 4.169) (layer "F.Fab") hide
      (effects (font (size 0.7 0.7) (thickness 0.15)) (justify left bottom))
    )
    (fp_rect (start -0.93 -0.47) (end 0.93 0.47) (layer "F.CrtYd") (width 0.05) (fill none))
    (fp_rect (start -0.5 -0.25) (end 0.5 0.25) (layer "F.Fab") (width 0.15) (fill none))
    (pad "1" smd roundrect (at -0.485 0) (size 0.59 0.64) (layers "F.Cu" "F.Paste" "F.Mask") (roundrect_rratio 0.25)
      (net 400 "Net-(R106-Pad2)") (pintype "passive"))
    (pad "2" smd roundrect (at 0.485 0) (size 0.59 0.64) (layers "F.Cu" "F.Paste" "F.Mask") (roundrect_rratio 0.25)
      (net 1 "GND") (pintype "passive"))
  )

  (footprint "sa800u-baseboard-hw-footprints:R_0402_1005Metric" (layer "F.Cu")
    (tedit 5FD9C158)
    (at 79.9 123.9)
    (descr "Resistor SMD 0402")
    (tags "resistor SMD 0402")
    (property "Author" "Antmicro")
    (property "License" "Apache-2.0")
    (property "MPN" "CR0402-FX-1372GLF")
    (property "Manufacturer" "Bourns")
    (property "Sheetfile" "psu.kicad_sch")
    (property "Sheetname" "PSU")
    (property "Tolerance" "1%")
    (property "Val" "13k7")
    (attr smd)
    (fp_text reference "R110" (at -1.22 6.27) (layer "F.SilkS")
      (effects (font (size 0.7 0.7) (thickness 0.15)) (justify left bottom))
    )
    (fp_text value "R_13k7_0402" (at 0 1.4) (layer "F.Fab")
      (effects (font (size 0.7 0.7) (thickness 0.15)) (justify left bottom))
    )
    (fp_text user "Author: Antmicro" (at -0.95 4.169) (layer "F.Fab") hide
      (effects (font (size 0.7 0.7) (thickness 0.15)) (justify left bottom))
    )
    (fp_text user "${REFERENCE}" (at -0.95 3.168) (layer "F.Fab") hide
      (effects (font (size 0.7 0.7) (thickness 0.15)) (justify left bottom))
    )
    (fp_text user "License: Apache-2.0" (at -0.95 5.169) (layer "F.Fab") hide
      (effects (font (size 0.7 0.7) (thickness 0.15)) (justify left bottom))
    )
    (fp_rect (start -0.93 -0.47) (end 0.93 0.47) (layer "F.CrtYd") (width 0.05) (fill none))
    (fp_rect (start -0.5 -0.25) (end 0.5 0.25) (layer "F.Fab") (width 0.15) (fill none))
    (pad "1" smd roundrect (at -0.485 0) (size 0.59 0.64) (layers "F.Cu" "F.Paste" "F.Mask") (roundrect_rratio 0.25)
      (net 128 "Net-(R109-Pad2)") (pintype "passive"))
    (pad "2" smd roundrect (at 0.485 0) (size 0.59 0.64) (layers "F.Cu" "F.Paste" "F.Mask") (roundrect_rratio 0.25)
      (net 1 "GND") (pintype "passive"))
  )

  (footprint "sa800u-baseboard-hw-footprints:R_0402_1005Metric" (layer "F.Cu")
    (tedit 5FD9C158)
    (at 79.9 125.9)
    (descr "Resistor SMD 0402")
    (tags "resistor SMD 0402")
    (property "Author" "Antmicro")
    (property "License" "Apache-2.0")
    (property "MPN" "CR0402-FX-1372GLF")
    (property "Manufacturer" "Bourns")
    (property "Sheetfile" "psu.kicad_sch")
    (property "Sheetname" "PSU")
    (property "Tolerance" "1%")
    (property "Val" "13k7")
    (attr smd)
    (fp_text reference "R114" (at -1.22 6.2) (layer "F.SilkS")
      (effects (font (size 0.7 0.7) (thickness 0.15)) (justify left bottom))
    )
    (fp_text value "R_13k7_0402" (at 0 1.4) (layer "F.Fab")
      (effects (font (size 0.7 0.7) (thickness 0.15)) (justify left bottom))
    )
    (fp_text user "${REFERENCE}" (at -0.95 3.168) (layer "F.Fab") hide
      (effects (font (size 0.7 0.7) (thickness 0.15)) (justify left bottom))
    )
    (fp_text user "Author: Antmicro" (at -0.95 4.169) (layer "F.Fab") hide
      (effects (font (size 0.7 0.7) (thickness 0.15)) (justify left bottom))
    )
    (fp_text user "License: Apache-2.0" (at -0.95 5.169) (layer "F.Fab") hide
      (effects (font (size 0.7 0.7) (thickness 0.15)) (justify left bottom))
    )
    (fp_rect (start -0.93 -0.47) (end 0.93 0.47) (layer "F.CrtYd") (width 0.05) (fill none))
    (fp_rect (start -0.5 -0.25) (end 0.5 0.25) (layer "F.Fab") (width 0.15) (fill none))
    (pad "1" smd roundrect (at -0.485 0) (size 0.59 0.64) (layers "F.Cu" "F.Paste" "F.Mask") (roundrect_rratio 0.25)
      (net 403 "Net-(R113-Pad2)") (pintype "passive"))
    (pad "2" smd roundrect (at 0.485 0) (size 0.59 0.64) (layers "F.Cu" "F.Paste" "F.Mask") (roundrect_rratio 0.25)
      (net 1 "GND") (pintype "passive"))
  )

  (footprint "sa800u-baseboard-hw-footprints:CONV_PDQE30-Q48-S5-D" locked (layer "F.Cu")
    (tedit 608ACD31)
    (at 57.842 84.841)
    (property "Author" "Antmicro")
    (property "License" "Apache-2.0")
    (property "MPN" "PDQE30-Q48-S5-D")
    (property "Manufacturer" "CUI Inc")
    (property "STANDARD" "Manufacturer Recommendations")
    (property "Sheetfile" "poe.kicad_sch")
    (property "Sheetname" "PoE")
    (attr through_hole)
    (fp_text reference "PS1" (at 23.558 -1.391 270) (layer "F.SilkS")
      (effects (font (size 0.65 0.65) (thickness 0.15)))
    )
    (fp_text value "PDQE30-Q48-S5-D" (at 0.16 14.155) (layer "F.Fab") hide
      (effects (font (size 1 1) (thickness 0.15)))
    )
    (fp_text user "${REFERENCE}" (at -3.912 28.711) (layer "F.Fab") hide
      (effects (font (size 0.7 0.7) (thickness 0.15)) (justify left bottom))
    )
    (fp_text user "Author: Antmicro" (at -3.912 26.312) (layer "F.Fab") hide
      (effects (font (size 0.7 0.7) (thickness 0.15)) (justify left bottom))
    )
    (fp_text user "License: Apache-2.0" (at -3.912 27.51) (layer "F.Fab") hide
      (effects (font (size 0.7 0.7) (thickness 0.15)) (justify left bottom))
    )
    (fp_line (start 22.859 22.859) (end -2.54 22.859) (layer "F.SilkS") (width 0.15))
    (fp_line (start 22.859 -2.54) (end 22.859 22.859) (layer "F.SilkS") (width 0.15))
    (fp_line (start -2.54 22.859) (end -2.54 -2.54) (layer "F.SilkS") (width 0.15))
    (fp_line (start -2.54 -2.54) (end 22.859 -2.54) (layer "F.SilkS") (width 0.15))
    (fp_circle (center -2.4 -2.9) (end -2.35 -2.9) (layer "F.SilkS") (width 0.15) (fill solid))
    (fp_rect (start -2.667 -2.667) (end 22.987 22.987) (layer "F.CrtYd") (width 0.05) (fill none))
    (fp_line (start 22.859 22.859) (end -2.54 22.859) (layer "F.Fab") (width 0.15))
    (fp_line (start 22.859 -2.54) (end 22.859 22.859) (layer "F.Fab") (width 0.15))
    (fp_line (start -2.54 -2.54) (end 22.859 -2.54) (layer "F.Fab") (width 0.15))
    (fp_line (start -2.54 22.859) (end -2.54 -2.54) (layer "F.Fab") (width 0.15))
    (pad "1" thru_hole rect locked (at 0 0) (size 2.25 2.25) (drill 1.5) (layers *.Cu *.Mask)
      (net 76 "/PoE/SMPS_CTRL") (pinfunction "CTRL") (pintype "input"))
    (pad "2" thru_hole circle locked (at 0 7.618) (size 2.25 2.25) (drill 1.5) (layers *.Cu *.Mask)
      (net 7 "GNDD") (pinfunction "GND") (pintype "power_in"))
    (pad "3" thru_hole circle locked (at 0 12.698) (size 2.25 2.25) (drill 1.5) (layers *.Cu *.Mask)
      (net 73 "/PoE/VDD_POE") (pinfunction "V_{IN}") (pintype "power_in"))
    (pad "4" thru_hole circle locked (at 20.318 20.318) (size 2.25 2.25) (drill 1.5) (layers *.Cu *.Mask)
      (net 136 "5V_POE") (pinfunction "V_{O}") (pintype "power_out"))
    (pad "5" thru_hole circle locked (at 20.318 10.159) (size 2.25 2.25) (drill 1.5) (layers *.Cu *.Mask)
      (net 153 "/PoE/TRIM") (pinfunction "TRIM") (pintype "passive"))
    (pad "6" thru_hole circle locked (at 20.318 0) (size 2.25 2.25) (drill 1.5) (layers *.Cu *.Mask)
      (net 1 "GND") (pinfunction "0V") (pintype "power_out"))
  )

  (footprint "sa800u-baseboard-hw-footprints:LED_0603_1608Metric_G" (layer "F.Cu")
    (tedit 60C2DD7B)
    (at 82.6 107.3)
    (descr "LED SMD 0603 Green")
    (tags "LED SMD 0603 Green")
    (property "Author" "Antmicro")
    (property "License" "Apache-2.0")
    (property "MPN" "KP-1608ZGC")
    (property "Manufacturer" "Kingbright")
    (property "Sheetfile" "psu.kicad_sch")
    (property "Sheetname" "PSU")
    (attr smd)
    (fp_text reference "D26" (at -1.04 -0.74) (layer "F.SilkS")
      (effects (font (size 0.7 0.7) (thickness 0.15)) (justify left bottom))
    )
    (fp_text value "KP-1608EC" (at 0 1.6) (layer "F.Fab")
      (effects (font (size 0.7 0.7) (thickness 0.15)) (justify left bottom))
    )
    (fp_text user "License: Apache-2.0" (at -1.31 5.769) (layer "F.Fab") hide
      (effects (font (size 0.7 0.7) (thickness 0.15)) (justify left bottom))
    )
    (fp_text user "${REFERENCE}" (at -1.31 3.769) (layer "F.Fab") hide
      (effects (font (size 0.7 0.7) (thickness 0.15)) (justify left bottom))
    )
    (fp_text user "Author: Antmicro" (at -1.31 4.769) (layer "F.Fab") hide
      (effects (font (size 0.7 0.7) (thickness 0.15)) (justify left bottom))
    )
    (fp_line (start -0.27 0.351) (end 0.27 0.351) (layer "F.SilkS") (width 0.15))
    (fp_line (start -0.27 -0.35) (end 0.27 -0.35) (layer "F.SilkS") (width 0.15))
    (fp_line (start 0.093672 -0.000008) (end 0.293672 -0.000008) (layer "F.SilkS") (width 0.1))
    (fp_line (start -0.106328 -0.200008) (end -0.106328 0.199992) (layer "F.SilkS") (width 0.1))
    (fp_line (start -0.106328 -0.200008) (end 0.093672 -0.000008) (layer "F.SilkS") (width 0.1))
    (fp_line (start -0.106328 -0.000008) (end -0.29 0) (layer "F.SilkS") (width 0.1))
    (fp_line (start 1.25 0.32) (end 1.25 -0.32) (layer "F.SilkS") (width 0.15))
    (fp_line (start 0.093672 -0.200008) (end 0.093672 0.199992) (layer "F.SilkS") (width 0.1))
    (fp_line (start 0.093672 -0.000008) (end -0.106328 0.199992) (layer "F.SilkS") (width 0.1))
    (fp_rect (start 1.26 0.65) (end -1.26 -0.65) (layer "F.CrtYd") (width 0.05) (fill none))
    (fp_line (start 0.199 0) (end 0.597 0) (layer "F.Fab") (width 0.15))
    (fp_line (start -0.599 0) (end -0.201 0) (layer "F.Fab") (width 0.15))
    (fp_line (start 0.101 0) (end -0.201 -0.2) (layer "F.Fab") (width 0.15))
    (fp_line (start 0.199 0.202) (end 0.199 -0.1) (layer "F.Fab") (width 0.15))
    (fp_line (start 0.199 -0.2) (end 0.199 -0.1) (layer "F.Fab") (width 0.15))
    (fp_line (start -0.201 0) (end -0.201 0.202) (layer "F.Fab") (width 0.15))
    (fp_line (start -0.201 -0.2) (end -0.201 0) (layer "F.Fab") (width 0.15))
    (fp_line (start -0.201 0.202) (end 0.101 0) (layer "F.Fab") (width 0.15))
    (fp_rect (start -0.848 -0.4) (end 0.85 0.402) (layer "F.Fab") (width 0.15) (fill none))
    (pad "1" smd rect (at -0.75 0 180) (size 0.8 0.8) (layers "F.Cu" "F.Paste" "F.Mask")
      (net 136 "5V_POE") (pinfunction "1") (pintype "passive"))
    (pad "2" smd rect (at 0.75 0 180) (size 0.8 0.8) (layers "F.Cu" "F.Paste" "F.Mask")
      (net 377 "Net-(D26-Pad2)") (pinfunction "2") (pintype "passive"))
  )

  (footprint "sa800u-baseboard-hw-footprints:Nexperia_DFN-10_2.5x1mm_P0.5mm" (layer "F.Cu")
    (tedit 6215DC23)
    (at 145.25 139.55 180)
    (property "Author" "Antmicro")
    (property "License" "Apache-2.0")
    (property "MPN" "PUSB3F96X")
    (property "Manufacturer" "Nexperia")
    (property "Sheetfile" "hdmi-converter.kicad_sch")
    (property "Sheetname" "HDMI converter")
    (attr smd)
    (fp_text reference "D5" (at 1.52 0.8 180) (layer "F.SilkS")
      (effects (font (size 0.7 0.7) (thickness 0.15)) (justify left bottom))
    )
    (fp_text value "PUSB3F96X_PASS" (at -0.016 1.705 180) (layer "F.Fab")
      (effects (font (size 0.7 0.7) (thickness 0.15)) (justify left bottom))
    )
    (fp_text user "Author: Antmicro" (at -1.367 4.905 180) (layer "F.Fab") hide
      (effects (font (size 0.7 0.7) (thickness 0.15)) (justify left bottom))
    )
    (fp_text user "${REFERENCE}" (at -1.367 3.704 180) (layer "F.Fab") hide
      (effects (font (size 0.7 0.7) (thickness 0.15)) (justify left bottom))
    )
    (fp_text user "License: Apache-2.0" (at -1.367 6.105 180) (layer "F.Fab") hide
      (effects (font (size 0.7 0.7) (thickness 0.15)) (justify left bottom))
    )
    (fp_line (start -1.266 -0.396) (end -1.266 0.405) (layer "F.SilkS") (width 0.15))
    (fp_line (start 1.233 0.405) (end 1.233 -0.396) (layer "F.SilkS") (width 0.15))
    (fp_circle (center -1.317 0.704) (end -1.266 0.704) (layer "F.SilkS") (width 0.15) (fill solid))
    (fp_rect (start -1.4 -0.7) (end 1.4 0.7) (layer "F.CrtYd") (width 0.05) (fill none))
    (pad "1" smd rect (at -1.016 0.392 180) (size 0.2 0.475) (layers "F.Cu" "F.Paste" "F.Mask")
      (net 243 "/HDMI converter/HDMI_TX2_CONN_P") (pinfunction "CH1") (pintype "passive"))
    (pad "2" smd rect (at -0.517 0.392 180) (size 0.2 0.475) (layers "F.Cu" "F.Paste" "F.Mask")
      (net 240 "/HDMI converter/HDMI_TX2_CONN_N") (pinfunction "CH2") (pintype "passive"))
    (pad "3" smd rect (at -0.016 0.392 180) (size 0.2 0.475) (layers "F.Cu" "F.Paste" "F.Mask")
      (net 1 "GND") (pinfunction "GND") (pintype "passive"))
    (pad "4" smd rect (at 0.482 0.392 180) (size 0.2 0.475) (layers "F.Cu" "F.Paste" "F.Mask")
      (net 241 "/HDMI converter/HDMI_TX1_CONN_P") (pinfunction "CH3") (pintype "passive"))
    (pad "5" smd rect (at 0.982 0.392 180) (size 0.2 0.475) (layers "F.Cu" "F.Paste" "F.Mask")
      (net 242 "/HDMI converter/HDMI_TX1_CONN_N") (pinfunction "CH4") (pintype "passive"))
    (pad "6" smd rect (at 0.982 -0.383) (size 0.2 0.475) (layers "F.Cu" "F.Paste" "F.Mask")
      (net 242 "/HDMI converter/HDMI_TX1_CONN_N") (pinfunction "CH4") (pintype "passive"))
    (pad "7" smd rect (at 0.482 -0.383) (size 0.2 0.475) (layers "F.Cu" "F.Paste" "F.Mask")
      (net 241 "/HDMI converter/HDMI_TX1_CONN_P") (pinfunction "CH3") (pintype "passive"))
    (pad "8" smd rect (at -0.016 -0.383) (size 0.2 0.475) (layers "F.Cu" "F.Paste" "F.Mask")
      (net 1 "GND") (pinfunction "GND") (pintype "passive"))
    (pad "9" smd rect (at -0.517 -0.383) (size 0.2 0.475) (layers "F.Cu" "F.Paste" "F.Mask")
      (net 240 "/HDMI converter/HDMI_TX2_CONN_N") (pinfunction "CH2") (pintype "passive"))
    (pad "10" smd rect (at -1.016 -0.383) (size 0.2 0.475) (layers "F.Cu" "F.Paste" "F.Mask")
      (net 243 "/HDMI converter/HDMI_TX2_CONN_P") (pinfunction "CH1") (pintype "passive"))
  )

  (footprint "sa800u-baseboard-hw-footprints:R_0402_1005Metric" (layer "F.Cu")
    (tedit 5FD9C158)
    (at 81.5 104.15 -90)
    (descr "Resistor SMD 0402")
    (tags "resistor SMD 0402")
    (property "Author" "Antmicro")
    (property "License" "Apache-2.0")
    (property "MPN" "CR0402-FX-1002GLF")
    (property "Manufacturer" "Bourns")
    (property "Sheetfile" "psu.kicad_sch")
    (property "Sheetname" "PSU")
    (property "Tolerance" "1%")
    (property "Val" "10k")
    (attr smd)
    (fp_text reference "R116" (at 1.47 -1.22 -90) (layer "F.SilkS")
      (effects (font (size 0.7 0.7) (thickness 0.15)) (justify left bottom))
    )
    (fp_text value "R_10k_0402" (at 0 1.4 -90) (layer "F.Fab")
      (effects (font (size 0.7 0.7) (thickness 0.15)) (justify left bottom))
    )
    (fp_text user "Author: Antmicro" (at -0.95 4.169 -90) (layer "F.Fab") hide
      (effects (font (size 0.7 0.7) (thickness 0.15)) (justify left bottom))
    )
    (fp_text user "License: Apache-2.0" (at -0.95 5.169 -90) (layer "F.Fab") hide
      (effects (font (size 0.7 0.7) (thickness 0.15)) (justify left bottom))
    )
    (fp_text user "${REFERENCE}" (at -0.95 3.168 -90) (layer "F.Fab") hide
      (effects (font (size 0.7 0.7) (thickness 0.15)) (justify left bottom))
    )
    (fp_rect (start -0.93 -0.47) (end 0.93 0.47) (layer "F.CrtYd") (width 0.05) (fill none))
    (fp_rect (start -0.5 -0.25) (end 0.5 0.25) (layer "F.Fab") (width 0.15) (fill none))
    (pad "1" smd roundrect (at -0.485 0 270) (size 0.59 0.64) (layers "F.Cu" "F.Paste" "F.Mask") (roundrect_rratio 0.25)
      (net 347 "Net-(Q13-Pad3)") (pintype "passive"))
    (pad "2" smd roundrect (at 0.485 0 270) (size 0.59 0.64) (layers "F.Cu" "F.Paste" "F.Mask") (roundrect_rratio 0.25)
      (net 377 "Net-(D26-Pad2)") (pintype "passive"))
  )

  (footprint "sa800u-baseboard-hw-footprints:R_0402_1005Metric" (layer "F.Cu")
    (tedit 5FD9C158)
    (at 90.75 132.65 180)
    (descr "Resistor SMD 0402")
    (tags "resistor SMD 0402")
    (property "Author" "Antmicro")
    (property "License" "Apache-2.0")
    (property "MPN" "CR0402-FX-5100GLF")
    (property "Manufacturer" "Bourns")
    (property "Sheetfile" "usb-pd.kicad_sch")
    (property "Sheetname" "USB-PD")
    (property "Tolerance" "1%")
    (property "Val" "510R")
    (attr smd)
    (fp_text reference "R171" (at 3.52 -0.33 180) (layer "F.SilkS")
      (effects (font (size 0.7 0.7) (thickness 0.15)) (justify left bottom))
    )
    (fp_text value "R_510R_0402" (at 0 1.4 180) (layer "F.Fab")
      (effects (font (size 0.7 0.7) (thickness 0.15)) (justify left bottom))
    )
    (fp_text user "License: Apache-2.0" (at -0.95 5.169 180) (layer "F.Fab") hide
      (effects (font (size 0.7 0.7) (thickness 0.15)) (justify left bottom))
    )
    (fp_text user "${REFERENCE}" (at -0.95 3.168 180) (layer "F.Fab") hide
      (effects (font (size 0.7 0.7) (thickness 0.15)) (justify left bottom))
    )
    (fp_text user "Author: Antmicro" (at -0.95 4.169 180) (layer "F.Fab") hide
      (effects (font (size 0.7 0.7) (thickness 0.15)) (justify left bottom))
    )
    (fp_rect (start -0.93 -0.47) (end 0.93 0.47) (layer "F.CrtYd") (width 0.05) (fill none))
    (fp_rect (start -0.5 -0.25) (end 0.5 0.25) (layer "F.Fab") (width 0.15) (fill none))
    (pad "1" smd roundrect (at -0.485 0 180) (size 0.59 0.64) (layers "F.Cu" "F.Paste" "F.Mask") (roundrect_rratio 0.25)
      (net 381 "Net-(D36-Pad6)") (pintype "passive"))
    (pad "2" smd roundrect (at 0.485 0 180) (size 0.59 0.64) (layers "F.Cu" "F.Paste" "F.Mask") (roundrect_rratio 0.25)
      (net 133 "5V_SYS") (pintype "passive"))
  )

  (footprint "sa800u-baseboard-hw-footprints:C_Elec_10x10.5mm" (layer "F.Cu")
    (tedit 5ED8C968)
    (at 62 113.6 180)
    (descr "SMD capacitor, aluminum electrolytic, 10x10.5mm")
    (tags "capacitor electrolytic")
    (property "Author" "Antmicro")
    (property "Dielectric" "")
    (property "License" "Apache-2.0")
    (property "MPN" "EEEHA2A470UP")
    (property "Manufacturer" "Panasonic")
    (property "Sheetfile" "poe.kicad_sch")
    (property "Sheetname" "PoE")
    (property "Val" "47u/100V")
    (property "Voltage" "")
    (attr smd)
    (fp_text reference "C145" (at 5.71 1.76 270) (layer "F.SilkS")
      (effects (font (size 0.7 0.7) (thickness 0.15)) (justify left bottom))
    )
    (fp_text value "C_47u_ELEC_100V" (at 0 6.299 180) (layer "F.Fab")
      (effects (font (size 0.7 0.7) (thickness 0.15)) (justify left bottom))
    )
    (fp_text user "${REFERENCE}" (at -6.85 8.3 180) (layer "F.Fab") hide
      (effects (font (size 0.7 0.7) (thickness 0.15)) (justify left bottom))
    )
    (fp_text user "Author: Antmicro" (at -6.85 9.499 180) (layer "F.Fab") hide
      (effects (font (size 0.7 0.7) (thickness 0.15)) (justify left bottom))
    )
    (fp_text user "License: Apache-2.0" (at -6.85 10.699 180) (layer "F.Fab") hide
      (effects (font (size 0.7 0.7) (thickness 0.15)) (justify left bottom))
    )
    (fp_line (start 5.36 -5.361) (end 5.36 -1.51) (layer "F.SilkS") (width 0.15))
    (fp_line (start -5.361 4.295) (end -5.361 1.509) (layer "F.SilkS") (width 0.15))
    (fp_line (start -5.361 4.295) (end -4.296 5.36) (layer "F.SilkS") (width 0.15))
    (fp_line (start -4.296 -5.361) (end 5.36 -5.361) (layer "F.SilkS") (width 0.15))
    (fp_line (start -6.85 -2.76) (end -5.6 -2.76) (layer "F.SilkS") (width 0.15))
    (fp_line (start -6.225 -3.385) (end -6.225 -2.135) (layer "F.SilkS") (width 0.15))
    (fp_line (start -4.296 5.36) (end 5.36 5.36) (layer "F.SilkS") (width 0.15))
    (fp_line (start 5.36 5.36) (end 5.36 1.509) (layer "F.SilkS") (width 0.15))
    (fp_line (start -5.361 -4.296) (end -4.296 -5.361) (layer "F.SilkS") (width 0.15))
    (fp_line (start -5.361 -4.296) (end -5.361 -1.51) (layer "F.SilkS") (width 0.15))
    (fp_line (start -5.5 1.49) (end -5.5 4.34) (layer "F.CrtYd") (width 0.05))
    (fp_line (start -6.66 -1.5) (end -6.66 1.49) (layer "F.CrtYd") (width 0.05))
    (fp_line (start -5.5 4.34) (end -4.35 5.49) (layer "F.CrtYd") (width 0.05))
    (fp_line (start -4.35 5.49) (end 5.49 5.49) (layer "F.CrtYd") (width 0.05))
    (fp_line (start 6.65 1.49) (end 5.49 1.49) (layer "F.CrtYd") (width 0.05))
    (fp_line (start -4.35 -5.5) (end 5.49 -5.5) (layer "F.CrtYd") (width 0.05))
    (fp_line (start 6.65 -1.5) (end 6.65 1.49) (layer "F.CrtYd") (width 0.05))
    (fp_line (start -5.5 -4.35) (end -4.35 -5.5) (layer "F.CrtYd") (width 0.05))
    (fp_line (start 5.49 -5.5) (end 5.49 -1.5) (layer "F.CrtYd") (width 0.05))
    (fp_line (start -5.5 -1.5) (end -6.66 -1.5) (layer "F.CrtYd") (width 0.05))
    (fp_line (start -6.66 1.49) (end -5.5 1.49) (layer "F.CrtYd") (width 0.05))
    (fp_line (start -5.5 -4.35) (end -5.5 -1.5) (layer "F.CrtYd") (width 0.05))
    (fp_line (start 5.49 -1.5) (end 6.65 -1.5) (layer "F.CrtYd") (width 0.05))
    (fp_line (start 5.49 1.49) (end 5.49 5.49) (layer "F.CrtYd") (width 0.05))
    (fp_line (start -4.25 -5.25) (end 5.249 -5.25) (layer "F.Fab") (width 0.15))
    (fp_line (start -4.25 5.249) (end 5.249 5.249) (layer "F.Fab") (width 0.15))
    (fp_line (start 5.249 -5.25) (end 5.249 5.249) (layer "F.Fab") (width 0.15))
    (fp_line (start -5.25 -4.25) (end -4.25 -5.25) (layer "F.Fab") (width 0.15))
    (fp_line (start -5.25 4.249) (end -4.25 5.249) (layer "F.Fab") (width 0.15))
    (fp_line (start -4.059 -2.201) (end -4.059 -1.2) (layer "F.Fab") (width 0.15))
    (fp_line (start -4.559 -1.7) (end -3.559 -1.7) (layer "F.Fab") (width 0.15))
    (fp_line (start -5.25 -4.25) (end -5.25 4.249) (layer "F.Fab") (width 0.15))
    (fp_circle (center 0 0) (end 4.999 0) (layer "F.Fab") (width 0.15) (fill none))
    (pad "1" smd roundrect (at -4.201 0 180) (size 4.4 2.5) (layers "F.Cu" "F.Paste" "F.Mask") (roundrect_rratio 0.1)
      (net 73 "/PoE/VDD_POE") (pintype "passive"))
    (pad "2" smd roundrect (at 4.2 0 180) (size 4.4 2.5) (layers "F.Cu" "F.Paste" "F.Mask") (roundrect_rratio 0.1)
      (net 7 "GNDD") (pintype "passive"))
  )

  (footprint "sa800u-baseboard-hw-footprints:LED_0603_1608Metric_G" (layer "F.Cu")
    (tedit 60C2DD7B)
    (at 83.45 124)
    (descr "LED SMD 0603 Green")
    (tags "LED SMD 0603 Green")
    (property "Author" "Antmicro")
    (property "License" "Apache-2.0")
    (property "MPN" "KP-1608ZGC")
    (property "Manufacturer" "Kingbright")
    (property "Sheetfile" "psu.kicad_sch")
    (property "Sheetname" "PSU")
    (attr smd)
    (fp_text reference "D28" (at -0.9 -0.47) (layer "F.SilkS")
      (effects (font (size 0.7 0.7) (thickness 0.15)) (justify left bottom))
    )
    (fp_text value "KP-1608EC" (at 0 1.6) (layer "F.Fab")
      (effects (font (size 0.7 0.7) (thickness 0.15)) (justify left bottom))
    )
    (fp_text user "Author: Antmicro" (at -1.31 4.769) (layer "F.Fab") hide
      (effects (font (size 0.7 0.7) (thickness 0.15)) (justify left bottom))
    )
    (fp_text user "License: Apache-2.0" (at -1.31 5.769) (layer "F.Fab") hide
      (effects (font (size 0.7 0.7) (thickness 0.15)) (justify left bottom))
    )
    (fp_text user "${REFERENCE}" (at -1.31 3.769) (layer "F.Fab") hide
      (effects (font (size 0.7 0.7) (thickness 0.15)) (justify left bottom))
    )
    (fp_line (start 0.093672 -0.000008) (end 0.293672 -0.000008) (layer "F.SilkS") (width 0.1))
    (fp_line (start -0.106328 -0.200008) (end -0.106328 0.199992) (layer "F.SilkS") (width 0.1))
    (fp_line (start 0.093672 -0.000008) (end -0.106328 0.199992) (layer "F.SilkS") (width 0.1))
    (fp_line (start -0.27 -0.35) (end 0.27 -0.35) (layer "F.SilkS") (width 0.15))
    (fp_line (start -0.27 0.351) (end 0.27 0.351) (layer "F.SilkS") (width 0.15))
    (fp_line (start 0.093672 -0.200008) (end 0.093672 0.199992) (layer "F.SilkS") (width 0.1))
    (fp_line (start -0.106328 -0.000008) (end -0.29 0) (layer "F.SilkS") (width 0.1))
    (fp_line (start -0.106328 -0.200008) (end 0.093672 -0.000008) (layer "F.SilkS") (width 0.1))
    (fp_line (start 1.25 0.32) (end 1.25 -0.32) (layer "F.SilkS") (width 0.15))
    (fp_rect (start 1.26 0.65) (end -1.26 -0.65) (layer "F.CrtYd") (width 0.05) (fill none))
    (fp_line (start 0.199 -0.2) (end 0.199 -0.1) (layer "F.Fab") (width 0.15))
    (fp_line (start -0.201 -0.2) (end -0.201 0) (layer "F.Fab") (width 0.15))
    (fp_line (start -0.201 0) (end -0.201 0.202) (layer "F.Fab") (width 0.15))
    (fp_line (start 0.199 0.202) (end 0.199 -0.1) (layer "F.Fab") (width 0.15))
    (fp_line (start -0.599 0) (end -0.201 0) (layer "F.Fab") (width 0.15))
    (fp_line (start -0.201 0.202) (end 0.101 0) (layer "F.Fab") (width 0.15))
    (fp_line (start 0.199 0) (end 0.597 0) (layer "F.Fab") (width 0.15))
    (fp_line (start 0.101 0) (end -0.201 -0.2) (layer "F.Fab") (width 0.15))
    (fp_rect (start -0.848 -0.4) (end 0.85 0.402) (layer "F.Fab") (width 0.15) (fill none))
    (pad "1" smd rect (at -0.75 0 180) (size 0.8 0.8) (layers "F.Cu" "F.Paste" "F.Mask")
      (net 74 "VDD") (pinfunction "1") (pintype "passive"))
    (pad "2" smd rect (at 0.75 0 180) (size 0.8 0.8) (layers "F.Cu" "F.Paste" "F.Mask")
      (net 342 "Net-(D28-Pad2)") (pinfunction "2") (pintype "passive"))
  )

  (footprint "sa800u-baseboard-hw-footprints:R_0402_1005Metric" (layer "F.Cu")
    (tedit 5FD9C158)
    (at 85.45 123.7 -90)
    (descr "Resistor SMD 0402")
    (tags "resistor SMD 0402")
    (property "Author" "Antmicro")
    (property "License" "Apache-2.0")
    (property "MPN" "CR0402-FX-1002GLF")
    (property "Manufacturer" "Bourns")
    (property "Sheetfile" "psu.kicad_sch")
    (property "Sheetname" "PSU")
    (property "Tolerance" "1%")
    (property "Val" "10k")
    (attr smd)
    (fp_text reference "R122" (at 1.11 -1.4 -90) (layer "F.SilkS")
      (effects (font (size 0.7 0.7) (thickness 0.15)) (justify left bottom))
    )
    (fp_text value "R_10k_0402" (at 0 1.4 -90) (layer "F.Fab")
      (effects (font (size 0.7 0.7) (thickness 0.15)) (justify left bottom))
    )
    (fp_text user "Author: Antmicro" (at -0.95 4.169 -90) (layer "F.Fab") hide
      (effects (font (size 0.7 0.7) (thickness 0.15)) (justify left bottom))
    )
    (fp_text user "${REFERENCE}" (at -0.95 3.168 -90) (layer "F.Fab") hide
      (effects (font (size 0.7 0.7) (thickness 0.15)) (justify left bottom))
    )
    (fp_text user "License: Apache-2.0" (at -0.95 5.169 -90) (layer "F.Fab") hide
      (effects (font (size 0.7 0.7) (thickness 0.15)) (justify left bottom))
    )
    (fp_rect (start -0.93 -0.47) (end 0.93 0.47) (layer "F.CrtYd") (width 0.05) (fill none))
    (fp_rect (start -0.5 -0.25) (end 0.5 0.25) (layer "F.Fab") (width 0.15) (fill none))
    (pad "1" smd roundrect (at -0.485 0 270) (size 0.59 0.64) (layers "F.Cu" "F.Paste" "F.Mask") (roundrect_rratio 0.25)
      (net 348 "Net-(Q14-Pad3)") (pintype "passive"))
    (pad "2" smd roundrect (at 0.485 0 270) (size 0.59 0.64) (layers "F.Cu" "F.Paste" "F.Mask") (roundrect_rratio 0.25)
      (net 342 "Net-(D28-Pad2)") (pintype "passive"))
  )

  (footprint "sa800u-baseboard-hw-footprints:R_0402_1005Metric" (layer "F.Cu")
    (tedit 5FD9C158)
    (at 76 137.3 180)
    (descr "Resistor SMD 0402")
    (tags "resistor SMD 0402")
    (property "Author" "Antmicro")
    (property "License" "Apache-2.0")
    (property "MPN" "CR0402-FX-1004GLF")
    (property "Manufacturer" "Bourns")
    (property "Sheetfile" "psu.kicad_sch")
    (property "Sheetname" "PSU")
    (property "Tolerance" "1%")
    (property "Val" "1M")
    (attr smd)
    (fp_text reference "R120" (at 1.46 -2.38 180) (layer "F.SilkS")
      (effects (font (size 0.7 0.7) (thickness 0.15)) (justify left bottom))
    )
    (fp_text value "R_1M_0402" (at 0 1.4 180) (layer "F.Fab")
      (effects (font (size 0.7 0.7) (thickness 0.15)) (justify left bottom))
    )
    (fp_text user "License: Apache-2.0" (at -0.95 5.169 180) (layer "F.Fab") hide
      (effects (font (size 0.7 0.7) (thickness 0.15)) (justify left bottom))
    )
    (fp_text user "Author: Antmicro" (at -0.95 4.169 180) (layer "F.Fab") hide
      (effects (font (size 0.7 0.7) (thickness 0.15)) (justify left bottom))
    )
    (fp_text user "${REFERENCE}" (at -0.95 3.168 180) (layer "F.Fab") hide
      (effects (font (size 0.7 0.7) (thickness 0.15)) (justify left bottom))
    )
    (fp_rect (start -0.93 -0.47) (end 0.93 0.47) (layer "F.CrtYd") (width 0.05) (fill none))
    (fp_rect (start -0.5 -0.25) (end 0.5 0.25) (layer "F.Fab") (width 0.15) (fill none))
    (pad "1" smd roundrect (at -0.485 0 180) (size 0.59 0.64) (layers "F.Cu" "F.Paste" "F.Mask") (roundrect_rratio 0.25)
      (net 74 "VDD") (pintype "passive"))
    (pad "2" smd roundrect (at 0.485 0 180) (size 0.59 0.64) (layers "F.Cu" "F.Paste" "F.Mask") (roundrect_rratio 0.25)
      (net 339 "/PSU/AUX_VALID") (pintype "passive"))
  )

  (footprint "sa800u-baseboard-hw-footprints:R_0402_1005Metric" (layer "F.Cu")
    (tedit 5FD9C158)
    (at 76 136.3 180)
    (descr "Resistor SMD 0402")
    (tags "resistor SMD 0402")
    (property "Author" "Antmicro")
    (property "License" "Apache-2.0")
    (property "MPN" "CR0402-FX-1004GLF")
    (property "Manufacturer" "Bourns")
    (property "Sheetfile" "psu.kicad_sch")
    (property "Sheetname" "PSU")
    (property "Tolerance" "1%")
    (property "Val" "1M")
    (attr smd)
    (fp_text reference "R119" (at 1.46 -2.38 180) (layer "F.SilkS")
      (effects (font (size 0.7 0.7) (thickness 0.15)) (justify left bottom))
    )
    (fp_text value "R_1M_0402" (at 0 1.4 180) (layer "F.Fab")
      (effects (font (size 0.7 0.7) (thickness 0.15)) (justify left bottom))
    )
    (fp_text user "License: Apache-2.0" (at -0.95 5.169 180) (layer "F.Fab") hide
      (effects (font (size 0.7 0.7) (thickness 0.15)) (justify left bottom))
    )
    (fp_text user "Author: Antmicro" (at -0.95 4.169 180) (layer "F.Fab") hide
      (effects (font (size 0.7 0.7) (thickness 0.15)) (justify left bottom))
    )
    (fp_text user "${REFERENCE}" (at -0.95 3.168 180) (layer "F.Fab") hide
      (effects (font (size 0.7 0.7) (thickness 0.15)) (justify left bottom))
    )
    (fp_rect (start -0.93 -0.47) (end 0.93 0.47) (layer "F.CrtYd") (width 0.05) (fill none))
    (fp_rect (start -0.5 -0.25) (end 0.5 0.25) (layer "F.Fab") (width 0.15) (fill none))
    (pad "1" smd roundrect (at -0.485 0 180) (size 0.59 0.64) (layers "F.Cu" "F.Paste" "F.Mask") (roundrect_rratio 0.25)
      (net 74 "VDD") (pintype "passive"))
    (pad "2" smd roundrect (at 0.485 0 180) (size 0.59 0.64) (layers "F.Cu" "F.Paste" "F.Mask") (roundrect_rratio 0.25)
      (net 341 "/PSU/USB_PD_VALID") (pintype "passive"))
  )

  (footprint "sa800u-baseboard-hw-footprints:R_0402_1005Metric" (layer "F.Cu")
    (tedit 5FD9C158)
    (at 86.9 103.7 -90)
    (descr "Resistor SMD 0402")
    (tags "resistor SMD 0402")
    (property "Author" "Antmicro")
    (property "License" "Apache-2.0")
    (property "MPN" "CR0402-FX-1004GLF")
    (property "Manufacturer" "Bourns")
    (property "Sheetfile" "psu.kicad_sch")
    (property "Sheetname" "PSU")
    (property "Tolerance" "1%")
    (property "Val" "1M")
    (attr smd)
    (fp_text reference "R118" (at 1.63 -1.44 -90) (layer "F.SilkS")
      (effects (font (size 0.7 0.7) (thickness 0.15)) (justify left bottom))
    )
    (fp_text value "R_1M_0402" (at 0 1.4 -90) (layer "F.Fab")
      (effects (font (size 0.7 0.7) (thickness 0.15)) (justify left bottom))
    )
    (fp_text user "Author: Antmicro" (at -0.95 4.169 -90) (layer "F.Fab") hide
      (effects (font (size 0.7 0.7) (thickness 0.15)) (justify left bottom))
    )
    (fp_text user "${REFERENCE}" (at -0.95 3.168 -90) (layer "F.Fab") hide
      (effects (font (size 0.7 0.7) (thickness 0.15)) (justify left bottom))
    )
    (fp_text user "License: Apache-2.0" (at -0.95 5.169 -90) (layer "F.Fab") hide
      (effects (font (size 0.7 0.7) (thickness 0.15)) (justify left bottom))
    )
    (fp_rect (start -0.93 -0.47) (end 0.93 0.47) (layer "F.CrtYd") (width 0.05) (fill none))
    (fp_rect (start -0.5 -0.25) (end 0.5 0.25) (layer "F.Fab") (width 0.15) (fill none))
    (pad "1" smd roundrect (at -0.485 0 270) (size 0.59 0.64) (layers "F.Cu" "F.Paste" "F.Mask") (roundrect_rratio 0.25)
      (net 74 "VDD") (pintype "passive"))
    (pad "2" smd roundrect (at 0.485 0 270) (size 0.59 0.64) (layers "F.Cu" "F.Paste" "F.Mask") (roundrect_rratio 0.25)
      (net 340 "/PSU/POE_VALID") (pintype "passive"))
  )

  (footprint "sa800u-baseboard-hw-footprints:R_0402_1005Metric" (layer "F.Cu")
    (tedit 5FD9C158)
    (at 95.15 128 180)
    (descr "Resistor SMD 0402")
    (tags "resistor SMD 0402")
    (property "Author" "Antmicro")
    (property "Current" "1A")
    (property "License" "Apache-2.0")
    (property "MPN" "ERJ2GE0R00X")
    (property "Manufacturer" "Panasonic")
    (property "Sheetfile" "usb-pd.kicad_sch")
    (property "Sheetname" "USB-PD")
    (property "Tolerance" "")
    (property "Val" "0R")
    (attr smd)
    (fp_text reference "R165" (at -0.9 -0.44 180) (layer "F.SilkS")
      (effects (font (size 0.7 0.7) (thickness 0.15)) (justify left bottom))
    )
    (fp_text value "R_0R_0402" (at 0 1.4 180) (layer "F.Fab")
      (effects (font (size 0.7 0.7) (thickness 0.15)) (justify left bottom))
    )
    (fp_text user "${REFERENCE}" (at -0.95 3.168 180) (layer "F.Fab") hide
      (effects (font (size 0.7 0.7) (thickness 0.15)) (justify left bottom))
    )
    (fp_text user "License: Apache-2.0" (at -0.95 5.169 180) (layer "F.Fab") hide
      (effects (font (size 0.7 0.7) (thickness 0.15)) (justify left bottom))
    )
    (fp_text user "Author: Antmicro" (at -0.95 4.169 180) (layer "F.Fab") hide
      (effects (font (size 0.7 0.7) (thickness 0.15)) (justify left bottom))
    )
    (fp_rect (start -0.93 -0.47) (end 0.93 0.47) (layer "F.CrtYd") (width 0.05) (fill none))
    (fp_rect (start -0.5 -0.25) (end 0.5 0.25) (layer "F.Fab") (width 0.15) (fill none))
    (pad "1" smd roundrect (at -0.485 0 180) (size 0.59 0.64) (layers "F.Cu" "F.Paste" "F.Mask") (roundrect_rratio 0.25)
      (net 167 "STUSB4500_ATTACH") (pintype "passive"))
    (pad "2" smd roundrect (at 0.485 0 180) (size 0.59 0.64) (layers "F.Cu" "F.Paste" "F.Mask") (roundrect_rratio 0.25)
      (net 335 "/USB-PD/ATTACH") (pintype "passive"))
  )

  (footprint "sa800u-baseboard-hw-footprints:R_0402_1005Metric" (layer "F.Cu")
    (tedit 5FD9C158)
    (at 95.15 126 180)
    (descr "Resistor SMD 0402")
    (tags "resistor SMD 0402")
    (property "Author" "Antmicro")
    (property "Current" "1A")
    (property "License" "Apache-2.0")
    (property "MPN" "ERJ2GE0R00X")
    (property "Manufacturer" "Panasonic")
    (property "Sheetfile" "usb-pd.kicad_sch")
    (property "Sheetname" "USB-PD")
    (property "Tolerance" "")
    (property "Val" "0R")
    (attr smd)
    (fp_text reference "R164" (at -0.9 -0.44 180) (layer "F.SilkS")
      (effects (font (size 0.7 0.7) (thickness 0.15)) (justify left bottom))
    )
    (fp_text value "R_0R_0402" (at 0 1.4 180) (layer "F.Fab")
      (effects (font (size 0.7 0.7) (thickness 0.15)) (justify left bottom))
    )
    (fp_text user "License: Apache-2.0" (at -0.95 5.169 180) (layer "F.Fab") hide
      (effects (font (size 0.7 0.7) (thickness 0.15)) (justify left bottom))
    )
    (fp_text user "Author: Antmicro" (at -0.95 4.169 180) (layer "F.Fab") hide
      (effects (font (size 0.7 0.7) (thickness 0.15)) (justify left bottom))
    )
    (fp_text user "${REFERENCE}" (at -0.95 3.168 180) (layer "F.Fab") hide
      (effects (font (size 0.7 0.7) (thickness 0.15)) (justify left bottom))
    )
    (fp_rect (start -0.93 -0.47) (end 0.93 0.47) (layer "F.CrtYd") (width 0.05) (fill none))
    (fp_rect (start -0.5 -0.25) (end 0.5 0.25) (layer "F.Fab") (width 0.15) (fill none))
    (pad "1" smd roundrect (at -0.485 0 180) (size 0.59 0.64) (layers "F.Cu" "F.Paste" "F.Mask") (roundrect_rratio 0.25)
      (net 166 "STUSB4500_GPIO") (pintype "passive"))
    (pad "2" smd roundrect (at 0.485 0 180) (size 0.59 0.64) (layers "F.Cu" "F.Paste" "F.Mask") (roundrect_rratio 0.25)
      (net 334 "/USB-PD/GPIO") (pintype "passive"))
  )

  (footprint "sa800u-baseboard-hw-footprints:R_0402_1005Metric" (layer "F.Cu")
    (tedit 5FD9C158)
    (at 95.15 127 180)
    (descr "Resistor SMD 0402")
    (tags "resistor SMD 0402")
    (property "Author" "Antmicro")
    (property "Current" "1A")
    (property "License" "Apache-2.0")
    (property "MPN" "ERJ2GE0R00X")
    (property "Manufacturer" "Panasonic")
    (property "Sheetfile" "usb-pd.kicad_sch")
    (property "Sheetname" "USB-PD")
    (property "Tolerance" "")
    (property "Val" "0R")
    (attr smd)
    (fp_text reference "R163" (at -0.9 -0.44 180) (layer "F.SilkS")
      (effects (font (size 0.7 0.7) (thickness 0.15)) (justify left bottom))
    )
    (fp_text value "R_0R_0402" (at 0 1.4 180) (layer "F.Fab")
      (effects (font (size 0.7 0.7) (thickness 0.15)) (justify left bottom))
    )
    (fp_text user "Author: Antmicro" (at -0.95 4.169 180) (layer "F.Fab") hide
      (effects (font (size 0.7 0.7) (thickness 0.15)) (justify left bottom))
    )
    (fp_text user "License: Apache-2.0" (at -0.95 5.169 180) (layer "F.Fab") hide
      (effects (font (size 0.7 0.7) (thickness 0.15)) (justify left bottom))
    )
    (fp_text user "${REFERENCE}" (at -0.95 3.168 180) (layer "F.Fab") hide
      (effects (font (size 0.7 0.7) (thickness 0.15)) (justify left bottom))
    )
    (fp_rect (start -0.93 -0.47) (end 0.93 0.47) (layer "F.CrtYd") (width 0.05) (fill none))
    (fp_rect (start -0.5 -0.25) (end 0.5 0.25) (layer "F.Fab") (width 0.15) (fill none))
    (pad "1" smd roundrect (at -0.485 0 180) (size 0.59 0.64) (layers "F.Cu" "F.Paste" "F.Mask") (roundrect_rratio 0.25)
      (net 165 "STUSB4500_AB_SIDE") (pintype "passive"))
    (pad "2" smd roundrect (at 0.485 0 180) (size 0.59 0.64) (layers "F.Cu" "F.Paste" "F.Mask") (roundrect_rratio 0.25)
      (net 333 "/USB-PD/AB_SIDE") (pintype "passive"))
  )

  (footprint "sa800u-baseboard-hw-footprints:R_0402_1005Metric" (layer "F.Cu")
    (tedit 5FD9C158)
    (at 95.15 129 180)
    (descr "Resistor SMD 0402")
    (tags "resistor SMD 0402")
    (property "Author" "Antmicro")
    (property "Current" "1A")
    (property "License" "Apache-2.0")
    (property "MPN" "ERJ2GE0R00X")
    (property "Manufacturer" "Panasonic")
    (property "Sheetfile" "usb-pd.kicad_sch")
    (property "Sheetname" "USB-PD")
    (property "Tolerance" "")
    (property "Val" "0R")
    (attr smd)
    (fp_text reference "R162" (at -0.9 -0.44 180) (layer "F.SilkS")
      (effects (font (size 0.7 0.7) (thickness 0.15)) (justify left bottom))
    )
    (fp_text value "R_0R_0402" (at 0 1.4 180) (layer "F.Fab")
      (effects (font (size 0.7 0.7) (thickness 0.15)) (justify left bottom))
    )
    (fp_text user "${REFERENCE}" (at -0.95 3.168 180) (layer "F.Fab") hide
      (effects (font (size 0.7 0.7) (thickness 0.15)) (justify left bottom))
    )
    (fp_text user "Author: Antmicro" (at -0.95 4.169 180) (layer "F.Fab") hide
      (effects (font (size 0.7 0.7) (thickness 0.15)) (justify left bottom))
    )
    (fp_text user "License: Apache-2.0" (at -0.95 5.169 180) (layer "F.Fab") hide
      (effects (font (size 0.7 0.7) (thickness 0.15)) (justify left bottom))
    )
    (fp_rect (start -0.93 -0.47) (end 0.93 0.47) (layer "F.CrtYd") (width 0.05) (fill none))
    (fp_rect (start -0.5 -0.25) (end 0.5 0.25) (layer "F.Fab") (width 0.15) (fill none))
    (pad "1" smd roundrect (at -0.485 0 180) (size 0.59 0.64) (layers "F.Cu" "F.Paste" "F.Mask") (roundrect_rratio 0.25)
      (net 168 "STUSB4500_ALERT") (pintype "passive"))
    (pad "2" smd roundrect (at 0.485 0 180) (size 0.59 0.64) (layers "F.Cu" "F.Paste" "F.Mask") (roundrect_rratio 0.25)
      (net 332 "/USB-PD/ALERT") (pintype "passive"))
  )

  (footprint "sa800u-baseboard-hw-footprints:L_Murata_025020_0605Metric" (layer "F.Cu")
    (tedit 61AA2C4F)
    (at 152 121.5)
    (property "Author" "Antmicro")
    (property "License" "Apache-2.0")
    (property "MPN" "NFP0QHB242HS2D")
    (property "Manufacturer" "Murata")
    (property "Sheetfile" "lcm.kicad_sch")
    (property "Sheetname" "LCM")
    (attr smd)
    (fp_text reference "L12" (at -0.99 -0.72) (layer "F.SilkS")
      (effects (font (size 0.7 0.7) (thickness 0.15)) (justify left bottom))
    )
    (fp_text value "NFP0QHB242HS2D" (at 0 1.55) (layer "F.Fab")
      (effects (font (size 0.7 0.7) (thickness 0.15)) (justify left bottom))
    )
    (fp_text user "Author: Antmicro" (at -1.027 4.605) (layer "F.Fab") hide
      (effects (font (size 0.7 0.7) (thickness 0.15)) (justify left bottom))
    )
    (fp_text user "${REFERENCE}" (at -1.027 3.406) (layer "F.Fab") hide
      (effects (font (size 0.7 0.7) (thickness 0.15)) (justify left bottom))
    )
    (fp_text user "License: Apache-2.0" (at -1.027 5.805) (layer "F.Fab") hide
      (effects (font (size 0.7 0.7) (thickness 0.15)) (justify left bottom))
    )
    (fp_line (start 0.276 -0.45) (end -0.276 -0.45) (layer "F.SilkS") (width 0.15))
    (fp_line (start -0.276 0.45) (end 0.276 0.45) (layer "F.SilkS") (width 0.15))
    (fp_circle (center -0.5 -0.5) (end -0.449 -0.5) (layer "F.SilkS") (width 0.15) (fill solid))
    (fp_rect (start -0.5 -0.6) (end 0.5 0.6) (layer "F.CrtYd") (width 0.05) (fill none))
    (fp_line (start -0.277 0.349) (end 0.275 0.349) (layer "F.Fab") (width 0.15))
    (fp_line (start 0.275 -0.351) (end -0.277 -0.351) (layer "F.Fab") (width 0.15))
    (fp_line (start 0.275 0.349) (end 0.275 -0.351) (layer "F.Fab") (width 0.15))
    (fp_line (start -0.277 -0.351) (end -0.277 0.349) (layer "F.Fab") (width 0.15))
    (pad "1" smd rect (at -0.25 -0.24) (size 0.3 0.23) (layers "F.Cu" "F.Paste" "F.Mask")
      (net 316 "/LCM/DSI_LN2_L_N") (pinfunction "1") (pintype "passive"))
    (pad "2" smd rect (at 0.248 -0.24) (size 0.3 0.23) (layers "F.Cu" "F.Paste" "F.Mask")
      (net 91 "DSI0_LN2_N") (pinfunction "2") (pintype "passive"))
    (pad "3" smd rect (at 0.248 0.239) (size 0.3 0.23) (layers "F.Cu" "F.Paste" "F.Mask")
      (net 92 "DSI0_LN2_P") (pinfunction "3") (pintype "passive"))
    (pad "4" smd rect (at -0.25 0.239) (size 0.3 0.23) (layers "F.Cu" "F.Paste" "F.Mask")
      (net 315 "/LCM/DSI_LN2_L_P") (pinfunction "4") (pintype "passive"))
  )

  (footprint "sa800u-baseboard-hw-footprints:R_0402_1005Metric" (layer "F.Cu")
    (tedit 5FD9C158)
    (at 137.2 104)
    (descr "Resistor SMD 0402")
    (tags "resistor SMD 0402")
    (property "Author" "Antmicro")
    (property "DNP" "")
    (property "License" "Apache-2.0")
    (property "MPN" "CR0402-FX-1002GLF")
    (property "Manufacturer" "Bourns")
    (property "Sheetfile" "som.kicad_sch")
    (property "Sheetname" "SoM")
    (property "Tolerance" "1%")
    (property "Val" "10k")
    (attr smd)
    (fp_text reference "R175" (at 0.81 0.36) (layer "F.SilkS")
      (effects (font (size 0.7 0.7) (thickness 0.15)) (justify left bottom))
    )
    (fp_text value "R_10k_0402" (at 0 1.4) (layer "F.Fab")
      (effects (font (size 0.7 0.7) (thickness 0.15)) (justify left bottom))
    )
    (fp_text user "Author: Antmicro" (at -0.95 4.169) (layer "F.Fab") hide
      (effects (font (size 0.7 0.7) (thickness 0.15)) (justify left bottom))
    )
    (fp_text user "License: Apache-2.0" (at -0.95 5.169) (layer "F.Fab") hide
      (effects (font (size 0.7 0.7) (thickness 0.15)) (justify left bottom))
    )
    (fp_text user "${REFERENCE}" (at -0.95 3.168) (layer "F.Fab") hide
      (effects (font (size 0.7 0.7) (thickness 0.15)) (justify left bottom))
    )
    (fp_rect (start -0.93 -0.47) (end 0.93 0.47) (layer "F.CrtYd") (width 0.05) (fill none))
    (fp_rect (start -0.5 -0.25) (end 0.5 0.25) (layer "F.Fab") (width 0.15) (fill none))
    (pad "1" smd roundrect (at -0.485 0) (size 0.59 0.64) (layers "F.Cu" "F.Paste" "F.Mask") (roundrect_rratio 0.25)
      (net 132 "VREG_S4A_1V8") (pintype "passive"))
    (pad "2" smd roundrect (at 0.485 0) (size 0.59 0.64) (layers "F.Cu" "F.Paste" "F.Mask") (roundrect_rratio 0.25)
      (net 417 "Net-(R175-Pad2)") (pintype "passive"))
  )

  (footprint "sa800u-baseboard-hw-footprints:R_0402_1005Metric" (layer "F.Cu")
    (tedit 5FD9C158)
    (at 121.9 93.8 -90)
    (descr "Resistor SMD 0402")
    (tags "resistor SMD 0402")
    (property "Author" "Antmicro")
    (property "DNP" "DNP")
    (property "License" "Apache-2.0")
    (property "MPN" "CR0402-FX-1001GLF")
    (property "Manufacturer" "Bourns")
    (property "Sheetfile" "other-interfaces.kicad_sch")
    (property "Sheetname" "Other Interfaces")
    (property "Tolerance" "1%")
    (property "Val" "1k")
    (attr exclude_from_pos_files)
    (fp_text reference "R95" (at -0.84 -0.33 -90) (layer "F.SilkS")
      (effects (font (size 0.7 0.7) (thickness 0.15)) (justify left bottom))
    )
    (fp_text value "R_1k_0402" (at 0 1.4 -90) (layer "F.Fab")
      (effects (font (size 0.7 0.7) (thickness 0.15)) (justify left bottom))
    )
    (fp_text user "Author: Antmicro" (at -0.95 4.169 -90) (layer "F.Fab") hide
      (effects (font (size 0.7 0.7) (thickness 0.15)) (justify left bottom))
    )
    (fp_text user "${REFERENCE}" (at -0.95 3.168 -90) (layer "F.Fab") hide
      (effects (font (size 0.7 0.7) (thickness 0.15)) (justify left bottom))
    )
    (fp_text user "License: Apache-2.0" (at -0.95 5.169 -90) (layer "F.Fab") hide
      (effects (font (size 0.7 0.7) (thickness 0.15)) (justify left bottom))
    )
    (fp_rect (start -0.93 -0.47) (end 0.93 0.47) (layer "F.CrtYd") (width 0.05) (fill none))
    (fp_rect (start -0.5 -0.25) (end 0.5 0.25) (layer "F.Fab") (width 0.15) (fill none))
    (pad "1" smd roundrect (at -0.485 0 270) (size 0.59 0.64) (layers "F.Cu" "F.Paste" "F.Mask") (roundrect_rratio 0.25)
      (net 112 "SD_DET") (pintype "passive"))
    (pad "2" smd roundrect (at 0.485 0 270) (size 0.59 0.64) (layers "F.Cu" "F.Paste" "F.Mask") (roundrect_rratio 0.25)
      (net 246 "/Other Interfaces/SD_DET_R") (pintype "passive"))
  )

  (footprint "sa800u-baseboard-hw-footprints:R_0402_1005Metric" (layer "F.Cu")
    (tedit 5FD9C158)
    (at 122.9 93.8 -90)
    (descr "Resistor SMD 0402")
    (tags "resistor SMD 0402")
    (property "Author" "Antmicro")
    (property "License" "Apache-2.0")
    (property "MPN" "CR0402-FX-33R0GLF")
    (property "Manufacturer" "Bourns")
    (property "Sheetfile" "other-interfaces.kicad_sch")
    (property "Sheetname" "Other Interfaces")
    (property "Tolerance" "1%")
    (property "Val" "33R")
    (attr smd)
    (fp_text reference "R98" (at -0.84 -0.33 -90) (layer "F.SilkS")
      (effects (font (size 0.7 0.7) (thickness 0.15)) (justify left bottom))
    )
    (fp_text value "R_33R_0402" (at 0 1.4 -90) (layer "F.Fab")
      (effects (font (size 0.7 0.7) (thickness 0.15)) (justify left bottom))
    )
    (fp_text user "Author: Antmicro" (at -0.95 4.169 -90) (layer "F.Fab") hide
      (effects (font (size 0.7 0.7) (thickness 0.15)) (justify left bottom))
    )
    (fp_text user "${REFERENCE}" (at -0.95 3.168 -90) (layer "F.Fab") hide
      (effects (font (size 0.7 0.7) (thickness 0.15)) (justify left bottom))
    )
    (fp_text user "License: Apache-2.0" (at -0.95 5.169 -90) (layer "F.Fab") hide
      (effects (font (size 0.7 0.7) (thickness 0.15)) (justify left bottom))
    )
    (fp_rect (start -0.93 -0.47) (end 0.93 0.47) (layer "F.CrtYd") (width 0.05) (fill none))
    (fp_rect (start -0.5 -0.25) (end 0.5 0.25) (layer "F.Fab") (width 0.15) (fill none))
    (pad "1" smd roundrect (at -0.485 0 270) (size 0.59 0.64) (layers "F.Cu" "F.Paste" "F.Mask") (roundrect_rratio 0.25)
      (net 115 "SD_CMD") (pintype "passive"))
    (pad "2" smd roundrect (at 0.485 0 270) (size 0.59 0.64) (layers "F.Cu" "F.Paste" "F.Mask") (roundrect_rratio 0.25)
      (net 248 "/Other Interfaces/SD_CMD_R") (pintype "passive"))
  )

  (footprint "sa800u-baseboard-hw-footprints:R_0402_1005Metric" (layer "F.Cu")
    (tedit 5FD9C158)
    (at 119.9 93.8 -90)
    (descr "Resistor SMD 0402")
    (tags "resistor SMD 0402")
    (property "Author" "Antmicro")
    (property "License" "Apache-2.0")
    (property "MPN" "CR0402-FX-33R0GLF")
    (property "Manufacturer" "Bourns")
    (property "Sheetfile" "other-interfaces.kicad_sch")
    (property "Sheetname" "Other Interfaces")
    (property "Tolerance" "1%")
    (property "Val" "33R")
    (attr smd)
    (fp_text reference "R96" (at -0.84 -0.33 -90) (layer "F.SilkS")
      (effects (font (size 0.7 0.7) (thickness 0.15)) (justify left bottom))
    )
    (fp_text value "R_33R_0402" (at 0 1.4 -90) (layer "F.Fab")
      (effects (font (size 0.7 0.7) (thickness 0.15)) (justify left bottom))
    )
    (fp_text user "Author: Antmicro" (at -0.95 4.169 -90) (layer "F.Fab") hide
      (effects (font (size 0.7 0.7) (thickness 0.15)) (justify left bottom))
    )
    (fp_text user "License: Apache-2.0" (at -0.95 5.169 -90) (layer "F.Fab") hide
      (effects (font (size 0.7 0.7) (thickness 0.15)) (justify left bottom))
    )
    (fp_text user "${REFERENCE}" (at -0.95 3.168 -90) (layer "F.Fab") hide
      (effects (font (size 0.7 0.7) (thickness 0.15)) (justify left bottom))
    )
    (fp_rect (start -0.93 -0.47) (end 0.93 0.47) (layer "F.CrtYd") (width 0.05) (fill none))
    (fp_rect (start -0.5 -0.25) (end 0.5 0.25) (layer "F.Fab") (width 0.15) (fill none))
    (pad "1" smd roundrect (at -0.485 0 270) (size 0.59 0.64) (layers "F.Cu" "F.Paste" "F.Mask") (roundrect_rratio 0.25)
      (net 114 "SD_DATA2") (pintype "passive"))
    (pad "2" smd roundrect (at 0.485 0 270) (size 0.59 0.64) (layers "F.Cu" "F.Paste" "F.Mask") (roundrect_rratio 0.25)
      (net 247 "/Other Interfaces/SD_DATA2_R") (pintype "passive"))
  )

  (footprint "sa800u-baseboard-hw-footprints:R_0402_1005Metric" (layer "F.Cu")
    (tedit 5FD9C158)
    (at 120.9 93.8 -90)
    (descr "Resistor SMD 0402")
    (tags "resistor SMD 0402")
    (property "Author" "Antmicro")
    (property "License" "Apache-2.0")
    (property "MPN" "CR0402-FX-33R0GLF")
    (property "Manufacturer" "Bourns")
    (property "Sheetfile" "other-interfaces.kicad_sch")
    (property "Sheetname" "Other Interfaces")
    (property "Tolerance" "1%")
    (property "Val" "33R")
    (attr smd)
    (fp_text reference "R97" (at -0.84 -0.33 -90) (layer "F.SilkS")
      (effects (font (size 0.7 0.7) (thickness 0.15)) (justify left bottom))
    )
    (fp_text value "R_33R_0402" (at 0 1.4 -90) (layer "F.Fab")
      (effects (font (size 0.7 0.7) (thickness 0.15)) (justify left bottom))
    )
    (fp_text user "License: Apache-2.0" (at -0.95 5.169 -90) (layer "F.Fab") hide
      (effects (font (size 0.7 0.7) (thickness 0.15)) (justify left bottom))
    )
    (fp_text user "${REFERENCE}" (at -0.95 3.168 -90) (layer "F.Fab") hide
      (effects (font (size 0.7 0.7) (thickness 0.15)) (justify left bottom))
    )
    (fp_text user "Author: Antmicro" (at -0.95 4.169 -90) (layer "F.Fab") hide
      (effects (font (size 0.7 0.7) (thickness 0.15)) (justify left bottom))
    )
    (fp_rect (start -0.93 -0.47) (end 0.93 0.47) (layer "F.CrtYd") (width 0.05) (fill none))
    (fp_rect (start -0.5 -0.25) (end 0.5 0.25) (layer "F.Fab") (width 0.15) (fill none))
    (pad "1" smd roundrect (at -0.485 0 270) (size 0.59 0.64) (layers "F.Cu" "F.Paste" "F.Mask") (roundrect_rratio 0.25)
      (net 113 "SD_DATA3") (pintype "passive"))
    (pad "2" smd roundrect (at 0.485 0 270) (size 0.59 0.64) (layers "F.Cu" "F.Paste" "F.Mask") (roundrect_rratio 0.25)
      (net 249 "/Other Interfaces/SD_DATA3_R") (pintype "passive"))
  )

  (footprint "sa800u-baseboard-hw-footprints:LED_0603_1608Metric_G" (layer "F.Cu")
    (tedit 60C2DD7B)
    (at 153.2 138.16 180)
    (descr "LED SMD 0603 Green")
    (tags "LED SMD 0603 Green")
    (property "Author" "Antmicro")
    (property "License" "Apache-2.0")
    (property "MPN" "KP-1608ZGC")
    (property "Manufacturer" "Kingbright")
    (property "Sheetfile" "som.kicad_sch")
    (property "Sheetname" "SoM")
    (attr smd)
    (fp_text reference "D14" (at 1.08 -1.25 180) (layer "F.SilkS")
      (effects (font (size 0.7 0.7) (thickness 0.15)) (justify left bottom))
    )
    (fp_text value "KP-1608EC" (at 0 1.6 180) (layer "F.Fab")
      (effects (font (size 0.7 0.7) (thickness 0.15)) (justify left bottom))
    )
    (fp_text user "License: Apache-2.0" (at -1.31 5.769 180) (layer "F.Fab") hide
      (effects (font (size 0.7 0.7) (thickness 0.15)) (justify left bottom))
    )
    (fp_text user "${REFERENCE}" (at -1.31 3.769 180) (layer "F.Fab") hide
      (effects (font (size 0.7 0.7) (thickness 0.15)) (justify left bottom))
    )
    (fp_text user "Author: Antmicro" (at -1.31 4.769 180) (layer "F.Fab") hide
      (effects (font (size 0.7 0.7) (thickness 0.15)) (justify left bottom))
    )
    (fp_line (start 0.093672 -0.000008) (end -0.106328 0.199992) (layer "F.SilkS") (width 0.1))
    (fp_line (start -0.106328 -0.000008) (end -0.29 0) (layer "F.SilkS") (width 0.1))
    (fp_line (start -0.106328 -0.200008) (end -0.106328 0.199992) (layer "F.SilkS") (width 0.1))
    (fp_line (start -0.106328 -0.200008) (end 0.093672 -0.000008) (layer "F.SilkS") (width 0.1))
    (fp_line (start 0.093672 -0.200008) (end 0.093672 0.199992) (layer "F.SilkS") (width 0.1))
    (fp_line (start -0.27 -0.35) (end 0.27 -0.35) (layer "F.SilkS") (width 0.15))
    (fp_line (start 0.093672 -0.000008) (end 0.293672 -0.000008) (layer "F.SilkS") (width 0.1))
    (fp_line (start 1.25 0.32) (end 1.25 -0.32) (layer "F.SilkS") (width 0.15))
    (fp_line (start -0.27 0.351) (end 0.27 0.351) (layer "F.SilkS") (width 0.15))
    (fp_rect (start 1.26 0.65) (end -1.26 -0.65) (layer "F.CrtYd") (width 0.05) (fill none))
    (fp_line (start 0.199 0) (end 0.597 0) (layer "F.Fab") (width 0.15))
    (fp_line (start 0.101 0) (end -0.201 -0.2) (layer "F.Fab") (width 0.15))
    (fp_line (start -0.201 -0.2) (end -0.201 0) (layer "F.Fab") (width 0.15))
    (fp_line (start -0.201 0) (end -0.201 0.202) (layer "F.Fab") (width 0.15))
    (fp_line (start 0.199 0.202) (end 0.199 -0.1) (layer "F.Fab") (width 0.15))
    (fp_line (start -0.599 0) (end -0.201 0) (layer "F.Fab") (width 0.15))
    (fp_line (start 0.199 -0.2) (end 0.199 -0.1) (layer "F.Fab") (width 0.15))
    (fp_line (start -0.201 0.202) (end 0.101 0) (layer "F.Fab") (width 0.15))
    (fp_rect (start -0.848 -0.4) (end 0.85 0.402) (layer "F.Fab") (width 0.15) (fill none))
    (pad "1" smd rect (at -0.75 0) (size 0.8 0.8) (layers "F.Cu" "F.Paste" "F.Mask")
      (net 133 "5V_SYS") (pinfunction "1") (pintype "passive"))
    (pad "2" smd rect (at 0.75 0) (size 0.8 0.8) (layers "F.Cu" "F.Paste" "F.Mask")
      (net 371 "Net-(D14-Pad2)") (pinfunction "2") (pintype "passive"))
  )

  (footprint "sa800u-baseboard-hw-footprints:LED_0603_1608Metric_G" (layer "F.Cu")
    (tedit 60C2DD7B)
    (at 153.2 142 180)
    (descr "LED SMD 0603 Green")
    (tags "LED SMD 0603 Green")
    (property "Author" "Antmicro")
    (property "License" "Apache-2.0")
    (property "MPN" "KP-1608ZGC")
    (property "Manufacturer" "Kingbright")
    (property "Sheetfile" "som.kicad_sch")
    (property "Sheetname" "SoM")
    (attr smd)
    (fp_text reference "D15" (at 1.08 -1.26 180) (layer "F.SilkS")
      (effects (font (size 0.7 0.7) (thickness 0.15)) (justify left bottom))
    )
    (fp_text value "KP-1608EC" (at 0 1.6 180) (layer "F.Fab")
      (effects (font (size 0.7 0.7) (thickness 0.15)) (justify left bottom))
    )
    (fp_text user "Author: Antmicro" (at -1.31 4.769 180) (layer "F.Fab") hide
      (effects (font (size 0.7 0.7) (thickness 0.15)) (justify left bottom))
    )
    (fp_text user "${REFERENCE}" (at -1.31 3.769 180) (layer "F.Fab") hide
      (effects (font (size 0.7 0.7) (thickness 0.15)) (justify left bottom))
    )
    (fp_text user "License: Apache-2.0" (at -1.31 5.769 180) (layer "F.Fab") hide
      (effects (font (size 0.7 0.7) (thickness 0.15)) (justify left bottom))
    )
    (fp_line (start 1.25 0.32) (end 1.25 -0.32) (layer "F.SilkS") (width 0.15))
    (fp_line (start -0.106328 -0.200008) (end -0.106328 0.199992) (layer "F.SilkS") (width 0.1))
    (fp_line (start -0.106328 -0.000008) (end -0.29 0) (layer "F.SilkS") (width 0.1))
    (fp_line (start 0.093672 -0.000008) (end -0.106328 0.199992) (layer "F.SilkS") (width 0.1))
    (fp_line (start -0.27 -0.35) (end 0.27 -0.35) (layer "F.SilkS") (width 0.15))
    (fp_line (start -0.106328 -0.200008) (end 0.093672 -0.000008) (layer "F.SilkS") (width 0.1))
    (fp_line (start 0.093672 -0.000008) (end 0.293672 -0.000008) (layer "F.SilkS") (width 0.1))
    (fp_line (start 0.093672 -0.200008) (end 0.093672 0.199992) (layer "F.SilkS") (width 0.1))
    (fp_line (start -0.27 0.351) (end 0.27 0.351) (layer "F.SilkS") (width 0.15))
    (fp_rect (start 1.26 0.65) (end -1.26 -0.65) (layer "F.CrtYd") (width 0.05) (fill none))
    (fp_line (start 0.199 0.202) (end 0.199 -0.1) (layer "F.Fab") (width 0.15))
    (fp_line (start 0.199 0) (end 0.597 0) (layer "F.Fab") (width 0.15))
    (fp_line (start -0.201 0.202) (end 0.101 0) (layer "F.Fab") (width 0.15))
    (fp_line (start 0.101 0) (end -0.201 -0.2) (layer "F.Fab") (width 0.15))
    (fp_line (start -0.201 -0.2) (end -0.201 0) (layer "F.Fab") (width 0.15))
    (fp_line (start -0.201 0) (end -0.201 0.202) (layer "F.Fab") (width 0.15))
    (fp_line (start 0.199 -0.2) (end 0.199 -0.1) (layer "F.Fab") (width 0.15))
    (fp_line (start -0.599 0) (end -0.201 0) (layer "F.Fab") (width 0.15))
    (fp_rect (start -0.848 -0.4) (end 0.85 0.402) (layer "F.Fab") (width 0.15) (fill none))
    (pad "1" smd rect (at -0.75 0) (size 0.8 0.8) (layers "F.Cu" "F.Paste" "F.Mask")
      (net 133 "5V_SYS") (pinfunction "1") (pintype "passive"))
    (pad "2" smd rect (at 0.75 0) (size 0.8 0.8) (layers "F.Cu" "F.Paste" "F.Mask")
      (net 372 "Net-(D15-Pad2)") (pinfunction "2") (pintype "passive"))
  )

  (footprint "sa800u-baseboard-hw-footprints:LED_0603_1608Metric_G" (layer "F.Cu")
    (tedit 60C2DD7B)
    (at 153.2 134.34 180)
    (descr "LED SMD 0603 Green")
    (tags "LED SMD 0603 Green")
    (property "Author" "Antmicro")
    (property "License" "Apache-2.0")
    (property "MPN" "KP-1608ZGC")
    (property "Manufacturer" "Kingbright")
    (property "Sheetfile" "som.kicad_sch")
    (property "Sheetname" "SoM")
    (attr smd)
    (fp_text reference "D16" (at 1.08 -1.26 180) (layer "F.SilkS")
      (effects (font (size 0.7 0.7) (thickness 0.15)) (justify left bottom))
    )
    (fp_text value "KP-1608EC" (at 0 1.6 180) (layer "F.Fab")
      (effects (font (size 0.7 0.7) (thickness 0.15)) (justify left bottom))
    )
    (fp_text user "License: Apache-2.0" (at -1.31 5.769 180) (layer "F.Fab") hide
      (effects (font (size 0.7 0.7) (thickness 0.15)) (justify left bottom))
    )
    (fp_text user "Author: Antmicro" (at -1.31 4.769 180) (layer "F.Fab") hide
      (effects (font (size 0.7 0.7) (thickness 0.15)) (justify left bottom))
    )
    (fp_text user "${REFERENCE}" (at -1.31 3.769 180) (layer "F.Fab") hide
      (effects (font (size 0.7 0.7) (thickness 0.15)) (justify left bottom))
    )
    (fp_line (start -0.106328 -0.200008) (end -0.106328 0.199992) (layer "F.SilkS") (width 0.1))
    (fp_line (start 1.25 0.32) (end 1.25 -0.32) (layer "F.SilkS") (width 0.15))
    (fp_line (start -0.106328 -0.000008) (end -0.29 0) (layer "F.SilkS") (width 0.1))
    (fp_line (start 0.093672 -0.000008) (end 0.293672 -0.000008) (layer "F.SilkS") (width 0.1))
    (fp_line (start 0.093672 -0.200008) (end 0.093672 0.199992) (layer "F.SilkS") (width 0.1))
    (fp_line (start 0.093672 -0.000008) (end -0.106328 0.199992) (layer "F.SilkS") (width 0.1))
    (fp_line (start -0.27 0.351) (end 0.27 0.351) (layer "F.SilkS") (width 0.15))
    (fp_line (start -0.27 -0.35) (end 0.27 -0.35) (layer "F.SilkS") (width 0.15))
    (fp_line (start -0.106328 -0.200008) (end 0.093672 -0.000008) (layer "F.SilkS") (width 0.1))
    (fp_rect (start 1.26 0.65) (end -1.26 -0.65) (layer "F.CrtYd") (width 0.05) (fill none))
    (fp_line (start -0.599 0) (end -0.201 0) (layer "F.Fab") (width 0.15))
    (fp_line (start -0.201 -0.2) (end -0.201 0) (layer "F.Fab") (width 0.15))
    (fp_line (start -0.201 0) (end -0.201 0.202) (layer "F.Fab") (width 0.15))
    (fp_line (start 0.199 0) (end 0.597 0) (layer "F.Fab") (width 0.15))
    (fp_line (start 0.199 0.202) (end 0.199 -0.1) (layer "F.Fab") (width 0.15))
    (fp_line (start 0.101 0) (end -0.201 -0.2) (layer "F.Fab") (width 0.15))
    (fp_line (start -0.201 0.202) (end 0.101 0) (layer "F.Fab") (width 0.15))
    (fp_line (start 0.199 -0.2) (end 0.199 -0.1) (layer "F.Fab") (width 0.15))
    (fp_rect (start -0.848 -0.4) (end 0.85 0.402) (layer "F.Fab") (width 0.15) (fill none))
    (pad "1" smd rect (at -0.75 0) (size 0.8 0.8) (layers "F.Cu" "F.Paste" "F.Mask")
      (net 133 "5V_SYS") (pinfunction "1") (pintype "passive"))
    (pad "2" smd rect (at 0.75 0) (size 0.8 0.8) (layers "F.Cu" "F.Paste" "F.Mask")
      (net 75 "Net-(D16-Pad2)") (pinfunction "2") (pintype "passive"))
  )

  (footprint "sa800u-baseboard-hw-footprints:R_0402_1005Metric" (layer "F.Cu")
    (tedit 5FD9C158)
    (at 150.8 141.8)
    (descr "Resistor SMD 0402")
    (tags "resistor SMD 0402")
    (property "Author" "Antmicro")
    (property "License" "Apache-2.0")
    (property "MPN" "CR0402-FX-1002GLF")
    (property "Manufacturer" "Bourns")
    (property "Sheetfile" "som.kicad_sch")
    (property "Sheetname" "SoM")
    (property "Tolerance" "1%")
    (property "Val" "10k")
    (attr smd)
    (fp_text reference "R78" (at -1.09 1.32) (layer "F.SilkS")
      (effects (font (size 0.7 0.7) (thickness 0.15)) (justify left bottom))
    )
    (fp_text value "R_10k_0402" (at 0 1.4) (layer "F.Fab")
      (effects (font (size 0.7 0.7) (thickness 0.15)) (justify left bottom))
    )
    (fp_text user "Author: Antmicro" (at -0.95 4.169) (layer "F.Fab") hide
      (effects (font (size 0.7 0.7) (thickness 0.15)) (justify left bottom))
    )
    (fp_text user "License: Apache-2.0" (at -0.95 5.169) (layer "F.Fab") hide
      (effects (font (size 0.7 0.7) (thickness 0.15)) (justify left bottom))
    )
    (fp_text user "${REFERENCE}" (at -0.95 3.168) (layer "F.Fab") hide
      (effects (font (size 0.7 0.7) (thickness 0.15)) (justify left bottom))
    )
    (fp_rect (start -0.93 -0.47) (end 0.93 0.47) (layer "F.CrtYd") (width 0.05) (fill none))
    (fp_rect (start -0.5 -0.25) (end 0.5 0.25) (layer "F.Fab") (width 0.15) (fill none))
    (pad "1" smd roundrect (at -0.485 0) (size 0.59 0.64) (layers "F.Cu" "F.Paste" "F.Mask") (roundrect_rratio 0.25)
      (net 386 "Net-(Q6-Pad3)") (pintype "passive"))
    (pad "2" smd roundrect (at 0.485 0) (size 0.59 0.64) (layers "F.Cu" "F.Paste" "F.Mask") (roundrect_rratio 0.25)
      (net 372 "Net-(D15-Pad2)") (pintype "passive"))
  )

  (footprint "sa800u-baseboard-hw-footprints:R_0402_1005Metric" (layer "F.Cu")
    (tedit 5FD9C158)
    (at 150.8 134.2)
    (descr "Resistor SMD 0402")
    (tags "resistor SMD 0402")
    (property "Author" "Antmicro")
    (property "License" "Apache-2.0")
    (property "MPN" "CR0402-FX-1002GLF")
    (property "Manufacturer" "Bourns")
    (property "Sheetfile" "som.kicad_sch")
    (property "Sheetname" "SoM")
    (property "Tolerance" "1%")
    (property "Val" "10k")
    (attr smd)
    (fp_text reference "R79" (at -1.09 1.33) (layer "F.SilkS")
      (effects (font (size 0.7 0.7) (thickness 0.15)) (justify left bottom))
    )
    (fp_text value "R_10k_0402" (at 0 1.4) (layer "F.Fab")
      (effects (font (size 0.7 0.7) (thickness 0.15)) (justify left bottom))
    )
    (fp_text user "License: Apache-2.0" (at -0.95 5.169) (layer "F.Fab") hide
      (effects (font (size 0.7 0.7) (thickness 0.15)) (justify left bottom))
    )
    (fp_text user "${REFERENCE}" (at -0.95 3.168) (layer "F.Fab") hide
      (effects (font (size 0.7 0.7) (thickness 0.15)) (justify left bottom))
    )
    (fp_text user "Author: Antmicro" (at -0.95 4.169) (layer "F.Fab") hide
      (effects (font (size 0.7 0.7) (thickness 0.15)) (justify left bottom))
    )
    (fp_rect (start -0.93 -0.47) (end 0.93 0.47) (layer "F.CrtYd") (width 0.05) (fill none))
    (fp_rect (start -0.5 -0.25) (end 0.5 0.25) (layer "F.Fab") (width 0.15) (fill none))
    (pad "1" smd roundrect (at -0.485 0) (size 0.59 0.64) (layers "F.Cu" "F.Paste" "F.Mask") (roundrect_rratio 0.25)
      (net 387 "Net-(Q7-Pad3)") (pintype "passive"))
    (pad "2" smd roundrect (at 0.485 0) (size 0.59 0.64) (layers "F.Cu" "F.Paste" "F.Mask") (roundrect_rratio 0.25)
      (net 75 "Net-(D16-Pad2)") (pintype "passive"))
  )

  (footprint "sa800u-baseboard-hw-footprints:R_0402_1005Metric" (layer "F.Cu")
    (tedit 5FD9C158)
    (at 87 132.4 -90)
    (descr "Resistor SMD 0402")
    (tags "resistor SMD 0402")
    (property "Author" "Antmicro")
    (property "License" "Apache-2.0")
    (property "MPN" "CR0402-FX-1101GLF")
    (property "Manufacturer" "Bourns")
    (property "Sheetfile" "usb-pd.kicad_sch")
    (property "Sheetname" "USB-PD")
    (property "Tolerance" "1%")
    (property "Val" "1k1")
    (attr smd)
    (fp_text reference "R169" (at -0.88 -0.22 -90) (layer "F.SilkS")
      (effects (font (size 0.7 0.7) (thickness 0.15)) (justify left bottom))
    )
    (fp_text value "R_1k1_0402" (at 0 1.4 -90) (layer "F.Fab")
      (effects (font (size 0.7 0.7) (thickness 0.15)) (justify left bottom))
    )
    (fp_text user "License: Apache-2.0" (at -0.95 5.169 -90) (layer "F.Fab") hide
      (effects (font (size 0.7 0.7) (thickness 0.15)) (justify left bottom))
    )
    (fp_text user "${REFERENCE}" (at -0.95 3.168 -90) (layer "F.Fab") hide
      (effects (font (size 0.7 0.7) (thickness 0.15)) (justify left bottom))
    )
    (fp_text user "Author: Antmicro" (at -0.95 4.169 -90) (layer "F.Fab") hide
      (effects (font (size 0.7 0.7) (thickness 0.15)) (justify left bottom))
    )
    (fp_rect (start -0.93 -0.47) (end 0.93 0.47) (layer "F.CrtYd") (width 0.05) (fill none))
    (fp_rect (start -0.5 -0.25) (end 0.5 0.25) (layer "F.Fab") (width 0.15) (fill none))
    (pad "1" smd roundrect (at -0.485 0 270) (size 0.59 0.64) (layers "F.Cu" "F.Paste" "F.Mask") (roundrect_rratio 0.25)
      (net 142 "PD_VDD") (pintype "passive"))
    (pad "2" smd roundrect (at 0.485 0 270) (size 0.59 0.64) (layers "F.Cu" "F.Paste" "F.Mask") (roundrect_rratio 0.25)
      (net 468 "/USB-PD/DISCH") (pintype "passive"))
  )

  (footprint "sa800u-baseboard-hw-footprints:R_0402_1005Metric" (layer "F.Cu")
    (tedit 5FD9C158)
    (at 92.85 126 180)
    (descr "Resistor SMD 0402")
    (tags "resistor SMD 0402")
    (property "Author" "Antmicro")
    (property "License" "Apache-2.0")
    (property "MPN" "CR0402-FX-4701GLF")
    (property "Manufacturer" "Bourns")
    (property "Sheetfile" "usb-pd.kicad_sch")
    (property "Sheetname" "USB-PD")
    (property "Tolerance" "1%")
    (property "Val" "4k7")
    (attr smd)
    (fp_text reference "R170" (at 3.75 -0.32 180) (layer "F.SilkS")
      (effects (font (size 0.7 0.7) (thickness 0.15)) (justify left bottom))
    )
    (fp_text value "R_4k7_0402" (at 0 1.4 180) (layer "F.Fab")
      (effects (font (size 0.7 0.7) (thickness 0.15)) (justify left bottom))
    )
    (fp_text user "License: Apache-2.0" (at -0.95 5.169 180) (layer "F.Fab") hide
      (effects (font (size 0.7 0.7) (thickness 0.15)) (justify left bottom))
    )
    (fp_text user "Author: Antmicro" (at -0.95 4.169 180) (layer "F.Fab") hide
      (effects (font (size 0.7 0.7) (thickness 0.15)) (justify left bottom))
    )
    (fp_text user "${REFERENCE}" (at -0.95 3.168 180) (layer "F.Fab") hide
      (effects (font (size 0.7 0.7) (thickness 0.15)) (justify left bottom))
    )
    (fp_rect (start -0.93 -0.47) (end 0.93 0.47) (layer "F.CrtYd") (width 0.05) (fill none))
    (fp_rect (start -0.5 -0.25) (end 0.5 0.25) (layer "F.Fab") (width 0.15) (fill none))
    (pad "1" smd roundrect (at -0.485 0 180) (size 0.59 0.64) (layers "F.Cu" "F.Paste" "F.Mask") (roundrect_rratio 0.25)
      (net 334 "/USB-PD/GPIO") (pintype "passive"))
    (pad "2" smd roundrect (at 0.485 0 180) (size 0.59 0.64) (layers "F.Cu" "F.Paste" "F.Mask") (roundrect_rratio 0.25)
      (net 132 "VREG_S4A_1V8") (pintype "passive"))
  )

  (footprint "sa800u-baseboard-hw-footprints:R_0402_1005Metric" (layer "F.Cu")
    (tedit 5FD9C158)
    (at 92.85 128 180)
    (descr "Resistor SMD 0402")
    (tags "resistor SMD 0402")
    (property "Author" "Antmicro")
    (property "License" "Apache-2.0")
    (property "MPN" "CR0402-FX-4701GLF")
    (property "Manufacturer" "Bourns")
    (property "Sheetfile" "usb-pd.kicad_sch")
    (property "Sheetname" "USB-PD")
    (property "Tolerance" "1%")
    (property "Val" "4k7")
    (attr smd)
    (fp_text reference "R172" (at 3.75 -0.32 180) (layer "F.SilkS")
      (effects (font (size 0.7 0.7) (thickness 0.15)) (justify left bottom))
    )
    (fp_text value "R_4k7_0402" (at 0 1.4 180) (layer "F.Fab")
      (effects (font (size 0.7 0.7) (thickness 0.15)) (justify left bottom))
    )
    (fp_text user "License: Apache-2.0" (at -0.95 5.169 180) (layer "F.Fab") hide
      (effects (font (size 0.7 0.7) (thickness 0.15)) (justify left bottom))
    )
    (fp_text user "${REFERENCE}" (at -0.95 3.168 180) (layer "F.Fab") hide
      (effects (font (size 0.7 0.7) (thickness 0.15)) (justify left bottom))
    )
    (fp_text user "Author: Antmicro" (at -0.95 4.169 180) (layer "F.Fab") hide
      (effects (font (size 0.7 0.7) (thickness 0.15)) (justify left bottom))
    )
    (fp_rect (start -0.93 -0.47) (end 0.93 0.47) (layer "F.CrtYd") (width 0.05) (fill none))
    (fp_rect (start -0.5 -0.25) (end 0.5 0.25) (layer "F.Fab") (width 0.15) (fill none))
    (pad "1" smd roundrect (at -0.485 0 180) (size 0.59 0.64) (layers "F.Cu" "F.Paste" "F.Mask") (roundrect_rratio 0.25)
      (net 335 "/USB-PD/ATTACH") (pintype "passive"))
    (pad "2" smd roundrect (at 0.485 0 180) (size 0.59 0.64) (layers "F.Cu" "F.Paste" "F.Mask") (roundrect_rratio 0.25)
      (net 132 "VREG_S4A_1V8") (pintype "passive"))
  )

  (footprint "sa800u-baseboard-hw-footprints:R_0402_1005Metric" (layer "F.Cu")
    (tedit 5FD9C158)
    (at 92.85 127 180)
    (descr "Resistor SMD 0402")
    (tags "resistor SMD 0402")
    (property "Author" "Antmicro")
    (property "License" "Apache-2.0")
    (property "MPN" "CR0402-FX-4701GLF")
    (property "Manufacturer" "Bourns")
    (property "Sheetfile" "usb-pd.kicad_sch")
    (property "Sheetname" "USB-PD")
    (property "Tolerance" "1%")
    (property "Val" "4k7")
    (attr smd)
    (fp_text reference "R168" (at 3.75 -0.32 180) (layer "F.SilkS")
      (effects (font (size 0.7 0.7) (thickness 0.15)) (justify left bottom))
    )
    (fp_text value "R_4k7_0402" (at 0 1.4 180) (layer "F.Fab")
      (effects (font (size 0.7 0.7) (thickness 0.15)) (justify left bottom))
    )
    (fp_text user "License: Apache-2.0" (at -0.95 5.169 180) (layer "F.Fab") hide
      (effects (font (size 0.7 0.7) (thickness 0.15)) (justify left bottom))
    )
    (fp_text user "${REFERENCE}" (at -0.95 3.168 180) (layer "F.Fab") hide
      (effects (font (size 0.7 0.7) (thickness 0.15)) (justify left bottom))
    )
    (fp_text user "Author: Antmicro" (at -0.95 4.169 180) (layer "F.Fab") hide
      (effects (font (size 0.7 0.7) (thickness 0.15)) (justify left bottom))
    )
    (fp_rect (start -0.93 -0.47) (end 0.93 0.47) (layer "F.CrtYd") (width 0.05) (fill none))
    (fp_rect (start -0.5 -0.25) (end 0.5 0.25) (layer "F.Fab") (width 0.15) (fill none))
    (pad "1" smd roundrect (at -0.485 0 180) (size 0.59 0.64) (layers "F.Cu" "F.Paste" "F.Mask") (roundrect_rratio 0.25)
      (net 333 "/USB-PD/AB_SIDE") (pintype "passive"))
    (pad "2" smd roundrect (at 0.485 0 180) (size 0.59 0.64) (layers "F.Cu" "F.Paste" "F.Mask") (roundrect_rratio 0.25)
      (net 132 "VREG_S4A_1V8") (pintype "passive"))
  )

  (footprint "sa800u-baseboard-hw-footprints:R_0402_1005Metric" (layer "F.Cu")
    (tedit 5FD9C158)
    (at 92.85 129 180)
    (descr "Resistor SMD 0402")
    (tags "resistor SMD 0402")
    (property "Author" "Antmicro")
    (property "License" "Apache-2.0")
    (property "MPN" "CR0402-FX-4701GLF")
    (property "Manufacturer" "Bourns")
    (property "Sheetfile" "usb-pd.kicad_sch")
    (property "Sheetname" "USB-PD")
    (property "Tolerance" "1%")
    (property "Val" "4k7")
    (attr smd)
    (fp_text reference "R167" (at 3.75 -0.32 180) (layer "F.SilkS")
      (effects (font (size 0.7 0.7) (thickness 0.15)) (justify left bottom))
    )
    (fp_text value "R_4k7_0402" (at 0 1.4 180) (layer "F.Fab")
      (effects (font (size 0.7 0.7) (thickness 0.15)) (justify left bottom))
    )
    (fp_text user "Author: Antmicro" (at -0.95 4.169 180) (layer "F.Fab") hide
      (effects (font (size 0.7 0.7) (thickness 0.15)) (justify left bottom))
    )
    (fp_text user "License: Apache-2.0" (at -0.95 5.169 180) (layer "F.Fab") hide
      (effects (font (size 0.7 0.7) (thickness 0.15)) (justify left bottom))
    )
    (fp_text user "${REFERENCE}" (at -0.95 3.168 180) (layer "F.Fab") hide
      (effects (font (size 0.7 0.7) (thickness 0.15)) (justify left bottom))
    )
    (fp_rect (start -0.93 -0.47) (end 0.93 0.47) (layer "F.CrtYd") (width 0.05) (fill none))
    (fp_rect (start -0.5 -0.25) (end 0.5 0.25) (layer "F.Fab") (width 0.15) (fill none))
    (pad "1" smd roundrect (at -0.485 0 180) (size 0.59 0.64) (layers "F.Cu" "F.Paste" "F.Mask") (roundrect_rratio 0.25)
      (net 332 "/USB-PD/ALERT") (pintype "passive"))
    (pad "2" smd roundrect (at 0.485 0 180) (size 0.59 0.64) (layers "F.Cu" "F.Paste" "F.Mask") (roundrect_rratio 0.25)
      (net 132 "VREG_S4A_1V8") (pintype "passive"))
  )

  (footprint "sa800u-baseboard-hw-footprints:R_0402_1005Metric" (layer "F.Cu")
    (tedit 5FD9C158)
    (at 145.9 128.8 -90)
    (descr "Resistor SMD 0402")
    (tags "resistor SMD 0402")
    (property "Author" "Antmicro")
    (property "DNP" "DNP")
    (property "License" "Apache-2.0")
    (property "MPN" "CR0402-FX-1004GLF")
    (property "Manufacturer" "Bourns")
    (property "Sheetfile" "hdmi-converter.kicad_sch")
    (property "Sheetname" "HDMI converter")
    (property "Tolerance" "1%")
    (property "Val" "1M")
    (attr exclude_from_pos_files)
    (fp_text reference "R21" (at -0.84 -0.43 -90) (layer "F.SilkS")
      (effects (font (size 0.7 0.7) (thickness 0.15)) (justify left bottom))
    )
    (fp_text value "R_1M_0402" (at 0 1.4 -90) (layer "F.Fab")
      (effects (font (size 0.7 0.7) (thickness 0.15)) (justify left bottom))
    )
    (fp_text user "Author: Antmicro" (at -0.95 4.169 -90) (layer "F.Fab") hide
      (effects (font (size 0.7 0.7) (thickness 0.15)) (justify left bottom))
    )
    (fp_text user "License: Apache-2.0" (at -0.95 5.169 -90) (layer "F.Fab") hide
      (effects (font (size 0.7 0.7) (thickness 0.15)) (justify left bottom))
    )
    (fp_text user "${REFERENCE}" (at -0.95 3.168 -90) (layer "F.Fab") hide
      (effects (font (size 0.7 0.7) (thickness 0.15)) (justify left bottom))
    )
    (fp_rect (start -0.93 -0.47) (end 0.93 0.47) (layer "F.CrtYd") (width 0.05) (fill none))
    (fp_rect (start -0.5 -0.25) (end 0.5 0.25) (layer "F.Fab") (width 0.15) (fill none))
    (pad "1" smd roundrect (at -0.485 0 270) (size 0.59 0.64) (layers "F.Cu" "F.Paste" "F.Mask") (roundrect_rratio 0.25)
      (net 190 "/HDMI converter/XTALO") (pintype "passive"))
    (pad "2" smd roundrect (at 0.485 0 270) (size 0.59 0.64) (layers "F.Cu" "F.Paste" "F.Mask") (roundrect_rratio 0.25)
      (net 192 "/HDMI converter/XTALI") (pintype "passive"))
  )

  (footprint "sa800u-baseboard-hw-footprints:R_0402_1005Metric" (layer "F.Cu")
    (tedit 5FD9C158)
    (at 145.75 136.9 -90)
    (descr "Resistor SMD 0402")
    (tags "resistor SMD 0402")
    (property "Author" "Antmicro")
    (property "License" "Apache-2.0")
    (property "MPN" "CR0402-FX-5100GLF")
    (property "Manufacturer" "Bourns")
    (property "Sheetfile" "hdmi-converter.kicad_sch")
    (property "Sheetname" "HDMI converter")
    (property "Tolerance" "1%")
    (property "Val" "510R")
    (attr smd)
    (fp_text reference "R55" (at -4.601 16.48 -90) (layer "F.SilkS")
      (effects (font (size 0.7 0.7) (thickness 0.15)) (justify left bottom))
    )
    (fp_text value "R_510R_0402" (at 0 1.4 -90) (layer "F.Fab")
      (effects (font (size 0.7 0.7) (thickness 0.15)) (justify left bottom))
    )
    (fp_text user "Author: Antmicro" (at -0.95 4.169 -90) (layer "F.Fab") hide
      (effects (font (size 0.7 0.7) (thickness 0.15)) (justify left bottom))
    )
    (fp_text user "License: Apache-2.0" (at -0.95 5.169 -90) (layer "F.Fab") hide
      (effects (font (size 0.7 0.7) (thickness 0.15)) (justify left bottom))
    )
    (fp_text user "${REFERENCE}" (at -0.95 3.168 -90) (layer "F.Fab") hide
      (effects (font (size 0.7 0.7) (thickness 0.15)) (justify left bottom))
    )
    (fp_rect (start -0.93 -0.47) (end 0.93 0.47) (layer "F.CrtYd") (width 0.05) (fill none))
    (fp_rect (start -0.5 -0.25) (end 0.5 0.25) (layer "F.Fab") (width 0.15) (fill none))
    (pad "1" smd roundrect (at -0.485 0 270) (size 0.59 0.64) (layers "F.Cu" "F.Paste" "F.Mask") (roundrect_rratio 0.25)
      (net 195 "/HDMI converter/HDMI_TX2_N") (pintype "passive"))
    (pad "2" smd roundrect (at 0.485 0 270) (size 0.59 0.64) (layers "F.Cu" "F.Paste" "F.Mask") (roundrect_rratio 0.25)
      (net 209 "/HDMI converter/VCOM") (pintype "passive"))
  )

  (footprint "sa800u-baseboard-hw-footprints:UQFN-12_2x1.7mm_P0.4mm_Texas_RUT" (layer "F.Cu")
    (tedit 5F354333)
    (at 133.888164 127.312953)
    (descr "Texas_R_PUQFN-N12")
    (tags "Texas_R_PUQFN-N12")
    (property "Author" "Antmicro")
    (property "License" "Apache-2.0")
    (property "MPN" "TXB0104RUTR")
    (property "Manufacturer" "Texas Instruments")
    (property "Sheetfile" "hdmi-converter.kicad_sch")
    (property "Sheetname" "HDMI converter")
    (attr smd)
    (fp_text reference "U2" (at 1.931836 0.767047 90) (layer "F.SilkS")
      (effects (font (size 0.7 0.7) (thickness 0.15)) (justify left bottom))
    )
    (fp_text value "TXB0104_UQFN" (at 0 2.35) (layer "F.Fab")
      (effects (font (size 0.7 0.7) (thickness 0.15)) (justify left bottom))
    )
    (fp_text user "License: Apache-2.0" (at -1.1 6.75) (layer "F.Fab") hide
      (effects (font (size 0.7 0.7) (thickness 0.15)) (justify left bottom))
    )
    (fp_text user "${REFERENCE}" (at -1.1 5.55) (layer "F.Fab") hide
      (effects (font (size 0.7 0.7) (thickness 0.15)) (justify left bottom))
    )
    (fp_text user "Author: Antmicro" (at -1.1 4.35) (layer "F.Fab") hide
      (effects (font (size 0.7 0.7) (thickness 0.15)) (justify left bottom))
    )
    (fp_line (start 0.497 1.3) (end -0.5 1.3) (layer "F.SilkS") (width 0.15))
    (fp_line (start 0.597 -1.301) (end -0.55 -1.301) (layer "F.SilkS") (width 0.15))
    (fp_circle (center -0.85 -1.2) (end -0.8 -1.2) (layer "F.SilkS") (width 0.15) (fill solid))
    (fp_rect (start -1.1 -1.3) (end 1.1 1.3) (layer "F.CrtYd") (width 0.05) (fill none))
    (fp_line (start 0.847 -1) (end 0.847 0.997) (layer "F.Fab") (width 0.15))
    (fp_line (start -0.5 -1) (end 0.847 -1) (layer "F.Fab") (width 0.15))
    (fp_line (start -0.85 0.997) (end -0.85 -0.5) (layer "F.Fab") (width 0.15))
    (fp_line (start -0.5 -1) (end -0.85 -0.5) (layer "F.Fab") (width 0.15))
    (fp_line (start 0.847 0.997) (end -0.85 0.997) (layer "F.Fab") (width 0.15))
    (pad "1" smd rect (at -0.425 -0.975) (size 0.15 0.25) (layers "F.Cu" "F.Paste" "F.Mask")
      (net 132 "VREG_S4A_1V8") (pinfunction "VCCA") (pintype "power_in"))
    (pad "1" smd rect (at -0.653 -0.803 270) (size 0.2 0.6) (layers "F.Cu" "F.Paste" "F.Mask")
      (net 132 "VREG_S4A_1V8") (pinfunction "VCCA") (pintype "power_in"))
    (pad "2" smd rect (at -0.653 -0.403 270) (size 0.2 0.6) (layers "F.Cu" "F.Paste" "F.Mask")
      (net 59 "I2S1_WS") (pinfunction "A1") (pintype "tri_state"))
    (pad "3" smd rect (at -0.653 0 270) (size 0.2 0.6) (layers "F.Cu" "F.Paste" "F.Mask")
      (net 61 "I2S1_SCK") (pinfunction "A2") (pintype "tri_state"))
    (pad "4" smd rect (at -0.653 0.4 270) (size 0.2 0.6) (layers "F.Cu" "F.Paste" "F.Mask")
      (net 60 "I2S1_MCLK") (pinfunction "A3") (pintype "tri_state"))
    (pad "5" smd rect (at -0.653 0.8 270) (size 0.2 0.6) (layers "F.Cu" "F.Paste" "F.Mask")
      (net 62 "I2S1_DATA0") (pinfunction "A4") (pintype "tri_state"))
    (pad "6" smd rect (at 0 0.8 270) (size 0.6 0.2) (layers "F.Cu" "F.Paste" "F.Mask")
      (net 1 "GND") (pinfunction "GND") (pintype "power_in"))
    (pad "7" smd rect (at 0.65 0.8 270) (size 0.2 0.6) (layers "F.Cu" "F.Paste" "F.Mask")
      (net 297 "/HDMI converter/LT9611_I2S_D0_SPDIF") (pinfunction "B4") (pintype "tri_state"))
    (pad "8" smd rect (at 0.65 0.4 270) (size 0.2 0.6) (layers "F.Cu" "F.Paste" "F.Mask")
      (net 300 "/HDMI converter/LT9611_I2S_MCLK") (pinfunction "B3") (pintype "tri_state"))
    (pad "9" smd rect (at 0.65 0 270) (size 0.2 0.6) (layers "F.Cu" "F.Paste" "F.Mask")
      (net 299 "/HDMI converter/LT9611_I2S_SCLK") (pinfunction "B2") (pintype "tri_state"))
    (pad "10" smd rect (at 0.65 -0.403 270) (size 0.2 0.6) (layers "F.Cu" "F.Paste" "F.Mask")
      (net 298 "/HDMI converter/LT9611_I2S_WS") (pinfunction "B1") (pintype "tri_state"))
    (pad "11" smd rect (at 0.65 -0.803 270) (size 0.2 0.6) (layers "F.Cu" "F.Paste" "F.Mask")
      (net 131 "3V3_SYS") (pinfunction "VCCB") (pintype "power_in"))
    (pad "12" smd rect (at 0 -0.803 270) (size 0.6 0.2) (layers "F.Cu" "F.Paste" "F.Mask")
      (net 132 "VREG_S4A_1V8") (pinfunction "OE") (pintype "input"))
  )

  (footprint "sa800u-baseboard-hw-footprints:C_0402_1005Metric" (layer "F.Cu")
    (tedit 616D63CF)
    (at 148.8 125.75)
    (descr "Capacitor SMD 0402")
    (tags "capacitor SMD 0402")
    (property "Author" "Antmicro")
    (property "Dielectric" "")
    (property "License" "Apache-2.0")
    (property "MPN" "MC0402N150J500CT")
    (property "Manufacturer" "Multicomp")
    (property "Sheetfile" "hdmi-converter.kicad_sch")
    (property "Sheetname" "HDMI converter")
    (property "Val" "15p")
    (property "Voltage" "")
    (attr smd)
    (fp_text reference "C19" (at -1.01 -0.59) (layer "F.SilkS")
      (effects (font (size 0.7 0.7) (thickness 0.15)) (justify left bottom))
    )
    (fp_text value "C_15p_0402" (at 0 1.4) (layer "F.Fab")
      (effects (font (size 0.7 0.7) (thickness 0.15)) (justify left bottom))
    )
    (fp_text user "License: Apache-2.0" (at -0.932 5.17) (layer "F.Fab") hide
      (effects (font (size 0.7 0.7) (thickness 0.15)) (justify left bottom))
    )
    (fp_text user "${REFERENCE}" (at -0.932 3.168) (layer "F.Fab") hide
      (effects (font (size 0.7 0.7) (thickness 0.15)) (justify left bottom))
    )
    (fp_text user "Author: Antmicro" (at -0.932 4.17) (layer "F.Fab") hide
      (effects (font (size 0.7 0.7) (thickness 0.15)) (justify left bottom))
    )
    (fp_rect (start -0.94 -0.47) (end 0.94 0.47) (layer "F.CrtYd") (width 0.05) (fill none))
    (fp_rect (start -0.499 -0.249) (end 0.499 0.249) (layer "F.Fab") (width 0.15) (fill none))
    (pad "1" smd roundrect (at -0.484 0) (size 0.59 0.64) (layers "F.Cu" "F.Paste" "F.Mask") (roundrect_rratio 0.25)
      (net 190 "/HDMI converter/XTALO") (pintype "passive"))
    (pad "2" smd roundrect (at 0.484 0) (size 0.59 0.64) (layers "F.Cu" "F.Paste" "F.Mask") (roundrect_rratio 0.25)
      (net 1 "GND") (pintype "passive"))
  )

  (footprint "sa800u-baseboard-hw-footprints:R_0402_1005Metric" (layer "F.Cu")
    (tedit 5FD9C158)
    (at 138.35 136.9 -90)
    (descr "Resistor SMD 0402")
    (tags "resistor SMD 0402")
    (property "Author" "Antmicro")
    (property "License" "Apache-2.0")
    (property "MPN" "CR0402-FX-5100GLF")
    (property "Manufacturer" "Bourns")
    (property "Sheetfile" "hdmi-converter.kicad_sch")
    (property "Sheetname" "HDMI converter")
    (property "Tolerance" "1%")
    (property "Val" "510R")
    (attr smd)
    (fp_text reference "R49" (at -4.62 15.6 -90) (layer "F.SilkS")
      (effects (font (size 0.7 0.7) (thickness 0.15)) (justify left bottom))
    )
    (fp_text value "R_510R_0402" (at 0 1.4 -90) (layer "F.Fab")
      (effects (font (size 0.7 0.7) (thickness 0.15)) (justify left bottom))
    )
    (fp_text user "Author: Antmicro" (at -0.95 4.169 -90) (layer "F.Fab") hide
      (effects (font (size 0.7 0.7) (thickness 0.15)) (justify left bottom))
    )
    (fp_text user "${REFERENCE}" (at -0.95 3.168 -90) (layer "F.Fab") hide
      (effects (font (size 0.7 0.7) (thickness 0.15)) (justify left bottom))
    )
    (fp_text user "License: Apache-2.0" (at -0.95 5.169 -90) (layer "F.Fab") hide
      (effects (font (size 0.7 0.7) (thickness 0.15)) (justify left bottom))
    )
    (fp_rect (start -0.93 -0.47) (end 0.93 0.47) (layer "F.CrtYd") (width 0.05) (fill none))
    (fp_rect (start -0.5 -0.25) (end 0.5 0.25) (layer "F.Fab") (width 0.15) (fill none))
    (pad "1" smd roundrect (at -0.485 0 270) (size 0.59 0.64) (layers "F.Cu" "F.Paste" "F.Mask") (roundrect_rratio 0.25)
      (net 206 "/HDMI converter/HDMI_CLK_P") (pintype "passive"))
    (pad "2" smd roundrect (at 0.485 0 270) (size 0.59 0.64) (layers "F.Cu" "F.Paste" "F.Mask") (roundrect_rratio 0.25)
      (net 209 "/HDMI converter/VCOM") (pintype "passive"))
  )

  (footprint "sa800u-baseboard-hw-footprints:C_0402_1005Metric" (layer "F.Cu")
    (tedit 616D63CF)
    (at 133.7 130.05 180)
    (descr "Capacitor SMD 0402")
    (tags "capacitor SMD 0402")
    (property "Author" "Antmicro")
    (property "Dielectric" "")
    (property "License" "Apache-2.0")
    (property "MPN" "C1005X6S1A105K050BC")
    (property "Manufacturer" "TDK")
    (property "Sheetfile" "hdmi-converter.kicad_sch")
    (property "Sheetname" "HDMI converter")
    (property "Val" "1u")
    (property "Voltage" "")
    (attr smd)
    (fp_text reference "C26" (at -0.92 -0.43 180) (layer "F.SilkS")
      (effects (font (size 0.7 0.7) (thickness 0.15)) (justify left bottom))
    )
    (fp_text value "C_1u_0402" (at 0 1.4 180) (layer "F.Fab")
      (effects (font (size 0.7 0.7) (thickness 0.15)) (justify left bottom))
    )
    (fp_text user "${REFERENCE}" (at -0.932 3.168 180) (layer "F.Fab") hide
      (effects (font (size 0.7 0.7) (thickness 0.15)) (justify left bottom))
    )
    (fp_text user "License: Apache-2.0" (at -0.932 5.17 180) (layer "F.Fab") hide
      (effects (font (size 0.7 0.7) (thickness 0.15)) (justify left bottom))
    )
    (fp_text user "Author: Antmicro" (at -0.932 4.17 180) (layer "F.Fab") hide
      (effects (font (size 0.7 0.7) (thickness 0.15)) (justify left bottom))
    )
    (fp_rect (start -0.94 -0.47) (end 0.94 0.47) (layer "F.CrtYd") (width 0.05) (fill none))
    (fp_rect (start -0.499 -0.249) (end 0.499 0.249) (layer "F.Fab") (width 0.15) (fill none))
    (pad "1" smd roundrect (at -0.484 0 180) (size 0.59 0.64) (layers "F.Cu" "F.Paste" "F.Mask") (roundrect_rratio 0.25)
      (net 184 "/HDMI converter/LT9611_VCC33_IO") (pintype "passive"))
    (pad "2" smd roundrect (at 0.484 0 180) (size 0.59 0.64) (layers "F.Cu" "F.Paste" "F.Mask") (roundrect_rratio 0.25)
      (net 1 "GND") (pintype "passive"))
  )

  (footprint "sa800u-baseboard-hw-footprints:C_0402_1005Metric" (layer "F.Cu")
    (tedit 616D63CF)
    (at 137.75 134.95 -90)
    (descr "Capacitor SMD 0402")
    (tags "capacitor SMD 0402")
    (property "Author" "Antmicro")
    (property "Dielectric" "X5R")
    (property "License" "Apache-2.0")
    (property "MPN" "GRM155R61H104KE14D")
    (property "Manufacturer" "Murata")
    (property "Sheetfile" "hdmi-converter.kicad_sch")
    (property "Sheetname" "HDMI converter")
    (property "Val" "100n")
    (property "Voltage" "50V")
    (attr smd)
    (fp_text reference "C53" (at -4.61 15.55 -90) (layer "F.SilkS")
      (effects (font (size 0.7 0.7) (thickness 0.15)) (justify left bottom))
    )
    (fp_text value "C_100n_0402" (at 0 1.4 -90) (layer "F.Fab")
      (effects (font (size 0.7 0.7) (thickness 0.15)) (justify left bottom))
    )
    (fp_text user "License: Apache-2.0" (at -0.932 5.17 -90) (layer "F.Fab") hide
      (effects (font (size 0.7 0.7) (thickness 0.15)) (justify left bottom))
    )
    (fp_text user "${REFERENCE}" (at -0.932 3.168 -90) (layer "F.Fab") hide
      (effects (font (size 0.7 0.7) (thickness 0.15)) (justify left bottom))
    )
    (fp_text user "Author: Antmicro" (at -0.932 4.17 -90) (layer "F.Fab") hide
      (effects (font (size 0.7 0.7) (thickness 0.15)) (justify left bottom))
    )
    (fp_rect (start -0.94 -0.47) (end 0.94 0.47) (layer "F.CrtYd") (width 0.05) (fill none))
    (fp_rect (start -0.499 -0.249) (end 0.499 0.249) (layer "F.Fab") (width 0.15) (fill none))
    (pad "1" smd roundrect (at -0.484 0 270) (size 0.59 0.64) (layers "F.Cu" "F.Paste" "F.Mask") (roundrect_rratio 0.25)
      (net 205 "/HDMI converter/HDMI_TX_CLK_P") (pintype "passive"))
    (pad "2" smd roundrect (at 0.484 0 270) (size 0.59 0.64) (layers "F.Cu" "F.Paste" "F.Mask") (roundrect_rratio 0.25)
      (net 206 "/HDMI converter/HDMI_CLK_P") (pintype "passive"))
  )

  (footprint "sa800u-baseboard-hw-footprints:C_0402_1005Metric" (layer "F.Cu")
    (tedit 616D63CF)
    (at 140.95 134.95 -90)
    (descr "Capacitor SMD 0402")
    (tags "capacitor SMD 0402")
    (property "Author" "Antmicro")
    (property "Dielectric" "X5R")
    (property "License" "Apache-2.0")
    (property "MPN" "GRM155R61H104KE14D")
    (property "Manufacturer" "Murata")
    (property "Sheetfile" "hdmi-converter.kicad_sch")
    (property "Sheetname" "HDMI converter")
    (property "Val" "100n")
    (property "Voltage" "50V")
    (attr smd)
    (fp_text reference "C52" (at -4.579 15.87 -90) (layer "F.SilkS")
      (effects (font (size 0.7 0.7) (thickness 0.15)) (justify left bottom))
    )
    (fp_text value "C_100n_0402" (at 0 1.4 -90) (layer "F.Fab")
      (effects (font (size 0.7 0.7) (thickness 0.15)) (justify left bottom))
    )
    (fp_text user "${REFERENCE}" (at -0.932 3.168 -90) (layer "F.Fab") hide
      (effects (font (size 0.7 0.7) (thickness 0.15)) (justify left bottom))
    )
    (fp_text user "License: Apache-2.0" (at -0.932 5.17 -90) (layer "F.Fab") hide
      (effects (font (size 0.7 0.7) (thickness 0.15)) (justify left bottom))
    )
    (fp_text user "Author: Antmicro" (at -0.932 4.17 -90) (layer "F.Fab") hide
      (effects (font (size 0.7 0.7) (thickness 0.15)) (justify left bottom))
    )
    (fp_rect (start -0.94 -0.47) (end 0.94 0.47) (layer "F.CrtYd") (width 0.05) (fill none))
    (fp_rect (start -0.499 -0.249) (end 0.499 0.249) (layer "F.Fab") (width 0.15) (fill none))
    (pad "1" smd roundrect (at -0.484 0 270) (size 0.59 0.64) (layers "F.Cu" "F.Paste" "F.Mask") (roundrect_rratio 0.25)
      (net 202 "/HDMI converter/HDMI_TX_D0_P") (pintype "passive"))
    (pad "2" smd roundrect (at 0.484 0 270) (size 0.59 0.64) (layers "F.Cu" "F.Paste" "F.Mask") (roundrect_rratio 0.25)
      (net 201 "/HDMI converter/HDMI_TX0_P") (pintype "passive"))
  )

  (footprint "sa800u-baseboard-hw-footprints:R_0402_1005Metric" (layer "F.Cu")
    (tedit 5FD9C158)
    (at 139.35 136.9 -90)
    (descr "Resistor SMD 0402")
    (tags "resistor SMD 0402")
    (property "Author" "Antmicro")
    (property "License" "Apache-2.0")
    (property "MPN" "CR0402-FX-5100GLF")
    (property "Manufacturer" "Bourns")
    (property "Sheetfile" "hdmi-converter.kicad_sch")
    (property "Sheetname" "HDMI converter")
    (property "Tolerance" "1%")
    (property "Val" "510R")
    (attr smd)
    (fp_text reference "R51" (at -4.62 15.68 -90) (layer "F.SilkS")
      (effects (font (size 0.7 0.7) (thickness 0.15)) (justify left bottom))
    )
    (fp_text value "R_510R_0402" (at 0 1.4 -90) (layer "F.Fab")
      (effects (font (size 0.7 0.7) (thickness 0.15)) (justify left bottom))
    )
    (fp_text user "${REFERENCE}" (at -0.95 3.168 -90) (layer "F.Fab") hide
      (effects (font (size 0.7 0.7) (thickness 0.15)) (justify left bottom))
    )
    (fp_text user "Author: Antmicro" (at -0.95 4.169 -90) (layer "F.Fab") hide
      (effects (font (size 0.7 0.7) (thickness 0.15)) (justify left bottom))
    )
    (fp_text user "License: Apache-2.0" (at -0.95 5.169 -90) (layer "F.Fab") hide
      (effects (font (size 0.7 0.7) (thickness 0.15)) (justify left bottom))
    )
    (fp_rect (start -0.93 -0.47) (end 0.93 0.47) (layer "F.CrtYd") (width 0.05) (fill none))
    (fp_rect (start -0.5 -0.25) (end 0.5 0.25) (layer "F.Fab") (width 0.15) (fill none))
    (pad "1" smd roundrect (at -0.485 0 270) (size 0.59 0.64) (layers "F.Cu" "F.Paste" "F.Mask") (roundrect_rratio 0.25)
      (net 203 "/HDMI converter/HDMI_TX0_N") (pintype "passive"))
    (pad "2" smd roundrect (at 0.485 0 270) (size 0.59 0.64) (layers "F.Cu" "F.Paste" "F.Mask") (roundrect_rratio 0.25)
      (net 209 "/HDMI converter/VCOM") (pintype "passive"))
  )

  (footprint "sa800u-baseboard-hw-footprints:R_0402_1005Metric" (layer "F.Cu")
    (tedit 5FD9C158)
    (at 141.55 136.9 -90)
    (descr "Resistor SMD 0402")
    (tags "resistor SMD 0402")
    (property "Author" "Antmicro")
    (property "License" "Apache-2.0")
    (property "MPN" "CR0402-FX-5100GLF")
    (property "Manufacturer" "Bourns")
    (property "Sheetfile" "hdmi-converter.kicad_sch")
    (property "Sheetname" "HDMI converter")
    (property "Tolerance" "1%")
    (property "Val" "510R")
    (attr smd)
    (fp_text reference "R52" (at -4.57 15.91 -90) (layer "F.SilkS")
      (effects (font (size 0.7 0.7) (thickness 0.15)) (justify left bottom))
    )
    (fp_text value "R_510R_0402" (at 0 1.4 -90) (layer "F.Fab")
      (effects (font (size 0.7 0.7) (thickness 0.15)) (justify left bottom))
    )
    (fp_text user "Author: Antmicro" (at -0.95 4.169 -90) (layer "F.Fab") hide
      (effects (font (size 0.7 0.7) (thickness 0.15)) (justify left bottom))
    )
    (fp_text user "${REFERENCE}" (at -0.95 3.168 -90) (layer "F.Fab") hide
      (effects (font (size 0.7 0.7) (thickness 0.15)) (justify left bottom))
    )
    (fp_text user "License: Apache-2.0" (at -0.95 5.169 -90) (layer "F.Fab") hide
      (effects (font (size 0.7 0.7) (thickness 0.15)) (justify left bottom))
    )
    (fp_rect (start -0.93 -0.47) (end 0.93 0.47) (layer "F.CrtYd") (width 0.05) (fill none))
    (fp_rect (start -0.5 -0.25) (end 0.5 0.25) (layer "F.Fab") (width 0.15) (fill none))
    (pad "1" smd roundrect (at -0.485 0 270) (size 0.59 0.64) (layers "F.Cu" "F.Paste" "F.Mask") (roundrect_rratio 0.25)
      (net 201 "/HDMI converter/HDMI_TX0_P") (pintype "passive"))
    (pad "2" smd roundrect (at 0.485 0 270) (size 0.59 0.64) (layers "F.Cu" "F.Paste" "F.Mask") (roundrect_rratio 0.25)
      (net 209 "/HDMI converter/VCOM") (pintype "passive"))
  )

  (footprint "sa800u-baseboard-hw-footprints:R_0402_1005Metric" (layer "F.Cu")
    (tedit 5FD9C158)
    (at 136.3 133.05 -90)
    (descr "Resistor SMD 0402")
    (tags "resistor SMD 0402")
    (property "Author" "Antmicro")
    (property "License" "Apache-2.0")
    (property "MPN" "CR0402-FX-50R0GLF")
    (property "Manufacturer" "Bourns")
    (property "Sheetfile" "hdmi-converter.kicad_sch")
    (property "Sheetname" "HDMI converter")
    (property "Tolerance" "1%")
    (property "Val" "50R")
    (attr smd)
    (fp_text reference "R35" (at -4.611 15.46 -90) (layer "F.SilkS")
      (effects (font (size 0.7 0.7) (thickness 0.15)) (justify left bottom))
    )
    (fp_text value "R_50R_0402" (at 0 1.4 -90) (layer "F.Fab")
      (effects (font (size 0.7 0.7) (thickness 0.15)) (justify left bottom))
    )
    (fp_text user "License: Apache-2.0" (at -0.95 5.169 -90) (layer "F.Fab") hide
      (effects (font (size 0.7 0.7) (thickness 0.15)) (justify left bottom))
    )
    (fp_text user "${REFERENCE}" (at -0.95 3.168 -90) (layer "F.Fab") hide
      (effects (font (size 0.7 0.7) (thickness 0.15)) (justify left bottom))
    )
    (fp_text user "Author: Antmicro" (at -0.95 4.169 -90) (layer "F.Fab") hide
      (effects (font (size 0.7 0.7) (thickness 0.15)) (justify left bottom))
    )
    (fp_rect (start -0.93 -0.47) (end 0.93 0.47) (layer "F.CrtYd") (width 0.05) (fill none))
    (fp_rect (start -0.5 -0.25) (end 0.5 0.25) (layer "F.Fab") (width 0.15) (fill none))
    (pad "1" smd roundrect (at -0.485 0 270) (size 0.59 0.64) (layers "F.Cu" "F.Paste" "F.Mask") (roundrect_rratio 0.25)
      (net 187 "/HDMI converter/LT9611_VCC33_TX") (pintype "passive"))
    (pad "2" smd roundrect (at 0.485 0 270) (size 0.59 0.64) (layers "F.Cu" "F.Paste" "F.Mask") (roundrect_rratio 0.25)
      (net 207 "/HDMI converter/HDMI_TX_CLK_N") (pintype "passive"))
  )

  (footprint "sa800u-baseboard-hw-footprints:R_0402_1005Metric" (layer "F.Cu")
    (tedit 5FD9C158)
    (at 142.55 136.9 -90)
    (descr "Resistor SMD 0402")
    (tags "resistor SMD 0402")
    (property "Author" "Antmicro")
    (property "License" "Apache-2.0")
    (property "MPN" "CR0402-FX-5100GLF")
    (property "Manufacturer" "Bourns")
    (property "Sheetfile" "hdmi-converter.kicad_sch")
    (property "Sheetname" "HDMI converter")
    (property "Tolerance" "1%")
    (property "Val" "510R")
    (attr smd)
    (fp_text reference "R53" (at -4.58 15.99 -90) (layer "F.SilkS")
      (effects (font (size 0.7 0.7) (thickness 0.15)) (justify left bottom))
    )
    (fp_text value "R_510R_0402" (at 0 1.4 -90) (layer "F.Fab")
      (effects (font (size 0.7 0.7) (thickness 0.15)) (justify left bottom))
    )
    (fp_text user "${REFERENCE}" (at -0.95 3.168 -90) (layer "F.Fab") hide
      (effects (font (size 0.7 0.7) (thickness 0.15)) (justify left bottom))
    )
    (fp_text user "License: Apache-2.0" (at -0.95 5.169 -90) (layer "F.Fab") hide
      (effects (font (size 0.7 0.7) (thickness 0.15)) (justify left bottom))
    )
    (fp_text user "Author: Antmicro" (at -0.95 4.169 -90) (layer "F.Fab") hide
      (effects (font (size 0.7 0.7) (thickness 0.15)) (justify left bottom))
    )
    (fp_rect (start -0.93 -0.47) (end 0.93 0.47) (layer "F.CrtYd") (width 0.05) (fill none))
    (fp_rect (start -0.5 -0.25) (end 0.5 0.25) (layer "F.Fab") (width 0.15) (fill none))
    (pad "1" smd roundrect (at -0.485 0 270) (size 0.59 0.64) (layers "F.Cu" "F.Paste" "F.Mask") (roundrect_rratio 0.25)
      (net 200 "/HDMI converter/HDMI_TX1_N") (pintype "passive"))
    (pad "2" smd roundrect (at 0.485 0 270) (size 0.59 0.64) (layers "F.Cu" "F.Paste" "F.Mask") (roundrect_rratio 0.25)
      (net 209 "/HDMI converter/VCOM") (pintype "passive"))
  )

  (footprint "sa800u-baseboard-hw-footprints:C_0402_1005Metric" (layer "F.Cu")
    (tedit 616D63CF)
    (at 148.815 123.7)
    (descr "Capacitor SMD 0402")
    (tags "capacitor SMD 0402")
    (property "Author" "Antmicro")
    (property "Dielectric" "X5R")
    (property "License" "Apache-2.0")
    (property "MPN" "GRM155R61H104KE14D")
    (property "Manufacturer" "Murata")
    (property "Sheetfile" "hdmi-converter.kicad_sch")
    (property "Sheetname" "HDMI converter")
    (property "Val" "100n")
    (property "Voltage" "50V")
    (attr smd)
    (fp_text reference "C30" (at -1.035 -0.59) (layer "F.SilkS")
      (effects (font (size 0.7 0.7) (thickness 0.15)) (justify left bottom))
    )
    (fp_text value "C_100n_0402" (at 0 1.4) (layer "F.Fab")
      (effects (font (size 0.7 0.7) (thickness 0.15)) (justify left bottom))
    )
    (fp_text user "Author: Antmicro" (at -0.932 4.17) (layer "F.Fab") hide
      (effects (font (size 0.7 0.7) (thickness 0.15)) (justify left bottom))
    )
    (fp_text user "${REFERENCE}" (at -0.932 3.168) (layer "F.Fab") hide
      (effects (font (size 0.7 0.7) (thickness 0.15)) (justify left bottom))
    )
    (fp_text user "License: Apache-2.0" (at -0.932 5.17) (layer "F.Fab") hide
      (effects (font (size 0.7 0.7) (thickness 0.15)) (justify left bottom))
    )
    (fp_rect (start -0.94 -0.47) (end 0.94 0.47) (layer "F.CrtYd") (width 0.05) (fill none))
    (fp_rect (start -0.499 -0.249) (end 0.499 0.249) (layer "F.Fab") (width 0.15) (fill none))
    (pad "1" smd roundrect (at -0.484 0) (size 0.59 0.64) (layers "F.Cu" "F.Paste" "F.Mask") (roundrect_rratio 0.25)
      (net 189 "/HDMI converter/LT9611_VCC12_RX") (pintype "passive"))
    (pad "2" smd roundrect (at 0.484 0) (size 0.59 0.64) (layers "F.Cu" "F.Paste" "F.Mask") (roundrect_rratio 0.25)
      (net 1 "GND") (pintype "passive"))
  )

  (footprint "sa800u-baseboard-hw-footprints:C_0402_1005Metric" (layer "F.Cu")
    (tedit 616D63CF)
    (at 143.15 134.95 -90)
    (descr "Capacitor SMD 0402")
    (tags "capacitor SMD 0402")
    (property "Author" "Antmicro")
    (property "Dielectric" "X5R")
    (property "License" "Apache-2.0")
    (property "MPN" "GRM155R61H104KE14D")
    (property "Manufacturer" "Murata")
    (property "Sheetfile" "hdmi-converter.kicad_sch")
    (property "Sheetname" "HDMI converter")
    (property "Val" "100n")
    (property "Voltage" "50V")
    (attr smd)
    (fp_text reference "C47" (at -4.579 15.99 -90) (layer "F.SilkS")
      (effects (font (size 0.7 0.7) (thickness 0.15)) (justify left bottom))
    )
    (fp_text value "C_100n_0402" (at 0 1.4 -90) (layer "F.Fab")
      (effects (font (size 0.7 0.7) (thickness 0.15)) (justify left bottom))
    )
    (fp_text user "License: Apache-2.0" (at -0.932 5.17 -90) (layer "F.Fab") hide
      (effects (font (size 0.7 0.7) (thickness 0.15)) (justify left bottom))
    )
    (fp_text user "${REFERENCE}" (at -0.932 3.168 -90) (layer "F.Fab") hide
      (effects (font (size 0.7 0.7) (thickness 0.15)) (justify left bottom))
    )
    (fp_text user "Author: Antmicro" (at -0.932 4.17 -90) (layer "F.Fab") hide
      (effects (font (size 0.7 0.7) (thickness 0.15)) (justify left bottom))
    )
    (fp_rect (start -0.94 -0.47) (end 0.94 0.47) (layer "F.CrtYd") (width 0.05) (fill none))
    (fp_rect (start -0.499 -0.249) (end 0.499 0.249) (layer "F.Fab") (width 0.15) (fill none))
    (pad "1" smd roundrect (at -0.484 0 270) (size 0.59 0.64) (layers "F.Cu" "F.Paste" "F.Mask") (roundrect_rratio 0.25)
      (net 199 "/HDMI converter/HDMI_TX_D1_N") (pintype "passive"))
    (pad "2" smd roundrect (at 0.484 0 270) (size 0.59 0.64) (layers "F.Cu" "F.Paste" "F.Mask") (roundrect_rratio 0.25)
      (net 200 "/HDMI converter/HDMI_TX1_N") (pintype "passive"))
  )

  (footprint "sa800u-baseboard-hw-footprints:R_0402_1005Metric" (layer "F.Cu")
    (tedit 5FD9C158)
    (at 144.75 136.9 -90)
    (descr "Resistor SMD 0402")
    (tags "resistor SMD 0402")
    (property "Author" "Antmicro")
    (property "License" "Apache-2.0")
    (property "MPN" "CR0402-FX-5100GLF")
    (property "Manufacturer" "Bourns")
    (property "Sheetfile" "hdmi-converter.kicad_sch")
    (property "Sheetname" "HDMI converter")
    (property "Tolerance" "1%")
    (property "Val" "510R")
    (attr smd)
    (fp_text reference "R54" (at -4.61 16.37 -90) (layer "F.SilkS")
      (effects (font (size 0.7 0.7) (thickness 0.15)) (justify left bottom))
    )
    (fp_text value "R_510R_0402" (at 0 1.4 -90) (layer "F.Fab")
      (effects (font (size 0.7 0.7) (thickness 0.15)) (justify left bottom))
    )
    (fp_text user "License: Apache-2.0" (at -0.95 5.169 -90) (layer "F.Fab") hide
      (effects (font (size 0.7 0.7) (thickness 0.15)) (justify left bottom))
    )
    (fp_text user "Author: Antmicro" (at -0.95 4.169 -90) (layer "F.Fab") hide
      (effects (font (size 0.7 0.7) (thickness 0.15)) (justify left bottom))
    )
    (fp_text user "${REFERENCE}" (at -0.95 3.168 -90) (layer "F.Fab") hide
      (effects (font (size 0.7 0.7) (thickness 0.15)) (justify left bottom))
    )
    (fp_rect (start -0.93 -0.47) (end 0.93 0.47) (layer "F.CrtYd") (width 0.05) (fill none))
    (fp_rect (start -0.5 -0.25) (end 0.5 0.25) (layer "F.Fab") (width 0.15) (fill none))
    (pad "1" smd roundrect (at -0.485 0 270) (size 0.59 0.64) (layers "F.Cu" "F.Paste" "F.Mask") (roundrect_rratio 0.25)
      (net 198 "/HDMI converter/HDMI_TX1_P") (pintype "passive"))
    (pad "2" smd roundrect (at 0.485 0 270) (size 0.59 0.64) (layers "F.Cu" "F.Paste" "F.Mask") (roundrect_rratio 0.25)
      (net 209 "/HDMI converter/VCOM") (pintype "passive"))
  )

  (footprint "sa800u-baseboard-hw-footprints:R_0402_1005Metric" (layer "F.Cu")
    (tedit 5FD9C158)
    (at 136.15 136.9 -90)
    (descr "Resistor SMD 0402")
    (tags "resistor SMD 0402")
    (property "Author" "Antmicro")
    (property "License" "Apache-2.0")
    (property "MPN" "CR0402-FX-5100GLF")
    (property "Manufacturer" "Bourns")
    (property "Sheetfile" "hdmi-converter.kicad_sch")
    (property "Sheetname" "HDMI converter")
    (property "Tolerance" "1%")
    (property "Val" "510R")
    (attr smd)
    (fp_text reference "R48" (at -4.64 15.39 -90) (layer "F.SilkS")
      (effects (font (size 0.7 0.7) (thickness 0.15)) (justify left bottom))
    )
    (fp_text value "R_510R_0402" (at 0 1.4 -90) (layer "F.Fab")
      (effects (font (size 0.7 0.7) (thickness 0.15)) (justify left bottom))
    )
    (fp_text user "License: Apache-2.0" (at -0.95 5.169 -90) (layer "F.Fab") hide
      (effects (font (size 0.7 0.7) (thickness 0.15)) (justify left bottom))
    )
    (fp_text user "Author: Antmicro" (at -0.95 4.169 -90) (layer "F.Fab") hide
      (effects (font (size 0.7 0.7) (thickness 0.15)) (justify left bottom))
    )
    (fp_text user "${REFERENCE}" (at -0.95 3.168 -90) (layer "F.Fab") hide
      (effects (font (size 0.7 0.7) (thickness 0.15)) (justify left bottom))
    )
    (fp_rect (start -0.93 -0.47) (end 0.93 0.47) (layer "F.CrtYd") (width 0.05) (fill none))
    (fp_rect (start -0.5 -0.25) (end 0.5 0.25) (layer "F.Fab") (width 0.15) (fill none))
    (pad "1" smd roundrect (at -0.485 0 270) (size 0.59 0.64) (layers "F.Cu" "F.Paste" "F.Mask") (roundrect_rratio 0.25)
      (net 208 "/HDMI converter/HDMI_CLK_N") (pintype "passive"))
    (pad "2" smd roundrect (at 0.485 0 270) (size 0.59 0.64) (layers "F.Cu" "F.Paste" "F.Mask") (roundrect_rratio 0.25)
      (net 209 "/HDMI converter/VCOM") (pintype "passive"))
  )

  (footprint "sa800u-baseboard-hw-footprints:C_0402_1005Metric" (layer "F.Cu")
    (tedit 616D63CF)
    (at 139.95 134.95 -90)
    (descr "Capacitor SMD 0402")
    (tags "capacitor SMD 0402")
    (property "Author" "Antmicro")
    (property "Dielectric" "X5R")
    (property "License" "Apache-2.0")
    (property "MPN" "GRM155R61H104KE14D")
    (property "Manufacturer" "Murata")
    (property "Sheetfile" "hdmi-converter.kicad_sch")
    (property "Sheetname" "HDMI converter")
    (property "Val" "100n")
    (property "Voltage" "50V")
    (attr smd)
    (fp_text reference "C48" (at -4.63 15.86 -90) (layer "F.SilkS")
      (effects (font (size 0.7 0.7) (thickness 0.15)) (justify left bottom))
    )
    (fp_text value "C_100n_0402" (at 0 1.4 -90) (layer "F.Fab")
      (effects (font (size 0.7 0.7) (thickness 0.15)) (justify left bottom))
    )
    (fp_text user "${REFERENCE}" (at -0.932 3.168 -90) (layer "F.Fab") hide
      (effects (font (size 0.7 0.7) (thickness 0.15)) (justify left bottom))
    )
    (fp_text user "License: Apache-2.0" (at -0.932 5.17 -90) (layer "F.Fab") hide
      (effects (font (size 0.7 0.7) (thickness 0.15)) (justify left bottom))
    )
    (fp_text user "Author: Antmicro" (at -0.932 4.17 -90) (layer "F.Fab") hide
      (effects (font (size 0.7 0.7) (thickness 0.15)) (justify left bottom))
    )
    (fp_rect (start -0.94 -0.47) (end 0.94 0.47) (layer "F.CrtYd") (width 0.05) (fill none))
    (fp_rect (start -0.499 -0.249) (end 0.499 0.249) (layer "F.Fab") (width 0.15) (fill none))
    (pad "1" smd roundrect (at -0.484 0 270) (size 0.59 0.64) (layers "F.Cu" "F.Paste" "F.Mask") (roundrect_rratio 0.25)
      (net 204 "/HDMI converter/HDMI_TX_D0_N") (pintype "passive"))
    (pad "2" smd roundrect (at 0.484 0 270) (size 0.59 0.64) (layers "F.Cu" "F.Paste" "F.Mask") (roundrect_rratio 0.25)
      (net 203 "/HDMI converter/HDMI_TX0_N") (pintype "passive"))
  )

  (footprint "sa800u-baseboard-hw-footprints:C_0402_1005Metric" (layer "F.Cu")
    (tedit 616D63CF)
    (at 148.2 130.9 180)
    (descr "Capacitor SMD 0402")
    (tags "capacitor SMD 0402")
    (property "Author" "Antmicro")
    (property "Dielectric" "")
    (property "License" "Apache-2.0")
    (property "MPN" "MC0402N150J500CT")
    (property "Manufacturer" "Multicomp")
    (property "Sheetfile" "hdmi-converter.kicad_sch")
    (property "Sheetname" "HDMI converter")
    (property "Val" "15p")
    (property "Voltage" "")
    (attr smd)
    (fp_text reference "C21" (at -0.89 -0.39 180) (layer "F.SilkS")
      (effects (font (size 0.7 0.7) (thickness 0.15)) (justify left bottom))
    )
    (fp_text value "C_15p_0402" (at 0 1.4 180) (layer "F.Fab")
      (effects (font (size 0.7 0.7) (thickness 0.15)) (justify left bottom))
    )
    (fp_text user "License: Apache-2.0" (at -0.932 5.17 180) (layer "F.Fab") hide
      (effects (font (size 0.7 0.7) (thickness 0.15)) (justify left bottom))
    )
    (fp_text user "Author: Antmicro" (at -0.932 4.17 180) (layer "F.Fab") hide
      (effects (font (size 0.7 0.7) (thickness 0.15)) (justify left bottom))
    )
    (fp_text user "${REFERENCE}" (at -0.932 3.168 180) (layer "F.Fab") hide
      (effects (font (size 0.7 0.7) (thickness 0.15)) (justify left bottom))
    )
    (fp_rect (start -0.94 -0.47) (end 0.94 0.47) (layer "F.CrtYd") (width 0.05) (fill none))
    (fp_rect (start -0.499 -0.249) (end 0.499 0.249) (layer "F.Fab") (width 0.15) (fill none))
    (pad "1" smd roundrect (at -0.484 0 180) (size 0.59 0.64) (layers "F.Cu" "F.Paste" "F.Mask") (roundrect_rratio 0.25)
      (net 192 "/HDMI converter/XTALI") (pintype "passive"))
    (pad "2" smd roundrect (at 0.484 0 180) (size 0.59 0.64) (layers "F.Cu" "F.Paste" "F.Mask") (roundrect_rratio 0.25)
      (net 1 "GND") (pintype "passive"))
  )

  (footprint "sa800u-baseboard-hw-footprints:C_0402_1005Metric" (layer "F.Cu")
    (tedit 616D63CF)
    (at 144.15 134.95 -90)
    (descr "Capacitor SMD 0402")
    (tags "capacitor SMD 0402")
    (property "Author" "Antmicro")
    (property "Dielectric" "X5R")
    (property "License" "Apache-2.0")
    (property "MPN" "GRM155R61H104KE14D")
    (property "Manufacturer" "Murata")
    (property "Sheetfile" "hdmi-converter.kicad_sch")
    (property "Sheetname" "HDMI converter")
    (property "Val" "100n")
    (property "Voltage" "50V")
    (attr smd)
    (fp_text reference "C51" (at -4.579 16.09 -90) (layer "F.SilkS")
      (effects (font (size 0.7 0.7) (thickness 0.15)) (justify left bottom))
    )
    (fp_text value "C_100n_0402" (at 0 1.4 -90) (layer "F.Fab")
      (effects (font (size 0.7 0.7) (thickness 0.15)) (justify left bottom))
    )
    (fp_text user "License: Apache-2.0" (at -0.932 5.17 -90) (layer "F.Fab") hide
      (effects (font (size 0.7 0.7) (thickness 0.15)) (justify left bottom))
    )
    (fp_text user "Author: Antmicro" (at -0.932 4.17 -90) (layer "F.Fab") hide
      (effects (font (size 0.7 0.7) (thickness 0.15)) (justify left bottom))
    )
    (fp_text user "${REFERENCE}" (at -0.932 3.168 -90) (layer "F.Fab") hide
      (effects (font (size 0.7 0.7) (thickness 0.15)) (justify left bottom))
    )
    (fp_rect (start -0.94 -0.47) (end 0.94 0.47) (layer "F.CrtYd") (width 0.05) (fill none))
    (fp_rect (start -0.499 -0.249) (end 0.499 0.249) (layer "F.Fab") (width 0.15) (fill none))
    (pad "1" smd roundrect (at -0.484 0 270) (size 0.59 0.64) (layers "F.Cu" "F.Paste" "F.Mask") (roundrect_rratio 0.25)
      (net 197 "/HDMI converter/HDMI_TX_D1_P") (pintype "passive"))
    (pad "2" smd roundrect (at 0.484 0 270) (size 0.59 0.64) (layers "F.Cu" "F.Paste" "F.Mask") (roundrect_rratio 0.25)
      (net 198 "/HDMI converter/HDMI_TX1_P") (pintype "passive"))
  )

  (footprint "sa800u-baseboard-hw-footprints:L_0603_1608Metric" (layer "F.Cu")
    (tedit 5D5D3F54)
    (at 133.1 131.375)
    (property "Author" "Antmicro")
    (property "IMax" "")
    (property "ISat" "")
    (property "License" "Apache-2.0")
    (property "MPN" "BRC1608TR35M")
    (property "Manufacturer" "Taiyo Yuden")
    (property "Sheetfile" "hdmi-converter.kicad_sch")
    (property "Sheetname" "HDMI converter")
    (property "Size" "")
    (property "Val" "350n/1.4A")
    (attr smd)
    (fp_text reference "L1" (at 0.92 0.395) (layer "F.SilkS")
      (effects (font (size 0.7 0.7) (thickness 0.15)) (justify left bottom))
    )
    (fp_text value "L_350n_1.4A_0603" (at 0 2) (layer "F.Fab")
      (effects (font (size 0.7 0.7) (thickness 0.15)) (justify left bottom))
    )
    (fp_text user "Author: Antmicro" (at -1.9 4.4) (layer "F.Fab") hide
      (effects (font (size 0.7 0.7) (thickness 0.15)) (justify left bottom))
    )
    (fp_text user "License: Apache-2.0" (at -1.9 5.75) (layer "F.Fab") hide
      (effects (font (size 0.7 0.7) (thickness 0.15)) (justify left bottom))
    )
    (fp_text user "${REFERENCE}" (at -1.9 3.1) (layer "F.Fab") hide
      (effects (font (size 0.7 0.7) (thickness 0.15)) (justify left bottom))
    )
    (fp_line (start -0.25 -0.45) (end 0.25 -0.45) (layer "F.SilkS") (width 0.1))
    (fp_line (start -0.25 0.45) (end 0.25 0.45) (layer "F.SilkS") (width 0.1))
    (fp_rect (start -1.15 -0.75) (end 1.15 0.75) (layer "F.CrtYd") (width 0.05) (fill none))
    (fp_rect (start -0.8 -0.4) (end 0.8 0.4) (layer "F.Fab") (width 0.1) (fill none))
    (pad "1" smd roundrect (at -0.625 0) (size 0.55 1) (layers "F.Cu" "F.Paste" "F.Mask") (roundrect_rratio 0.15)
      (net 131 "3V3_SYS") (pintype "passive"))
    (pad "2" smd roundrect (at 0.625 0) (size 0.55 1) (layers "F.Cu" "F.Paste" "F.Mask") (roundrect_rratio 0.15)
      (net 184 "/HDMI converter/LT9611_VCC33_IO") (pintype "passive"))
  )

  (footprint "sa800u-baseboard-hw-footprints:L_0603_1608Metric" (layer "F.Cu")
    (tedit 5D5D3F54)
    (at 146.8 121 180)
    (property "Author" "Antmicro")
    (property "IMax" "")
    (property "ISat" "")
    (property "License" "Apache-2.0")
    (property "MPN" "BRC1608TR35M")
    (property "Manufacturer" "Taiyo Yuden")
    (property "Sheetfile" "hdmi-converter.kicad_sch")
    (property "Sheetname" "HDMI converter")
    (property "Size" "")
    (property "Val" "350n/1.4A")
    (attr smd)
    (fp_text reference "L2" (at -1.1 -0.47 180) (layer "F.SilkS")
      (effects (font (size 0.7 0.7) (thickness 0.15)) (justify left bottom))
    )
    (fp_text value "L_350n_1.4A_0603" (at 0 2 180) (layer "F.Fab")
      (effects (font (size 0.7 0.7) (thickness 0.15)) (justify left bottom))
    )
    (fp_text user "License: Apache-2.0" (at -1.9 5.75 180) (layer "F.Fab") hide
      (effects (font (size 0.7 0.7) (thickness 0.15)) (justify left bottom))
    )
    (fp_text user "${REFERENCE}" (at -1.9 3.1 180) (layer "F.Fab") hide
      (effects (font (size 0.7 0.7) (thickness 0.15)) (justify left bottom))
    )
    (fp_text user "Author: Antmicro" (at -1.9 4.4 180) (layer "F.Fab") hide
      (effects (font (size 0.7 0.7) (thickness 0.15)) (justify left bottom))
    )
    (fp_line (start -0.25 -0.45) (end 0.25 -0.45) (layer "F.SilkS") (width 0.1))
    (fp_line (start -0.25 0.45) (end 0.25 0.45) (layer "F.SilkS") (width 0.1))
    (fp_rect (start -1.15 -0.75) (end 1.15 0.75) (layer "F.CrtYd") (width 0.05) (fill none))
    (fp_rect (start -0.8 -0.4) (end 0.8 0.4) (layer "F.Fab") (width 0.1) (fill none))
    (pad "1" smd roundrect (at -0.625 0 180) (size 0.55 1) (layers "F.Cu" "F.Paste" "F.Mask") (roundrect_rratio 0.15)
      (net 131 "3V3_SYS") (pintype "passive"))
    (pad "2" smd roundrect (at 0.625 0 180) (size 0.55 1) (layers "F.Cu" "F.Paste" "F.Mask") (roundrect_rratio 0.15)
      (net 185 "/HDMI converter/LT9611_VCC33_RX") (pintype "passive"))
  )

  (footprint "sa800u-baseboard-hw-footprints:L_0603_1608Metric" (layer "F.Cu")
    (tedit 5D5D3F54)
    (at 146.8 119.4 180)
    (property "Author" "Antmicro")
    (property "IMax" "")
    (property "ISat" "")
    (property "License" "Apache-2.0")
    (property "MPN" "BRC1608TR35M")
    (property "Manufacturer" "Taiyo Yuden")
    (property "Sheetfile" "hdmi-converter.kicad_sch")
    (property "Sheetname" "HDMI converter")
    (property "Size" "")
    (property "Val" "350n/1.4A")
    (attr smd)
    (fp_text reference "L5" (at -1.1 -0.47 180) (layer "F.SilkS")
      (effects (font (size 0.7 0.7) (thickness 0.15)) (justify left bottom))
    )
    (fp_text value "L_350n_1.4A_0603" (at 0 2 180) (layer "F.Fab")
      (effects (font (size 0.7 0.7) (thickness 0.15)) (justify left bottom))
    )
    (fp_text user "License: Apache-2.0" (at -1.9 5.75 180) (layer "F.Fab") hide
      (effects (font (size 0.7 0.7) (thickness 0.15)) (justify left bottom))
    )
    (fp_text user "${REFERENCE}" (at -1.9 3.1 180) (layer "F.Fab") hide
      (effects (font (size 0.7 0.7) (thickness 0.15)) (justify left bottom))
    )
    (fp_text user "Author: Antmicro" (at -1.9 4.4 180) (layer "F.Fab") hide
      (effects (font (size 0.7 0.7) (thickness 0.15)) (justify left bottom))
    )
    (fp_line (start -0.25 -0.45) (end 0.25 -0.45) (layer "F.SilkS") (width 0.1))
    (fp_line (start -0.25 0.45) (end 0.25 0.45) (layer "F.SilkS") (width 0.1))
    (fp_rect (start -1.15 -0.75) (end 1.15 0.75) (layer "F.CrtYd") (width 0.05) (fill none))
    (fp_rect (start -0.8 -0.4) (end 0.8 0.4) (layer "F.Fab") (width 0.1) (fill none))
    (pad "1" smd roundrect (at -0.625 0 180) (size 0.55 1) (layers "F.Cu" "F.Paste" "F.Mask") (roundrect_rratio 0.15)
      (net 138 "1V2_SYS") (pintype "passive"))
    (pad "2" smd roundrect (at 0.625 0 180) (size 0.55 1) (layers "F.Cu" "F.Paste" "F.Mask") (roundrect_rratio 0.15)
      (net 189 "/HDMI converter/LT9611_VCC12_RX") (pintype "passive"))
  )

  (footprint "sa800u-baseboard-hw-footprints:R_0402_1005Metric" (layer "F.Cu")
    (tedit 5FD9C158)
    (at 144.6 133.05 -90)
    (descr "Resistor SMD 0402")
    (tags "resistor SMD 0402")
    (property "Author" "Antmicro")
    (property "License" "Apache-2.0")
    (property "MPN" "CR0402-FX-50R0GLF")
    (property "Manufacturer" "Bourns")
    (property "Sheetfile" "hdmi-converter.kicad_sch")
    (property "Sheetname" "HDMI converter")
    (property "Tolerance" "1%")
    (property "Val" "50R")
    (attr smd)
    (fp_text reference "R42" (at -4.58 16.09 -90) (layer "F.SilkS")
      (effects (font (size 0.7 0.7) (thickness 0.15)) (justify left bottom))
    )
    (fp_text value "R_50R_0402" (at 0 1.4 -90) (layer "F.Fab")
      (effects (font (size 0.7 0.7) (thickness 0.15)) (justify left bottom))
    )
    (fp_text user "Author: Antmicro" (at -0.95 4.169 -90) (layer "F.Fab") hide
      (effects (font (size 0.7 0.7) (thickness 0.15)) (justify left bottom))
    )
    (fp_text user "License: Apache-2.0" (at -0.95 5.169 -90) (layer "F.Fab") hide
      (effects (font (size 0.7 0.7) (thickness 0.15)) (justify left bottom))
    )
    (fp_text user "${REFERENCE}" (at -0.95 3.168 -90) (layer "F.Fab") hide
      (effects (font (size 0.7 0.7) (thickness 0.15)) (justify left bottom))
    )
    (fp_rect (start -0.93 -0.47) (end 0.93 0.47) (layer "F.CrtYd") (width 0.05) (fill none))
    (fp_rect (start -0.5 -0.25) (end 0.5 0.25) (layer "F.Fab") (width 0.15) (fill none))
    (pad "1" smd roundrect (at -0.485 0 270) (size 0.59 0.64) (layers "F.Cu" "F.Paste" "F.Mask") (roundrect_rratio 0.25)
      (net 187 "/HDMI converter/LT9611_VCC33_TX") (pintype "passive"))
    (pad "2" smd roundrect (at 0.485 0 270) (size 0.59 0.64) (layers "F.Cu" "F.Paste" "F.Mask") (roundrect_rratio 0.25)
      (net 197 "/HDMI converter/HDMI_TX_D1_P") (pintype "passive"))
  )

  (footprint "sa800u-baseboard-hw-footprints:R_0402_1005Metric" (layer "F.Cu")
    (tedit 5FD9C158)
    (at 141.4 133.05 -90)
    (descr "Resistor SMD 0402")
    (tags "resistor SMD 0402")
    (property "Author" "Antmicro")
    (property "License" "Apache-2.0")
    (property "MPN" "CR0402-FX-50R0GLF")
    (property "Manufacturer" "Bourns")
    (property "Sheetfile" "hdmi-converter.kicad_sch")
    (property "Sheetname" "HDMI converter")
    (property "Tolerance" "1%")
    (property "Val" "50R")
    (attr smd)
    (fp_text reference "R39" (at -4.66 15.86 -90) (layer "F.SilkS")
      (effects (font (size 0.7 0.7) (thickness 0.15)) (justify left bottom))
    )
    (fp_text value "R_50R_0402" (at 0 1.4 -90) (layer "F.Fab")
      (effects (font (size 0.7 0.7) (thickness 0.15)) (justify left bottom))
    )
    (fp_text user "License: Apache-2.0" (at -0.95 5.169 -90) (layer "F.Fab") hide
      (effects (font (size 0.7 0.7) (thickness 0.15)) (justify left bottom))
    )
    (fp_text user "${REFERENCE}" (at -0.95 3.168 -90) (layer "F.Fab") hide
      (effects (font (size 0.7 0.7) (thickness 0.15)) (justify left bottom))
    )
    (fp_text user "Author: Antmicro" (at -0.95 4.169 -90) (layer "F.Fab") hide
      (effects (font (size 0.7 0.7) (thickness 0.15)) (justify left bottom))
    )
    (fp_rect (start -0.93 -0.47) (end 0.93 0.47) (layer "F.CrtYd") (width 0.05) (fill none))
    (fp_rect (start -0.5 -0.25) (end 0.5 0.25) (layer "F.Fab") (width 0.15) (fill none))
    (pad "1" smd roundrect (at -0.485 0 270) (size 0.59 0.64) (layers "F.Cu" "F.Paste" "F.Mask") (roundrect_rratio 0.25)
      (net 187 "/HDMI converter/LT9611_VCC33_TX") (pintype "passive"))
    (pad "2" smd roundrect (at 0.485 0 270) (size 0.59 0.64) (layers "F.Cu" "F.Paste" "F.Mask") (roundrect_rratio 0.25)
      (net 202 "/HDMI converter/HDMI_TX_D0_P") (pintype "passive"))
  )

  (footprint "sa800u-baseboard-hw-footprints:R_0402_1005Metric" (layer "F.Cu")
    (tedit 5FD9C158)
    (at 139.5 133.05 -90)
    (descr "Resistor SMD 0402")
    (tags "resistor SMD 0402")
    (property "Author" "Antmicro")
    (property "License" "Apache-2.0")
    (property "MPN" "CR0402-FX-50R0GLF")
    (property "Manufacturer" "Bourns")
    (property "Sheetfile" "hdmi-converter.kicad_sch")
    (property "Sheetname" "HDMI converter")
    (property "Tolerance" "1%")
    (property "Val" "50R")
    (attr smd)
    (fp_text reference "R38" (at -4.631 15.86 -90) (layer "F.SilkS")
      (effects (font (size 0.7 0.7) (thickness 0.15)) (justify left bottom))
    )
    (fp_text value "R_50R_0402" (at 0 1.4 -90) (layer "F.Fab")
      (effects (font (size 0.7 0.7) (thickness 0.15)) (justify left bottom))
    )
    (fp_text user "${REFERENCE}" (at -0.95 3.168 -90) (layer "F.Fab") hide
      (effects (font (size 0.7 0.7) (thickness 0.15)) (justify left bottom))
    )
    (fp_text user "Author: Antmicro" (at -0.95 4.169 -90) (layer "F.Fab") hide
      (effects (font (size 0.7 0.7) (thickness 0.15)) (justify left bottom))
    )
    (fp_text user "License: Apache-2.0" (at -0.95 5.169 -90) (layer "F.Fab") hide
      (effects (font (size 0.7 0.7) (thickness 0.15)) (justify left bottom))
    )
    (fp_rect (start -0.93 -0.47) (end 0.93 0.47) (layer "F.CrtYd") (width 0.05) (fill none))
    (fp_rect (start -0.5 -0.25) (end 0.5 0.25) (layer "F.Fab") (width 0.15) (fill none))
    (pad "1" smd roundrect (at -0.485 0 270) (size 0.59 0.64) (layers "F.Cu" "F.Paste" "F.Mask") (roundrect_rratio 0.25)
      (net 187 "/HDMI converter/LT9611_VCC33_TX") (pintype "passive"))
    (pad "2" smd roundrect (at 0.485 0 270) (size 0.59 0.64) (layers "F.Cu" "F.Paste" "F.Mask") (roundrect_rratio 0.25)
      (net 204 "/HDMI converter/HDMI_TX_D0_N") (pintype "passive"))
  )

  (footprint "sa800u-baseboard-hw-footprints:C_0402_1005Metric" (layer "F.Cu")
    (tedit 616D63CF)
    (at 132.888164 125.012952 90)
    (descr "Capacitor SMD 0402")
    (tags "capacitor SMD 0402")
    (property "Author" "Antmicro")
    (property "Dielectric" "X5R")
    (property "License" "Apache-2.0")
    (property "MPN" "GRM155R61H104KE14D")
    (property "Manufacturer" "Murata")
    (property "Sheetfile" "hdmi-converter.kicad_sch")
    (property "Sheetname" "HDMI converter")
    (property "Val" "100n")
    (property "Voltage" "50V")
    (attr smd)
    (fp_text reference "C18" (at -1.107048 -2.498164 90) (layer "F.SilkS")
      (effects (font (size 0.7 0.7) (thickness 0.15)) (justify left bottom))
    )
    (fp_text value "C_100n_0402" (at 0 1.4 90) (layer "F.Fab")
      (effects (font (size 0.7 0.7) (thickness 0.15)) (justify left bottom))
    )
    (fp_text user "License: Apache-2.0" (at -0.932 5.17 90) (layer "F.Fab") hide
      (effects (font (size 0.7 0.7) (thickness 0.15)) (justify left bottom))
    )
    (fp_text user "Author: Antmicro" (at -0.932 4.17 90) (layer "F.Fab") hide
      (effects (font (size 0.7 0.7) (thickness 0.15)) (justify left bottom))
    )
    (fp_text user "${REFERENCE}" (at -0.932 3.168 90) (layer "F.Fab") hide
      (effects (font (size 0.7 0.7) (thickness 0.15)) (justify left bottom))
    )
    (fp_rect (start -0.94 -0.47) (end 0.94 0.47) (layer "F.CrtYd") (width 0.05) (fill none))
    (fp_rect (start -0.499 -0.249) (end 0.499 0.249) (layer "F.Fab") (width 0.15) (fill none))
    (pad "1" smd roundrect (at -0.484 0 90) (size 0.59 0.64) (layers "F.Cu" "F.Paste" "F.Mask") (roundrect_rratio 0.25)
      (net 132 "VREG_S4A_1V8") (pintype "passive"))
    (pad "2" smd roundrect (at 0.484 0 90) (size 0.59 0.64) (layers "F.Cu" "F.Paste" "F.Mask") (roundrect_rratio 0.25)
      (net 1 "GND") (pintype "passive"))
  )

  (footprint "sa800u-baseboard-hw-footprints:L_Murata_025020_0605Metric" (layer "F.Cu")
    (tedit 61AA2C4F)
    (at 137.25 136.85 -90)
    (property "Author" "Antmicro")
    (property "License" "Apache-2.0")
    (property "MPN" "NFP0QHB242HS2D")
    (property "Manufacturer" "Murata")
    (property "Sheetfile" "hdmi-converter.kicad_sch")
    (property "Sheetname" "HDMI converter")
    (attr smd)
    (fp_text reference "L10" (at -4.611 15.5 -90) (layer "F.SilkS")
      (effects (font (size 0.7 0.7) (thickness 0.15)) (justify left bottom))
    )
    (fp_text value "NFP0QHB242HS2D" (at 0 1.55 -90) (layer "F.Fab")
      (effects (font (size 0.7 0.7) (thickness 0.15)) (justify left bottom))
    )
    (fp_text user "License: Apache-2.0" (at -1.027 5.805 -90) (layer "F.Fab") hide
      (effects (font (size 0.7 0.7) (thickness 0.15)) (justify left bottom))
    )
    (fp_text user "${REFERENCE}" (at -1.027 3.406 -90) (layer "F.Fab") hide
      (effects (font (size 0.7 0.7) (thickness 0.15)) (justify left bottom))
    )
    (fp_text user "Author: Antmicro" (at -1.027 4.605 -90) (layer "F.Fab") hide
      (effects (font (size 0.7 0.7) (thickness 0.15)) (justify left bottom))
    )
    (fp_line (start 0.276 -0.45) (end -0.276 -0.45) (layer "F.SilkS") (width 0.15))
    (fp_line (start -0.276 0.45) (end 0.276 0.45) (layer "F.SilkS") (width 0.15))
    (fp_circle (center -0.5 -0.5) (end -0.449 -0.5) (layer "F.SilkS") (width 0.15) (fill solid))
    (fp_rect (start -0.5 -0.6) (end 0.5 0.6) (layer "F.CrtYd") (width 0.05) (fill none))
    (fp_line (start 0.275 0.349) (end 0.275 -0.351) (layer "F.Fab") (width 0.15))
    (fp_line (start 0.275 -0.351) (end -0.277 -0.351) (layer "F.Fab") (width 0.15))
    (fp_line (start -0.277 -0.351) (end -0.277 0.349) (layer "F.Fab") (width 0.15))
    (fp_line (start -0.277 0.349) (end 0.275 0.349) (layer "F.Fab") (width 0.15))
    (pad "1" smd rect (at -0.25 -0.24 270) (size 0.3 0.23) (layers "F.Cu" "F.Paste" "F.Mask")
      (net 206 "/HDMI converter/HDMI_CLK_P") (pinfunction "1") (pintype "passive"))
    (pad "2" smd rect (at 0.248 -0.24 270) (size 0.3 0.23) (layers "F.Cu" "F.Paste" "F.Mask")
      (net 237 "/HDMI converter/HDMI_CLK_CONN_P") (pinfunction "2") (pintype "passive"))
    (pad "3" smd rect (at 0.248 0.239 270) (size 0.3 0.23) (layers "F.Cu" "F.Paste" "F.Mask")
      (net 238 "/HDMI converter/HDMI_CLK_CONN_N") (pinfunction "3") (pintype "passive"))
    (pad "4" smd rect (at -0.25 0.239 270) (size 0.3 0.23) (layers "F.Cu" "F.Paste" "F.Mask")
      (net 208 "/HDMI converter/HDMI_CLK_N") (pinfunction "4") (pintype "passive"))
  )

  (footprint "sa800u-baseboard-hw-footprints:C_0402_1005Metric" (layer "F.Cu")
    (tedit 616D63CF)
    (at 147.35 134.95 -90)
    (descr "Capacitor SMD 0402")
    (tags "capacitor SMD 0402")
    (property "Author" "Antmicro")
    (property "Dielectric" "X5R")
    (property "License" "Apache-2.0")
    (property "MPN" "GRM155R61H104KE14D")
    (property "Manufacturer" "Murata")
    (property "Sheetfile" "hdmi-converter.kicad_sch")
    (property "Sheetname" "HDMI converter")
    (property "Val" "100n")
    (property "Voltage" "50V")
    (attr smd)
    (fp_text reference "C50" (at -4.58 16.59 -90) (layer "F.SilkS")
      (effects (font (size 0.7 0.7) (thickness 0.15)) (justify left bottom))
    )
    (fp_text value "C_100n_0402" (at 0 1.4 -90) (layer "F.Fab")
      (effects (font (size 0.7 0.7) (thickness 0.15)) (justify left bottom))
    )
    (fp_text user "${REFERENCE}" (at -0.932 3.168 -90) (layer "F.Fab") hide
      (effects (font (size 0.7 0.7) (thickness 0.15)) (justify left bottom))
    )
    (fp_text user "Author: Antmicro" (at -0.932 4.17 -90) (layer "F.Fab") hide
      (effects (font (size 0.7 0.7) (thickness 0.15)) (justify left bottom))
    )
    (fp_text user "License: Apache-2.0" (at -0.932 5.17 -90) (layer "F.Fab") hide
      (effects (font (size 0.7 0.7) (thickness 0.15)) (justify left bottom))
    )
    (fp_rect (start -0.94 -0.47) (end 0.94 0.47) (layer "F.CrtYd") (width 0.05) (fill none))
    (fp_rect (start -0.499 -0.249) (end 0.499 0.249) (layer "F.Fab") (width 0.15) (fill none))
    (pad "1" smd roundrect (at -0.484 0 270) (size 0.59 0.64) (layers "F.Cu" "F.Paste" "F.Mask") (roundrect_rratio 0.25)
      (net 194 "/HDMI converter/HDMI_TX_D2_P") (pintype "passive"))
    (pad "2" smd roundrect (at 0.484 0 270) (size 0.59 0.64) (layers "F.Cu" "F.Paste" "F.Mask") (roundrect_rratio 0.25)
      (net 193 "/HDMI converter/HDMI_TX2_P") (pintype "passive"))
  )

  (footprint "sa800u-baseboard-hw-footprints:Nexperia_DFN-10_2.5x1mm_P0.5mm" (layer "F.Cu")
    (tedit 6215DC23)
    (at 138.85 139.55 180)
    (property "Author" "Antmicro")
    (property "License" "Apache-2.0")
    (property "MPN" "PUSB3F96X")
    (property "Manufacturer" "Nexperia")
    (property "Sheetfile" "hdmi-converter.kicad_sch")
    (property "Sheetname" "HDMI converter")
    (attr smd)
    (fp_text reference "D4" (at 1.59 0.82 180) (layer "F.SilkS")
      (effects (font (size 0.7 0.7) (thickness 0.15)) (justify left bottom))
    )
    (fp_text value "PUSB3F96X_PASS" (at -0.016 1.705 180) (layer "F.Fab")
      (effects (font (size 0.7 0.7) (thickness 0.15)) (justify left bottom))
    )
    (fp_text user "Author: Antmicro" (at -1.367 4.905 180) (layer "F.Fab") hide
      (effects (font (size 0.7 0.7) (thickness 0.15)) (justify left bottom))
    )
    (fp_text user "License: Apache-2.0" (at -1.367 6.105 180) (layer "F.Fab") hide
      (effects (font (size 0.7 0.7) (thickness 0.15)) (justify left bottom))
    )
    (fp_text user "${REFERENCE}" (at -1.367 3.704 180) (layer "F.Fab") hide
      (effects (font (size 0.7 0.7) (thickness 0.15)) (justify left bottom))
    )
    (fp_line (start 1.233 0.405) (end 1.233 -0.396) (layer "F.SilkS") (width 0.15))
    (fp_line (start -1.266 -0.396) (end -1.266 0.405) (layer "F.SilkS") (width 0.15))
    (fp_circle (center -1.317 0.704) (end -1.266 0.704) (layer "F.SilkS") (width 0.15) (fill solid))
    (fp_rect (start -1.4 -0.7) (end 1.4 0.7) (layer "F.CrtYd") (width 0.05) (fill none))
    (pad "1" smd rect (at -1.016 0.392 180) (size 0.2 0.475) (layers "F.Cu" "F.Paste" "F.Mask")
      (net 239 "/HDMI converter/HDMI_TX0_CONN_P") (pinfunction "CH1") (pintype "passive"))
    (pad "2" smd rect (at -0.517 0.392 180) (size 0.2 0.475) (layers "F.Cu" "F.Paste" "F.Mask")
      (net 236 "/HDMI converter/HDMI_TX0_CONN_N") (pinfunction "CH2") (pintype "passive"))
    (pad "3" smd rect (at -0.016 0.392 180) (size 0.2 0.475) (layers "F.Cu" "F.Paste" "F.Mask")
      (net 1 "GND") (pinfunction "GND") (pintype "passive"))
    (pad "4" smd rect (at 0.482 0.392 180) (size 0.2 0.475) (layers "F.Cu" "F.Paste" "F.Mask")
      (net 237 "/HDMI converter/HDMI_CLK_CONN_P") (pinfunction "CH3") (pintype "passive"))
    (pad "5" smd rect (at 0.982 0.392 180) (size 0.2 0.475) (layers "F.Cu" "F.Paste" "F.Mask")
      (net 238 "/HDMI converter/HDMI_CLK_CONN_N") (pinfunction "CH4") (pintype "passive"))
    (pad "6" smd rect (at 0.982 -0.383) (size 0.2 0.475) (layers "F.Cu" "F.Paste" "F.Mask")
      (net 238 "/HDMI converter/HDMI_CLK_CONN_N") (pinfunction "CH4") (pintype "passive"))
    (pad "7" smd rect (at 0.482 -0.383) (size 0.2 0.475) (layers "F.Cu" "F.Paste" "F.Mask")
      (net 237 "/HDMI converter/HDMI_CLK_CONN_P") (pinfunction "CH3") (pintype "passive"))
    (pad "8" smd rect (at -0.016 -0.383) (size 0.2 0.475) (layers "F.Cu" "F.Paste" "F.Mask")
      (net 1 "GND") (pinfunction "GND") (pintype "passive"))
    (pad "9" smd rect (at -0.517 -0.383) (size 0.2 0.475) (layers "F.Cu" "F.Paste" "F.Mask")
      (net 236 "/HDMI converter/HDMI_TX0_CONN_N") (pinfunction "CH2") (pintype "passive"))
    (pad "10" smd rect (at -1.016 -0.383) (size 0.2 0.475) (layers "F.Cu" "F.Paste" "F.Mask")
      (net 239 "/HDMI converter/HDMI_TX0_CONN_P") (pinfunction "CH1") (pintype "passive"))
  )

  (footprint "sa800u-baseboard-hw-footprints:Nexperia_DFN-10_2.5x1mm_P0.5mm" (layer "F.Cu")
    (tedit 6215DC23)
    (at 142.2 139.55)
    (property "Author" "Antmicro")
    (property "License" "Apache-2.0")
    (property "MPN" "PUSB3F96X")
    (property "Manufacturer" "Nexperia")
    (property "Sheetfile" "hdmi-converter.kicad_sch")
    (property "Sheetname" "HDMI converter")
    (attr smd)
    (fp_text reference "D3" (at -1.53 -0.87) (layer "F.SilkS")
      (effects (font (size 0.7 0.7) (thickness 0.15)) (justify left bottom))
    )
    (fp_text value "PUSB3F96X_PASS" (at -0.016 1.705) (layer "F.Fab")
      (effects (font (size 0.7 0.7) (thickness 0.15)) (justify left bottom))
    )
    (fp_text user "License: Apache-2.0" (at -1.367 6.105) (layer "F.Fab") hide
      (effects (font (size 0.7 0.7) (thickness 0.15)) (justify left bottom))
    )
    (fp_text user "${REFERENCE}" (at -1.367 3.704) (layer "F.Fab") hide
      (effects (font (size 0.7 0.7) (thickness 0.15)) (justify left bottom))
    )
    (fp_text user "Author: Antmicro" (at -1.367 4.905) (layer "F.Fab") hide
      (effects (font (size 0.7 0.7) (thickness 0.15)) (justify left bottom))
    )
    (fp_line (start -1.266 -0.396) (end -1.266 0.405) (layer "F.SilkS") (width 0.15))
    (fp_line (start 1.233 0.405) (end 1.233 -0.396) (layer "F.SilkS") (width 0.15))
    (fp_circle (center -1.317 0.704) (end -1.266 0.704) (layer "F.SilkS") (width 0.15) (fill solid))
    (fp_rect (start -1.4 -0.7) (end 1.4 0.7) (layer "F.CrtYd") (width 0.05) (fill none))
    (pad "1" smd rect (at -1.016 0.392) (size 0.2 0.475) (layers "F.Cu" "F.Paste" "F.Mask")
      (net 235 "/HDMI converter/HDMI_SDA") (pinfunction "CH1") (pintype "passive"))
    (pad "2" smd rect (at -0.517 0.392) (size 0.2 0.475) (layers "F.Cu" "F.Paste" "F.Mask")
      (net 232 "/HDMI converter/HDMI_SCL") (pinfunction "CH2") (pintype "passive"))
    (pad "3" smd rect (at -0.016 0.392) (size 0.2 0.475) (layers "F.Cu" "F.Paste" "F.Mask")
      (net 1 "GND") (pinfunction "GND") (pintype "passive"))
    (pad "4" smd rect (at 0.482 0.392) (size 0.2 0.475) (layers "F.Cu" "F.Paste" "F.Mask")
      (net 233 "/HDMI converter/HDMI_CEC") (pinfunction "CH3") (pintype "passive"))
    (pad "5" smd rect (at 0.982 0.392) (size 0.2 0.475) (layers "F.Cu" "F.Paste" "F.Mask")
      (net 234 "/HDMI converter/HDMI_DETECT") (pinfunction "CH4") (pintype "passive"))
    (pad "6" smd rect (at 0.982 -0.383 180) (size 0.2 0.475) (layers "F.Cu" "F.Paste" "F.Mask")
      (net 234 "/HDMI converter/HDMI_DETECT") (pinfunction "CH4") (pintype "passive"))
    (pad "7" smd rect (at 0.482 -0.383 180) (size 0.2 0.475) (layers "F.Cu" "F.Paste" "F.Mask")
      (net 233 "/HDMI converter/HDMI_CEC") (pinfunction "CH3") (pintype "passive"))
    (pad "8" smd rect (at -0.016 -0.383 180) (size 0.2 0.475) (layers "F.Cu" "F.Paste" "F.Mask")
      (net 1 "GND") (pinfunction "GND") (pintype "passive"))
    (pad "9" smd rect (at -0.517 -0.383 180) (size 0.2 0.475) (layers "F.Cu" "F.Paste" "F.Mask")
      (net 232 "/HDMI converter/HDMI_SCL") (pinfunction "CH2") (pintype "passive"))
    (pad "10" smd rect (at -1.016 -0.383 180) (size 0.2 0.475) (layers "F.Cu" "F.Paste" "F.Mask")
      (net 235 "/HDMI converter/HDMI_SDA") (pinfunction "CH1") (pintype "passive"))
  )

  (footprint "sa800u-baseboard-hw-footprints:R_0402_1005Metric" (layer "F.Cu")
    (tedit 5FD9C158)
    (at 138.2 133.05 -90)
    (descr "Resistor SMD 0402")
    (tags "resistor SMD 0402")
    (property "Author" "Antmicro")
    (property "License" "Apache-2.0")
    (property "MPN" "CR0402-FX-50R0GLF")
    (property "Manufacturer" "Bourns")
    (property "Sheetfile" "hdmi-converter.kicad_sch")
    (property "Sheetname" "HDMI converter")
    (property "Tolerance" "1%")
    (property "Val" "50R")
    (attr smd)
    (fp_text reference "R37" (at -4.611 15.55 -90) (layer "F.SilkS")
      (effects (font (size 0.7 0.7) (thickness 0.15)) (justify left bottom))
    )
    (fp_text value "R_50R_0402" (at 0 1.4 -90) (layer "F.Fab")
      (effects (font (size 0.7 0.7) (thickness 0.15)) (justify left bottom))
    )
    (fp_text user "${REFERENCE}" (at -0.95 3.168 -90) (layer "F.Fab") hide
      (effects (font (size 0.7 0.7) (thickness 0.15)) (justify left bottom))
    )
    (fp_text user "Author: Antmicro" (at -0.95 4.169 -90) (layer "F.Fab") hide
      (effects (font (size 0.7 0.7) (thickness 0.15)) (justify left bottom))
    )
    (fp_text user "License: Apache-2.0" (at -0.95 5.169 -90) (layer "F.Fab") hide
      (effects (font (size 0.7 0.7) (thickness 0.15)) (justify left bottom))
    )
    (fp_rect (start -0.93 -0.47) (end 0.93 0.47) (layer "F.CrtYd") (width 0.05) (fill none))
    (fp_rect (start -0.5 -0.25) (end 0.5 0.25) (layer "F.Fab") (width 0.15) (fill none))
    (pad "1" smd roundrect (at -0.485 0 270) (size 0.59 0.64) (layers "F.Cu" "F.Paste" "F.Mask") (roundrect_rratio 0.25)
      (net 187 "/HDMI converter/LT9611_VCC33_TX") (pintype "passive"))
    (pad "2" smd roundrect (at 0.485 0 270) (size 0.59 0.64) (layers "F.Cu" "F.Paste" "F.Mask") (roundrect_rratio 0.25)
      (net 205 "/HDMI converter/HDMI_TX_CLK_P") (pintype "passive"))
  )

  (footprint "sa800u-baseboard-hw-footprints:C_0402_1005Metric" (layer "F.Cu")
    (tedit 616D63CF)
    (at 136.75 134.95 -90)
    (descr "Capacitor SMD 0402")
    (tags "capacitor SMD 0402")
    (property "Author" "Antmicro")
    (property "Dielectric" "X5R")
    (property "License" "Apache-2.0")
    (property "MPN" "GRM155R61H104KE14D")
    (property "Manufacturer" "Murata")
    (property "Sheetfile" "hdmi-converter.kicad_sch")
    (property "Sheetname" "HDMI converter")
    (property "Val" "100n")
    (property "Voltage" "50V")
    (attr smd)
    (fp_text reference "C49" (at -4.61 15.46 -90) (layer "F.SilkS")
      (effects (font (size 0.7 0.7) (thickness 0.15)) (justify left bottom))
    )
    (fp_text value "C_100n_0402" (at 0 1.4 -90) (layer "F.Fab")
      (effects (font (size 0.7 0.7) (thickness 0.15)) (justify left bottom))
    )
    (fp_text user "License: Apache-2.0" (at -0.932 5.17 -90) (layer "F.Fab") hide
      (effects (font (size 0.7 0.7) (thickness 0.15)) (justify left bottom))
    )
    (fp_text user "${REFERENCE}" (at -0.932 3.168 -90) (layer "F.Fab") hide
      (effects (font (size 0.7 0.7) (thickness 0.15)) (justify left bottom))
    )
    (fp_text user "Author: Antmicro" (at -0.932 4.17 -90) (layer "F.Fab") hide
      (effects (font (size 0.7 0.7) (thickness 0.15)) (justify left bottom))
    )
    (fp_rect (start -0.94 -0.47) (end 0.94 0.47) (layer "F.CrtYd") (width 0.05) (fill none))
    (fp_rect (start -0.499 -0.249) (end 0.499 0.249) (layer "F.Fab") (width 0.15) (fill none))
    (pad "1" smd roundrect (at -0.484 0 270) (size 0.59 0.64) (layers "F.Cu" "F.Paste" "F.Mask") (roundrect_rratio 0.25)
      (net 207 "/HDMI converter/HDMI_TX_CLK_N") (pintype "passive"))
    (pad "2" smd roundrect (at 0.484 0 270) (size 0.59 0.64) (layers "F.Cu" "F.Paste" "F.Mask") (roundrect_rratio 0.25)
      (net 208 "/HDMI converter/HDMI_CLK_N") (pintype "passive"))
  )

  (footprint "sa800u-baseboard-hw-footprints:QFN-64-1EP_7.5x7.5mm_P0.4mm" (layer "F.Cu")
    (tedit 6215E41B)
    (at 140.97322 125 -90)
    (property "Author" "Antmicro")
    (property "License" "Apache-2.0")
    (property "MPN" "LT9611")
    (property "Manufacturer" "Lontium")
    (property "Sheetfile" "hdmi-converter.kicad_sch")
    (property "Sheetname" "HDMI converter")
    (attr smd)
    (fp_text reference "U3" (at -4.53 -2.42678) (layer "F.SilkS")
      (effects (font (size 0.7 0.7) (thickness 0.15)) (justify left bottom))
    )
    (fp_text value "LT9611" (at 0 5.4 -90) (layer "F.Fab")
      (effects (font (size 0.7 0.7) (thickness 0.15)) (justify left bottom))
    )
    (fp_text user "License: Apache-2.0" (at -4.5 6.498 -90) (layer "F.Fab") hide
      (effects (font (size 0.7 0.7) (thickness 0.15)) (justify left bottom))
    )
    (fp_text user "Author: Antmicro" (at -4.5 8.897 -90) (layer "F.Fab") hide
      (effects (font (size 0.7 0.7) (thickness 0.15)) (justify left bottom))
    )
    (fp_text user "${REFERENCE}" (at -4.5 7.698 -90) (layer "F.Fab") hide
      (effects (font (size 0.7 0.7) (thickness 0.15)) (justify left bottom))
    )
    (fp_poly (pts
        (xy 0.726 0.77)
        (xy -0.774 0.77)
        (xy -0.774 -0.784)
        (xy 0.726 -0.784)
      ) (layer "F.Paste") (width 0.01) (fill solid))
    (fp_poly (pts
        (xy 0.726 -1.131)
        (xy -0.774 -1.131)
        (xy -0.774 -2.681)
        (xy 0.726 -2.681)
      ) (layer "F.Paste") (width 0.01) (fill solid))
    (fp_poly (pts
        (xy -2.681 1.126)
        (xy -1.18 1.126)
        (xy -1.18 2.68)
        (xy -2.681 2.68)
      ) (layer "F.Paste") (width 0.01) (fill solid))
    (fp_poly (pts
        (xy -1.17 0.77)
        (xy -2.67 0.77)
        (xy -2.67 -0.784)
        (xy -1.17 -0.784)
      ) (layer "F.Paste") (width 0.01) (fill solid))
    (fp_poly (pts
        (xy 1.169 1.126)
        (xy 2.668 1.126)
        (xy 2.668 2.68)
        (xy 1.169 2.68)
      ) (layer "F.Paste") (width 0.01) (fill solid))
    (fp_poly (pts
        (xy 2.68 0.77)
        (xy 1.179 0.77)
        (xy 1.179 -0.784)
        (xy 2.68 -0.784)
      ) (layer "F.Paste") (width 0.01) (fill solid))
    (fp_poly (pts
        (xy -0.73 1.126)
        (xy 0.77 1.126)
        (xy 0.77 2.68)
        (xy -0.73 2.68)
      ) (layer "F.Paste") (width 0.01) (fill solid))
    (fp_poly (pts
        (xy -1.17 -1.131)
        (xy -2.67 -1.131)
        (xy -2.67 -2.681)
        (xy -1.17 -2.681)
      ) (layer "F.Paste") (width 0.01) (fill solid))
    (fp_poly (pts
        (xy 2.68 -1.131)
        (xy 1.179 -1.131)
        (xy 1.179 -2.681)
        (xy 2.68 -2.681)
      ) (layer "F.Paste") (width 0.01) (fill solid))
    (fp_line (start 3.898 3.898) (end 3.898 3.398) (layer "F.SilkS") (width 0.15))
    (fp_line (start 3.398 -3.9) (end 3.898 -3.9) (layer "F.SilkS") (width 0.15))
    (fp_line (start 3.898 -3.9) (end 3.898 -3.4) (layer "F.SilkS") (width 0.15))
    (fp_line (start -3.9 -3.9) (end -3.4 -3.9) (layer "F.SilkS") (width 0.15))
    (fp_line (start -3.9 3.898) (end -3.9 3.398) (layer "F.SilkS") (width 0.15))
    (fp_line (start 3.398 3.898) (end 3.898 3.898) (layer "F.SilkS") (width 0.15))
    (fp_line (start -3.9 -3.4) (end -3.9 -3.9) (layer "F.SilkS") (width 0.15))
    (fp_line (start -3.4 3.898) (end -3.9 3.898) (layer "F.SilkS") (width 0.15))
    (fp_circle (center -4.202 -3.301) (end -4.151 -3.301) (layer "F.SilkS") (width 0.15) (fill solid))
    (fp_rect (start -4.4 -4.4) (end 4.4 4.4) (layer "F.CrtYd") (width 0.05) (fill none))
    (fp_line (start 3.749 -3.75) (end -2.75 -3.75) (layer "F.Fab") (width 0.15))
    (fp_line (start 3.749 3.749) (end 3.749 -3.75) (layer "F.Fab") (width 0.15))
    (fp_line (start -3.75 -2.75) (end -3.75 3.749) (layer "F.Fab") (width 0.15))
    (fp_line (start -2.75 -3.75) (end -3.75 -2.75) (layer "F.Fab") (width 0.15))
    (fp_line (start -3.75 3.749) (end 3.749 3.749) (layer "F.Fab") (width 0.15))
    (pad "1" smd rect (at -3.801 -3) (size 0.2 1) (layers "F.Cu" "F.Paste" "F.Mask")
      (net 484 "unconnected-(U3-Pad1)") (pinfunction "M0_N2") (pintype "unspecified+no_connect"))
    (pad "2" smd rect (at -3.801 -2.601) (size 0.2 1) (layers "F.Cu" "F.Paste" "F.Mask")
      (net 483 "unconnected-(U3-Pad2)") (pinfunction "M0_P2") (pintype "unspecified+no_connect"))
    (pad "3" smd rect (at -3.801 -2.202) (size 0.2 1) (layers "F.Cu" "F.Paste" "F.Mask")
      (net 185 "/HDMI converter/LT9611_VCC33_RX") (pinfunction "VCC33_MRX01") (pintype "power_in"))
    (pad "4" smd rect (at -3.801 -1.801) (size 0.2 1) (layers "F.Cu" "F.Paste" "F.Mask")
      (net 189 "/HDMI converter/LT9611_VCC12_RX") (pinfunction "VCC12_MRX01") (pintype "power_in"))
    (pad "5" smd rect (at -3.801 -1.401) (size 0.2 1) (layers "F.Cu" "F.Paste" "F.Mask")
      (net 54 "DSI1_LN3_N") (pinfunction "M3_N0") (pintype "input"))
    (pad "6" smd rect (at -3.801 -1) (size 0.2 1) (layers "F.Cu" "F.Paste" "F.Mask")
      (net 58 "DSI1_LN3_P") (pinfunction "M3_P0") (pintype "input"))
    (pad "7" smd rect (at -3.801 -0.6) (size 0.2 1) (layers "F.Cu" "F.Paste" "F.Mask")
      (net 53 "DSI1_LN2_N") (pinfunction "M2_N0") (pintype "input"))
    (pad "8" smd rect (at -3.801 -0.204) (size 0.2 1) (layers "F.Cu" "F.Paste" "F.Mask")
      (net 57 "DSI1_LN2_P") (pinfunction "M2_P0") (pintype "input"))
    (pad "9" smd rect (at -3.801 0.2) (size 0.2 1) (layers "F.Cu" "F.Paste" "F.Mask")
      (net 55 "DSI1_CLK_N") (pinfunction "MC_N0") (pintype "input"))
    (pad "10" smd rect (at -3.801 0.596) (size 0.2 1) (layers "F.Cu" "F.Paste" "F.Mask")
      (net 56 "DSI1_CLK_P") (pinfunction "MC_P0") (pintype "input"))
    (pad "11" smd rect (at -3.801 0.996) (size 0.2 1) (layers "F.Cu" "F.Paste" "F.Mask")
      (net 52 "DSI1_LN1_N") (pinfunction "M1_N0") (pintype "input"))
    (pad "12" smd rect (at -3.801 1.396) (size 0.2 1) (layers "F.Cu" "F.Paste" "F.Mask")
      (net 50 "DSI1_LN1_P") (pinfunction "M1_P0") (pintype "input"))
    (pad "13" smd rect (at -3.801 1.8) (size 0.2 1) (layers "F.Cu" "F.Paste" "F.Mask")
      (net 51 "DSI1_LN0_N") (pinfunction "M0_N0") (pintype "input"))
    (pad "14" smd rect (at -3.801 2.2) (size 0.2 1) (layers "F.Cu" "F.Paste" "F.Mask")
      (net 176 "DSI1_LN0_P") (pinfunction "M0_P0") (pintype "input"))
    (pad "15" smd rect (at -3.801 2.6) (size 0.2 1) (layers "F.Cu" "F.Paste" "F.Mask")
      (net 188 "/HDMI converter/LT9611_VDD12") (pinfunction "VDD1") (pintype "power_in"))
    (pad "16" smd rect (at -3.801 2.999) (size 0.2 1) (layers "F.Cu" "F.Paste" "F.Mask")
      (net 188 "/HDMI converter/LT9611_VDD12") (pinfunction "VDD2") (pintype "power_in"))
    (pad "17" smd rect (at -3 3.798 270) (size 0.2 1) (layers "F.Cu" "F.Paste" "F.Mask")
      (net 186 "/HDMI converter/LT9611_RST_N") (pinfunction "RST_N") (pintype "input"))
    (pad "18" smd rect (at -2.601 3.798 270) (size 0.2 1) (layers "F.Cu" "F.Paste" "F.Mask")
      (net 287 "/HDMI converter/LT9611_SCL") (pinfunction "CSCL_GPIO10") (pintype "bidirectional"))
    (pad "19" smd rect (at -2.202 3.798 270) (size 0.2 1) (layers "F.Cu" "F.Paste" "F.Mask")
      (net 288 "/HDMI converter/LT9611_SDA") (pinfunction "CSDA_GPIO11") (pintype "bidirectional"))
    (pad "20" smd rect (at -1.801 3.798 270) (size 0.2 1) (layers "F.Cu" "F.Paste" "F.Mask")
      (net 482 "unconnected-(U3-Pad20)") (pinfunction "SPI_CSN") (pintype "bidirectional+no_connect"))
    (pad "21" smd rect (at -1.401 3.798 270) (size 0.2 1) (layers "F.Cu" "F.Paste" "F.Mask")
      (net 481 "unconnected-(U3-Pad21)") (pinfunction "SPI_MISO") (pintype "bidirectional+no_connect"))
    (pad "22" smd rect (at -1 3.798 270) (size 0.2 1) (layers "F.Cu" "F.Paste" "F.Mask")
      (net 480 "unconnected-(U3-Pad22)") (pinfunction "GPIO4") (pintype "bidirectional+no_connect"))
    (pad "23" smd rect (at -0.6 3.798 270) (size 0.2 1) (layers "F.Cu" "F.Paste" "F.Mask")
      (net 284 "/HDMI converter/LT9611_INTO_GPIO5") (pinfunction "INTIO_GPIO5") (pintype "bidirectional"))
    (pad "24" smd rect (at -0.204 3.798 270) (size 0.2 1) (layers "F.Cu" "F.Paste" "F.Mask")
      (net 285 "/HDMI converter/LT9611_CEC") (pinfunction "CEC_GPIO6") (pintype "bidirectional"))
    (pad "25" smd rect (at 0.2 3.798 270) (size 0.2 1) (layers "F.Cu" "F.Paste" "F.Mask")
      (net 289 "/HDMI converter/I2C_ADDR") (pinfunction "I2C_ADDR") (pintype "input"))
    (pad "26" smd rect (at 0.596 3.798 270) (size 0.2 1) (layers "F.Cu" "F.Paste" "F.Mask")
      (net 184 "/HDMI converter/LT9611_VCC33_IO") (pinfunction "VC33_IO") (pintype "power_in"))
    (pad "27" smd rect (at 0.996 3.798 270) (size 0.2 1) (layers "F.Cu" "F.Paste" "F.Mask")
      (net 298 "/HDMI converter/LT9611_I2S_WS") (pinfunction "I2S_WS_GPIO7") (pintype "bidirectional"))
    (pad "28" smd rect (at 1.396 3.798 270) (size 0.2 1) (layers "F.Cu" "F.Paste" "F.Mask")
      (net 299 "/HDMI converter/LT9611_I2S_SCLK") (pinfunction "I2S_SCLK_GPIO8") (pintype "bidirectional"))
    (pad "29" smd rect (at 1.8 3.798 270) (size 0.2 1) (layers "F.Cu" "F.Paste" "F.Mask")
      (net 300 "/HDMI converter/LT9611_I2S_MCLK") (pinfunction "I2S_MCLK_GPIO9") (pintype "bidirectional"))
    (pad "30" smd rect (at 2.2 3.798 270) (size 0.2 1) (layers "F.Cu" "F.Paste" "F.Mask")
      (net 297 "/HDMI converter/LT9611_I2S_D0_SPDIF") (pinfunction "I2S_D0_SPDIF") (pintype "bidirectional"))
    (pad "31" smd rect (at 2.6 3.798 270) (size 0.2 1) (layers "F.Cu" "F.Paste" "F.Mask")
      (net 188 "/HDMI converter/LT9611_VDD12") (pinfunction "VDD3") (pintype "power_in"))
    (pad "32" smd rect (at 2.999 3.798 270) (size 0.2 1) (layers "F.Cu" "F.Paste" "F.Mask")
      (net 479 "unconnected-(U3-Pad32)") (pinfunction "SPI_MOSI") (pintype "bidirectional+no_connect"))
    (pad "33" smd rect (at 3.798 2.999) (size 0.2 1) (layers "F.Cu" "F.Paste" "F.Mask")
      (net 478 "unconnected-(U3-Pad33)") (pinfunction "SPI_SCK") (pintype "bidirectional+no_connect"))
    (pad "34" smd rect (at 3.798 2.6) (size 0.2 1) (layers "F.Cu" "F.Paste" "F.Mask")
      (net 184 "/HDMI converter/LT9611_VCC33_IO") (pinfunction "VCC33_IO") (pintype "power_in"))
    (pad "35" smd rect (at 3.798 2.2) (size 0.2 1) (layers "F.Cu" "F.Paste" "F.Mask")
      (net 395 "Net-(R27-Pad1)") (pinfunction "HTX_HPD") (pintype "input"))
    (pad "36" smd rect (at 3.798 1.8) (size 0.2 1) (layers "F.Cu" "F.Paste" "F.Mask")
      (net 235 "/HDMI converter/HDMI_SDA") (pinfunction "HTX_DSDA") (pintype "bidirectional"))
    (pad "37" smd rect (at 3.798 1.396) (size 0.2 1) (layers "F.Cu" "F.Paste" "F.Mask")
      (net 232 "/HDMI converter/HDMI_SCL") (pinfunction "HTX_DSCL") (pintype "output"))
    (pad "38" smd rect (at 3.798 0.996) (size 0.2 1) (layers "F.Cu" "F.Paste" "F.Mask")
      (net 207 "/HDMI converter/HDMI_TX_CLK_N") (pinfunction "HTX_C-") (pintype "output"))
    (pad "39" smd rect (at 3.798 0.596) (size 0.2 1) (layers "F.Cu" "F.Paste" "F.Mask")
      (net 205 "/HDMI converter/HDMI_TX_CLK_P") (pinfunction "HTX_C+") (pintype "output"))
    (pad "40" smd rect (at 3.798 0.2) (size 0.2 1) (layers "F.Cu" "F.Paste" "F.Mask")
      (net 204 "/HDMI converter/HDMI_TX_D0_N") (pinfunction "HTX_D0-") (pintype "output"))
    (pad "41" smd rect (at 3.798 -0.204) (size 0.2 1) (layers "F.Cu" "F.Paste" "F.Mask")
      (net 202 "/HDMI converter/HDMI_TX_D0_P") (pinfunction "HTX_D0+") (pintype "output"))
    (pad "42" smd rect (at 3.798 -0.6) (size 0.2 1) (layers "F.Cu" "F.Paste" "F.Mask")
      (net 209 "/HDMI converter/VCOM") (pinfunction "VCOM") (pintype "input"))
    (pad "43" smd rect (at 3.798 -1) (size 0.2 1) (layers "F.Cu" "F.Paste" "F.Mask")
      (net 187 "/HDMI converter/LT9611_VCC33_TX") (pinfunction "VCC33_HTX") (pintype "power_in"))
    (pad "44" smd rect (at 3.798 -1.401) (size 0.2 1) (layers "F.Cu" "F.Paste" "F.Mask")
      (net 191 "/HDMI converter/LT9611_VCC12_TX") (pinfunction "VCC12_HTX") (pintype "power_in"))
    (pad "45" smd rect (at 3.798 -1.801) (size 0.2 1) (layers "F.Cu" "F.Paste" "F.Mask")
      (net 199 "/HDMI converter/HDMI_TX_D1_N") (pinfunction "HTX_D1-") (pintype "output"))
    (pad "46" smd rect (at 3.798 -2.202) (size 0.2 1) (layers "F.Cu" "F.Paste" "F.Mask")
      (net 197 "/HDMI converter/HDMI_TX_D1_P") (pinfunction "HTX_D1+") (pintype "output"))
    (pad "47" smd rect (at 3.798 -2.601) (size 0.2 1) (layers "F.Cu" "F.Paste" "F.Mask")
      (net 196 "/HDMI converter/HDMI_TX_D2_N") (pinfunction "HTX_D2-") (pintype "output"))
    (pad "48" smd rect (at 3.798 -3) (size 0.2 1) (layers "F.Cu" "F.Paste" "F.Mask")
      (net 194 "/HDMI converter/HDMI_TX_D2_P") (pinfunction "HTX_D2+") (pintype "output"))
    (pad "49" smd rect (at 2.999 -3.801 90) (size 0.2 1) (layers "F.Cu" "F.Paste" "F.Mask")
      (net 192 "/HDMI converter/XTALI") (pinfunction "XTALI") (pintype "input"))
    (pad "50" smd rect (at 2.6 -3.801 90) (size 0.2 1) (layers "F.Cu" "F.Paste" "F.Mask")
      (net 190 "/HDMI converter/XTALO") (pinfunction "XTALO") (pintype "output"))
    (pad "51" smd rect (at 2.2 -3.801 90) (size 0.2 1) (layers "F.Cu" "F.Paste" "F.Mask")
      (net 185 "/HDMI converter/LT9611_VCC33_RX") (pinfunction "VCC33_BG") (pintype "power_in"))
    (pad "52" smd rect (at 1.8 -3.801 90) (size 0.2 1) (layers "F.Cu" "F.Paste" "F.Mask")
      (net 394 "Net-(R22-Pad1)") (pinfunction "REXT") (pintype "passive"))
    (pad "53" smd rect (at 1.396 -3.801 90) (size 0.2 1) (layers "F.Cu" "F.Paste" "F.Mask")
      (net 188 "/HDMI converter/LT9611_VDD12") (pinfunction "VCC12_SYSPLL") (pintype "power_in"))
    (pad "54" smd rect (at 0.996 -3.801 90) (size 0.2 1) (layers "F.Cu" "F.Paste" "F.Mask")
      (net 188 "/HDMI converter/LT9611_VDD12") (pinfunction "VDD") (pintype "power_in"))
    (pad "55" smd rect (at 0.596 -3.801 90) (size 0.2 1) (layers "F.Cu" "F.Paste" "F.Mask")
      (net 185 "/HDMI converter/LT9611_VCC33_RX") (pinfunction "VCC33_MRX23") (pintype "power_in"))
    (pad "56" smd rect (at 0.2 -3.801 90) (size 0.2 1) (layers "F.Cu" "F.Paste" "F.Mask")
      (net 189 "/HDMI converter/LT9611_VCC12_RX") (pinfunction "VCC12_MRX23") (pintype "power_in"))
    (pad "57" smd rect (at -0.204 -3.801 90) (size 0.2 1) (layers "F.Cu" "F.Paste" "F.Mask")
      (net 477 "unconnected-(U3-Pad57)") (pinfunction "M3_N2") (pintype "input+no_connect"))
    (pad "58" smd rect (at -0.6 -3.801 90) (size 0.2 1) (layers "F.Cu" "F.Paste" "F.Mask")
      (net 476 "unconnected-(U3-Pad58)") (pinfunction "M3_P2") (pintype "input+no_connect"))
    (pad "59" smd rect (at -1 -3.801 90) (size 0.2 1) (layers "F.Cu" "F.Paste" "F.Mask")
      (net 475 "unconnected-(U3-Pad59)") (pinfunction "M2_N2") (pintype "input+no_connect"))
    (pad "60" smd rect (at -1.401 -3.801 90) (size 0.2 1) (layers "F.Cu" "F.Paste" "F.Mask")
      (net 474 "unconnected-(U3-Pad60)") (pinfunction "M2_P2") (pintype "input+no_connect"))
    (pad "61" smd rect (at -1.801 -3.801 90) (size 0.2 1) (layers "F.Cu" "F.Paste" "F.Mask")
      (net 473 "unconnected-(U3-Pad61)") (pinfunction "MC_N2") (pintype "input+no_connect"))
    (pad "62" smd rect (at -2.202 -3.801 90) (size 0.2 1) (layers "F.Cu" "F.Paste" "F.Mask")
      (net 472 "unconnected-(U3-Pad62)") (pinfunction "MC_P2") (pintype "input+no_connect"))
    (pad "63" smd rect (at -2.601 -3.801 90) (size 0.2 1) (layers "F.Cu" "F.Paste" "F.Mask")
      (net 471 "unconnected-(U3-Pad63)") (pinfunction "M1_N2") (pintype "input+no_connect"))
    (pad "64" smd rect (at -3 -3.801 90) (size 0.2 1) (layers "F.Cu" "F.Paste" "F.Mask")
      (net 470 "unconnected-(U3-Pad64)") (pinfunction "M1_P2") (pintype "input+no_connect"))
    (pad "65" smd rect (at 0 0 270) (size 6.15 6.15) (layers "F.Cu" "F.Mask")
      (net 1 "GND") (pinfunction "GND") (pintype "power_in"))
  )

  (footprint "sa800u-baseboard-hw-footprints:L_Murata_025020_0605Metric" (layer "F.Cu")
    (tedit 61AA2C4F)
    (at 140.45 136.85 -90)
    (property "Author" "Antmicro")
    (property "License" "Apache-2.0")
    (property "MPN" "NFP0QHB242HS2D")
    (property "Manufacturer" "Murata")
    (property "Sheetfile" "hdmi-converter.kicad_sch")
    (property "Sheetname" "HDMI converter")
    (attr smd)
    (fp_text reference "L9" (at -4.57 15.86 -90) (layer "F.SilkS")
      (effects (font (size 0.7 0.7) (thickness 0.15)) (justify left bottom))
    )
    (fp_text value "NFP0QHB242HS2D" (at 0 1.55 -90) (layer "F.Fab")
      (effects (font (size 0.7 0.7) (thickness 0.15)) (justify left bottom))
    )
    (fp_text user "License: Apache-2.0" (at -1.027 5.805 -90) (layer "F.Fab") hide
      (effects (font (size 0.7 0.7) (thickness 0.15)) (justify left bottom))
    )
    (fp_text user "${REFERENCE}" (at -1.027 3.406 -90) (layer "F.Fab") hide
      (effects (font (size 0.7 0.7) (thickness 0.15)) (justify left bottom))
    )
    (fp_text user "Author: Antmicro" (at -1.027 4.605 -90) (layer "F.Fab") hide
      (effects (font (size 0.7 0.7) (thickness 0.15)) (justify left bottom))
    )
    (fp_line (start -0.276 0.45) (end 0.276 0.45) (layer "F.SilkS") (width 0.15))
    (fp_line (start 0.276 -0.45) (end -0.276 -0.45) (layer "F.SilkS") (width 0.15))
    (fp_circle (center -0.5 -0.5) (end -0.449 -0.5) (layer "F.SilkS") (width 0.15) (fill solid))
    (fp_rect (start -0.5 -0.6) (end 0.5 0.6) (layer "F.CrtYd") (width 0.05) (fill none))
    (fp_line (start 0.275 0.349) (end 0.275 -0.351) (layer "F.Fab") (width 0.15))
    (fp_line (start 0.275 -0.351) (end -0.277 -0.351) (layer "F.Fab") (width 0.15))
    (fp_line (start -0.277 -0.351) (end -0.277 0.349) (layer "F.Fab") (width 0.15))
    (fp_line (start -0.277 0.349) (end 0.275 0.349) (layer "F.Fab") (width 0.15))
    (pad "1" smd rect (at -0.25 -0.24 270) (size 0.3 0.23) (layers "F.Cu" "F.Paste" "F.Mask")
      (net 201 "/HDMI converter/HDMI_TX0_P") (pinfunction "1") (pintype "passive"))
    (pad "2" smd rect (at 0.248 -0.24 270) (size 0.3 0.23) (layers "F.Cu" "F.Paste" "F.Mask")
      (net 239 "/HDMI converter/HDMI_TX0_CONN_P") (pinfunction "2") (pintype "passive"))
    (pad "3" smd rect (at 0.248 0.239 270) (size 0.3 0.23) (layers "F.Cu" "F.Paste" "F.Mask")
      (net 236 "/HDMI converter/HDMI_TX0_CONN_N") (pinfunction "3") (pintype "passive"))
    (pad "4" smd rect (at -0.25 0.239 270) (size 0.3 0.23) (layers "F.Cu" "F.Paste" "F.Mask")
      (net 203 "/HDMI converter/HDMI_TX0_N") (pinfunction "4") (pintype "passive"))
  )

  (footprint "sa800u-baseboard-hw-footprints:L_Murata_025020_0605Metric" (layer "F.Cu")
    (tedit 61AA2C4F)
    (at 143.65 136.85 -90)
    (property "Author" "Antmicro")
    (property "License" "Apache-2.0")
    (property "MPN" "NFP0QHB242HS2D")
    (property "Manufacturer" "Murata")
    (property "Sheetfile" "hdmi-converter.kicad_sch")
    (property "Sheetname" "HDMI converter")
    (attr smd)
    (fp_text reference "L8" (at -4.55 16.16 -90) (layer "F.SilkS")
      (effects (font (size 0.7 0.7) (thickness 0.15)) (justify left bottom))
    )
    (fp_text value "NFP0QHB242HS2D" (at 0 1.55 -90) (layer "F.Fab")
      (effects (font (size 0.7 0.7) (thickness 0.15)) (justify left bottom))
    )
    (fp_text user "License: Apache-2.0" (at -1.027 5.805 -90) (layer "F.Fab") hide
      (effects (font (size 0.7 0.7) (thickness 0.15)) (justify left bottom))
    )
    (fp_text user "Author: Antmicro" (at -1.027 4.605 -90) (layer "F.Fab") hide
      (effects (font (size 0.7 0.7) (thickness 0.15)) (justify left bottom))
    )
    (fp_text user "${REFERENCE}" (at -1.027 3.406 -90) (layer "F.Fab") hide
      (effects (font (size 0.7 0.7) (thickness 0.15)) (justify left bottom))
    )
    (fp_line (start -0.276 0.45) (end 0.276 0.45) (layer "F.SilkS") (width 0.15))
    (fp_line (start 0.276 -0.45) (end -0.276 -0.45) (layer "F.SilkS") (width 0.15))
    (fp_circle (center -0.5 -0.5) (end -0.449 -0.5) (layer "F.SilkS") (width 0.15) (fill solid))
    (fp_rect (start -0.5 -0.6) (end 0.5 0.6) (layer "F.CrtYd") (width 0.05) (fill none))
    (fp_line (start -0.277 -0.351) (end -0.277 0.349) (layer "F.Fab") (width 0.15))
    (fp_line (start 0.275 -0.351) (end -0.277 -0.351) (layer "F.Fab") (width 0.15))
    (fp_line (start -0.277 0.349) (end 0.275 0.349) (layer "F.Fab") (width 0.15))
    (fp_line (start 0.275 0.349) (end 0.275 -0.351) (layer "F.Fab") (width 0.15))
    (pad "1" smd rect (at -0.25 -0.24 270) (size 0.3 0.23) (layers "F.Cu" "F.Paste" "F.Mask")
      (net 198 "/HDMI converter/HDMI_TX1_P") (pinfunction "1") (pintype "passive"))
    (pad "2" smd rect (at 0.248 -0.24 270) (size 0.3 0.23) (layers "F.Cu" "F.Paste" "F.Mask")
      (net 241 "/HDMI converter/HDMI_TX1_CONN_P") (pinfunction "2") (pintype "passive"))
    (pad "3" smd rect (at 0.248 0.239 270) (size 0.3 0.23) (layers "F.Cu" "F.Paste" "F.Mask")
      (net 242 "/HDMI converter/HDMI_TX1_CONN_N") (pinfunction "3") (pintype "passive"))
    (pad "4" smd rect (at -0.25 0.239 270) (size 0.3 0.23) (layers "F.Cu" "F.Paste" "F.Mask")
      (net 200 "/HDMI converter/HDMI_TX1_N") (pinfunction "4") (pintype "passive"))
  )

  (footprint "sa800u-baseboard-hw-footprints:L_Murata_025020_0605Metric" (layer "F.Cu")
    (tedit 61AA2C4F)
    (at 146.85 136.85 -90)
    (property "Author" "Antmicro")
    (property "License" "Apache-2.0")
    (property "MPN" "NFP0QHB242HS2D")
    (property "Manufacturer" "Murata")
    (property "Sheetfile" "hdmi-converter.kicad_sch")
    (property "Sheetname" "HDMI converter")
    (attr smd)
    (fp_text reference "L7" (at -4.57 16.65 -90) (layer "F.SilkS")
      (effects (font (size 0.7 0.7) (thickness 0.15)) (justify left bottom))
    )
    (fp_text value "NFP0QHB242HS2D" (at 0 1.55 -90) (layer "F.Fab")
      (effects (font (size 0.7 0.7) (thickness 0.15)) (justify left bottom))
    )
    (fp_text user "License: Apache-2.0" (at -1.027 5.805 -90) (layer "F.Fab") hide
      (effects (font (size 0.7 0.7) (thickness 0.15)) (justify left bottom))
    )
    (fp_text user "Author: Antmicro" (at -1.027 4.605 -90) (layer "F.Fab") hide
      (effects (font (size 0.7 0.7) (thickness 0.15)) (justify left bottom))
    )
    (fp_text user "${REFERENCE}" (at -1.027 3.406 -90) (layer "F.Fab") hide
      (effects (font (size 0.7 0.7) (thickness 0.15)) (justify left bottom))
    )
    (fp_line (start 0.276 -0.45) (end -0.276 -0.45) (layer "F.SilkS") (width 0.15))
    (fp_line (start -0.276 0.45) (end 0.276 0.45) (layer "F.SilkS") (width 0.15))
    (fp_circle (center -0.5 -0.5) (end -0.449 -0.5) (layer "F.SilkS") (width 0.15) (fill solid))
    (fp_rect (start -0.5 -0.6) (end 0.5 0.6) (layer "F.CrtYd") (width 0.05) (fill none))
    (fp_line (start -0.277 -0.351) (end -0.277 0.349) (layer "F.Fab") (width 0.15))
    (fp_line (start 0.275 0.349) (end 0.275 -0.351) (layer "F.Fab") (width 0.15))
    (fp_line (start -0.277 0.349) (end 0.275 0.349) (layer "F.Fab") (width 0.15))
    (fp_line (start 0.275 -0.351) (end -0.277 -0.351) (layer "F.Fab") (width 0.15))
    (pad "1" smd rect (at -0.25 -0.24 270) (size 0.3 0.23) (layers "F.Cu" "F.Paste" "F.Mask")
      (net 193 "/HDMI converter/HDMI_TX2_P") (pinfunction "1") (pintype "passive"))
    (pad "2" smd rect (at 0.248 -0.24 270) (size 0.3 0.23) (layers "F.Cu" "F.Paste" "F.Mask")
      (net 243 "/HDMI converter/HDMI_TX2_CONN_P") (pinfunction "2") (pintype "passive"))
    (pad "3" smd rect (at 0.248 0.239 270) (size 0.3 0.23) (layers "F.Cu" "F.Paste" "F.Mask")
      (net 240 "/HDMI converter/HDMI_TX2_CONN_N") (pinfunction "3") (pintype "passive"))
    (pad "4" smd rect (at -0.25 0.239 270) (size 0.3 0.23) (layers "F.Cu" "F.Paste" "F.Mask")
      (net 195 "/HDMI converter/HDMI_TX2_N") (pinfunction "4") (pintype "passive"))
  )

  (footprint "sa800u-baseboard-hw-footprints:R_0402_1005Metric" (layer "F.Cu")
    (tedit 5FD9C158)
    (at 142.7 133.05 -90)
    (descr "Resistor SMD 0402")
    (tags "resistor SMD 0402")
    (property "Author" "Antmicro")
    (property "License" "Apache-2.0")
    (property "MPN" "CR0402-FX-50R0GLF")
    (property "Manufacturer" "Bourns")
    (property "Sheetfile" "hdmi-converter.kicad_sch")
    (property "Sheetname" "HDMI converter")
    (property "Tolerance" "1%")
    (property "Val" "50R")
    (attr smd)
    (fp_text reference "R40" (at -4.66 15.99 -90) (layer "F.SilkS")
      (effects (font (size 0.7 0.7) (thickness 0.15)) (justify left bottom))
    )
    (fp_text value "R_50R_0402" (at 0 1.4 -90) (layer "F.Fab")
      (effects (font (size 0.7 0.7) (thickness 0.15)) (justify left bottom))
    )
    (fp_text user "License: Apache-2.0" (at -0.95 5.169 -90) (layer "F.Fab") hide
      (effects (font (size 0.7 0.7) (thickness 0.15)) (justify left bottom))
    )
    (fp_text user "${REFERENCE}" (at -0.95 3.168 -90) (layer "F.Fab") hide
      (effects (font (size 0.7 0.7) (thickness 0.15)) (justify left bottom))
    )
    (fp_text user "Author: Antmicro" (at -0.95 4.169 -90) (layer "F.Fab") hide
      (effects (font (size 0.7 0.7) (thickness 0.15)) (justify left bottom))
    )
    (fp_rect (start -0.93 -0.47) (end 0.93 0.47) (layer "F.CrtYd") (width 0.05) (fill none))
    (fp_rect (start -0.5 -0.25) (end 0.5 0.25) (layer "F.Fab") (width 0.15) (fill none))
    (pad "1" smd roundrect (at -0.485 0 270) (size 0.59 0.64) (layers "F.Cu" "F.Paste" "F.Mask") (roundrect_rratio 0.25)
      (net 187 "/HDMI converter/LT9611_VCC33_TX") (pintype "passive"))
    (pad "2" smd roundrect (at 0.485 0 270) (size 0.59 0.64) (layers "F.Cu" "F.Paste" "F.Mask") (roundrect_rratio 0.25)
      (net 199 "/HDMI converter/HDMI_TX_D1_N") (pintype "passive"))
  )

  (footprint "sa800u-baseboard-hw-footprints:R_0402_1005Metric" (layer "F.Cu")
    (tedit 5FD9C158)
    (at 145.9 133.05 -90)
    (descr "Resistor SMD 0402")
    (tags "resistor SMD 0402")
    (property "Author" "Antmicro")
    (property "License" "Apache-2.0")
    (property "MPN" "CR0402-FX-50R0GLF")
    (property "Manufacturer" "Bourns")
    (property "Sheetfile" "hdmi-converter.kicad_sch")
    (property "Sheetname" "HDMI converter")
    (property "Tolerance" "1%")
    (property "Val" "50R")
    (attr smd)
    (fp_text reference "R45" (at -4.601 16.48 -90) (layer "F.SilkS")
      (effects (font (size 0.7 0.7) (thickness 0.15)) (justify left bottom))
    )
    (fp_text value "R_50R_0402" (at 0 1.4 -90) (layer "F.Fab")
      (effects (font (size 0.7 0.7) (thickness 0.15)) (justify left bottom))
    )
    (fp_text user "Author: Antmicro" (at -0.95 4.169 -90) (layer "F.Fab") hide
      (effects (font (size 0.7 0.7) (thickness 0.15)) (justify left bottom))
    )
    (fp_text user "${REFERENCE}" (at -0.95 3.168 -90) (layer "F.Fab") hide
      (effects (font (size 0.7 0.7) (thickness 0.15)) (justify left bottom))
    )
    (fp_text user "License: Apache-2.0" (at -0.95 5.169 -90) (layer "F.Fab") hide
      (effects (font (size 0.7 0.7) (thickness 0.15)) (justify left bottom))
    )
    (fp_rect (start -0.93 -0.47) (end 0.93 0.47) (layer "F.CrtYd") (width 0.05) (fill none))
    (fp_rect (start -0.5 -0.25) (end 0.5 0.25) (layer "F.Fab") (width 0.15) (fill none))
    (pad "1" smd roundrect (at -0.485 0 270) (size 0.59 0.64) (layers "F.Cu" "F.Paste" "F.Mask") (roundrect_rratio 0.25)
      (net 187 "/HDMI converter/LT9611_VCC33_TX") (pintype "passive"))
    (pad "2" smd roundrect (at 0.485 0 270) (size 0.59 0.64) (layers "F.Cu" "F.Paste" "F.Mask") (roundrect_rratio 0.25)
      (net 196 "/HDMI converter/HDMI_TX_D2_N") (pintype "passive"))
  )

  (footprint "sa800u-baseboard-hw-footprints:C_0402_1005Metric" (layer "F.Cu")
    (tedit 616D63CF)
    (at 146.35 134.95 -90)
    (descr "Capacitor SMD 0402")
    (tags "capacitor SMD 0402")
    (property "Author" "Antmicro")
    (property "Dielectric" "X5R")
    (property "License" "Apache-2.0")
    (property "MPN" "GRM155R61H104KE14D")
    (property "Manufacturer" "Murata")
    (property "Sheetfile" "hdmi-converter.kicad_sch")
    (property "Sheetname" "HDMI converter")
    (property "Val" "100n")
    (property "Voltage" "50V")
    (attr smd)
    (fp_text reference "C46" (at -4.6 16.48 -90) (layer "F.SilkS")
      (effects (font (size 0.7 0.7) (thickness 0.15)) (justify left bottom))
    )
    (fp_text value "C_100n_0402" (at 0 1.4 -90) (layer "F.Fab")
      (effects (font (size 0.7 0.7) (thickness 0.15)) (justify left bottom))
    )
    (fp_text user "${REFERENCE}" (at -0.932 3.168 -90) (layer "F.Fab") hide
      (effects (font (size 0.7 0.7) (thickness 0.15)) (justify left bottom))
    )
    (fp_text user "Author: Antmicro" (at -0.932 4.17 -90) (layer "F.Fab") hide
      (effects (font (size 0.7 0.7) (thickness 0.15)) (justify left bottom))
    )
    (fp_text user "License: Apache-2.0" (at -0.932 5.17 -90) (layer "F.Fab") hide
      (effects (font (size 0.7 0.7) (thickness 0.15)) (justify left bottom))
    )
    (fp_rect (start -0.94 -0.47) (end 0.94 0.47) (layer "F.CrtYd") (width 0.05) (fill none))
    (fp_rect (start -0.499 -0.249) (end 0.499 0.249) (layer "F.Fab") (width 0.15) (fill none))
    (pad "1" smd roundrect (at -0.484 0 270) (size 0.59 0.64) (layers "F.Cu" "F.Paste" "F.Mask") (roundrect_rratio 0.25)
      (net 196 "/HDMI converter/HDMI_TX_D2_N") (pintype "passive"))
    (pad "2" smd roundrect (at 0.484 0 270) (size 0.59 0.64) (layers "F.Cu" "F.Paste" "F.Mask") (roundrect_rratio 0.25)
      (net 195 "/HDMI converter/HDMI_TX2_N") (pintype "passive"))
  )

  (footprint "sa800u-baseboard-hw-footprints:C_0402_1005Metric" (layer "F.Cu")
    (tedit 616D63CF)
    (at 135.238164 129.09 180)
    (descr "Capacitor SMD 0402")
    (tags "capacitor SMD 0402")
    (property "Author" "Antmicro")
    (property "Dielectric" "X5R")
    (property "License" "Apache-2.0")
    (property "MPN" "GRM155R61H104KE14D")
    (property "Manufacturer" "Murata")
    (property "Sheetfile" "hdmi-converter.kicad_sch")
    (property "Sheetname" "HDMI converter")
    (property "Val" "100n")
    (property "Voltage" "50V")
    (attr smd)
    (fp_text reference "C37" (at 3.028164 -0.477047 180) (layer "F.SilkS")
      (effects (font (size 0.7 0.7) (thickness 0.15)) (justify left bottom))
    )
    (fp_text value "C_100n_0402" (at 0 1.4 180) (layer "F.Fab")
      (effects (font (size 0.7 0.7) (thickness 0.15)) (justify left bottom))
    )
    (fp_text user "Author: Antmicro" (at -0.932 4.17 180) (layer "F.Fab") hide
      (effects (font (size 0.7 0.7) (thickness 0.15)) (justify left bottom))
    )
    (fp_text user "License: Apache-2.0" (at -0.932 5.17 180) (layer "F.Fab") hide
      (effects (font (size 0.7 0.7) (thickness 0.15)) (justify left bottom))
    )
    (fp_text user "${REFERENCE}" (at -0.932 3.168 180) (layer "F.Fab") hide
      (effects (font (size 0.7 0.7) (thickness 0.15)) (justify left bottom))
    )
    (fp_rect (start -0.94 -0.47) (end 0.94 0.47) (layer "F.CrtYd") (width 0.05) (fill none))
    (fp_rect (start -0.499 -0.249) (end 0.499 0.249) (layer "F.Fab") (width 0.15) (fill none))
    (pad "1" smd roundrect (at -0.484 0 180) (size 0.59 0.64) (layers "F.Cu" "F.Paste" "F.Mask") (roundrect_rratio 0.25)
      (net 188 "/HDMI converter/LT9611_VDD12") (pintype "passive"))
    (pad "2" smd roundrect (at 0.484 0 180) (size 0.59 0.64) (layers "F.Cu" "F.Paste" "F.Mask") (roundrect_rratio 0.25)
      (net 1 "GND") (pintype "passive"))
  )

  (footprint "sa800u-baseboard-hw-footprints:C_0402_1005Metric" (layer "F.Cu")
    (tedit 616D63CF)
    (at 136.15 138.8 -90)
    (descr "Capacitor SMD 0402")
    (tags "capacitor SMD 0402")
    (property "Author" "Antmicro")
    (property "Dielectric" "X5R")
    (property "License" "Apache-2.0")
    (property "MPN" "GRM155R61H104KE14D")
    (property "Manufacturer" "Murata")
    (property "Sheetfile" "hdmi-converter.kicad_sch")
    (property "Sheetname" "HDMI converter")
    (property "Val" "100n")
    (property "Voltage" "50V")
    (attr smd)
    (fp_text reference "C55" (at 3.09 -0.38 -90) (layer "F.SilkS")
      (effects (font (size 0.7 0.7) (thickness 0.15)) (justify left bottom))
    )
    (fp_text value "C_100n_0402" (at 0 1.4 -90) (layer "F.Fab")
      (effects (font (size 0.7 0.7) (thickness 0.15)) (justify left bottom))
    )
    (fp_text user "Author: Antmicro" (at -0.932 4.17 -90) (layer "F.Fab") hide
      (effects (font (size 0.7 0.7) (thickness 0.15)) (justify left bottom))
    )
    (fp_text user "License: Apache-2.0" (at -0.932 5.17 -90) (layer "F.Fab") hide
      (effects (font (size 0.7 0.7) (thickness 0.15)) (justify left bottom))
    )
    (fp_text user "${REFERENCE}" (at -0.932 3.168 -90) (layer "F.Fab") hide
      (effects (font (size 0.7 0.7) (thickness 0.15)) (justify left bottom))
    )
    (fp_rect (start -0.94 -0.47) (end 0.94 0.47) (layer "F.CrtYd") (width 0.05) (fill none))
    (fp_rect (start -0.499 -0.249) (end 0.499 0.249) (layer "F.Fab") (width 0.15) (fill none))
    (pad "1" smd roundrect (at -0.484 0 270) (size 0.59 0.64) (layers "F.Cu" "F.Paste" "F.Mask") (roundrect_rratio 0.25)
      (net 209 "/HDMI converter/VCOM") (pintype "passive"))
    (pad "2" smd roundrect (at 0.484 0 270) (size 0.59 0.64) (layers "F.Cu" "F.Paste" "F.Mask") (roundrect_rratio 0.25)
      (net 1 "GND") (pintype "passive"))
  )

  (footprint "sa800u-baseboard-hw-footprints:R_0402_1005Metric" (layer "F.Cu")
    (tedit 5FD9C158)
    (at 147.8 133.05 -90)
    (descr "Resistor SMD 0402")
    (tags "resistor SMD 0402")
    (property "Author" "Antmicro")
    (property "License" "Apache-2.0")
    (property "MPN" "CR0402-FX-50R0GLF")
    (property "Manufacturer" "Bourns")
    (property "Sheetfile" "hdmi-converter.kicad_sch")
    (property "Sheetname" "HDMI converter")
    (property "Tolerance" "1%")
    (property "Val" "50R")
    (attr smd)
    (fp_text reference "R47" (at -4.66 16.68 -90) (layer "F.SilkS")
      (effects (font (size 0.7 0.7) (thickness 0.15)) (justify left bottom))
    )
    (fp_text value "R_50R_0402" (at 0 1.4 -90) (layer "F.Fab")
      (effects (font (size 0.7 0.7) (thickness 0.15)) (justify left bottom))
    )
    (fp_text user "License: Apache-2.0" (at -0.95 5.169 -90) (layer "F.Fab") hide
      (effects (font (size 0.7 0.7) (thickness 0.15)) (justify left bottom))
    )
    (fp_text user "${REFERENCE}" (at -0.95 3.168 -90) (layer "F.Fab") hide
      (effects (font (size 0.7 0.7) (thickness 0.15)) (justify left bottom))
    )
    (fp_text user "Author: Antmicro" (at -0.95 4.169 -90) (layer "F.Fab") hide
      (effects (font (size 0.7 0.7) (thickness 0.15)) (justify left bottom))
    )
    (fp_rect (start -0.93 -0.47) (end 0.93 0.47) (layer "F.CrtYd") (width 0.05) (fill none))
    (fp_rect (start -0.5 -0.25) (end 0.5 0.25) (layer "F.Fab") (width 0.15) (fill none))
    (pad "1" smd roundrect (at -0.485 0 270) (size 0.59 0.64) (layers "F.Cu" "F.Paste" "F.Mask") (roundrect_rratio 0.25)
      (net 187 "/HDMI converter/LT9611_VCC33_TX") (pintype "passive"))
    (pad "2" smd roundrect (at 0.485 0 270) (size 0.59 0.64) (layers "F.Cu" "F.Paste" "F.Mask") (roundrect_rratio 0.25)
      (net 194 "/HDMI converter/HDMI_TX_D2_P") (pintype "passive"))
  )

  (footprint "sa800u-baseboard-hw-footprints:LED_0603_1608Metric_G" (layer "F.Cu")
    (tedit 60C2DD7B)
    (at 68.7 118.6 90)
    (descr "LED SMD 0603 Green")
    (tags "LED SMD 0603 Green")
    (property "Author" "Antmicro")
    (property "License" "Apache-2.0")
    (property "MPN" "KP-1608ZGC")
    (property "Manufacturer" "Kingbright")
    (property "Sheetfile" "poe.kicad_sch")
    (property "Sheetname" "PoE")
    (attr smd)
    (fp_text reference "D32" (at -1.62 -0.78 90) (layer "F.SilkS")
      (effects (font (size 0.7 0.7) (thickness 0.15)) (justify left bottom))
    )
    (fp_text value "KP-1608EC" (at 0 1.6 90) (layer "F.Fab")
      (effects (font (size 0.7 0.7) (thickness 0.15)) (justify left bottom))
    )
    (fp_text user "License: Apache-2.0" (at -1.31 5.769 90) (layer "F.Fab") hide
      (effects (font (size 0.7 0.7) (thickness 0.15)) (justify left bottom))
    )
    (fp_text user "Author: Antmicro" (at -1.31 4.769 90) (layer "F.Fab") hide
      (effects (font (size 0.7 0.7) (thickness 0.15)) (justify left bottom))
    )
    (fp_text user "${REFERENCE}" (at -1.31 3.769 90) (layer "F.Fab") hide
      (effects (font (size 0.7 0.7) (thickness 0.15)) (justify left bottom))
    )
    (fp_line (start -0.27 -0.35) (end 0.27 -0.35) (layer "F.SilkS") (width 0.15))
    (fp_line (start -0.106328 -0.200008) (end -0.106328 0.199992) (layer "F.SilkS") (width 0.1))
    (fp_line (start 0.093672 -0.200008) (end 0.093672 0.199992) (layer "F.SilkS") (width 0.1))
    (fp_line (start 1.25 0.32) (end 1.25 -0.32) (layer "F.SilkS") (width 0.15))
    (fp_line (start -0.106328 -0.000008) (end -0.29 0) (layer "F.SilkS") (width 0.1))
    (fp_line (start -0.27 0.351) (end 0.27 0.351) (layer "F.SilkS") (width 0.15))
    (fp_line (start -0.106328 -0.200008) (end 0.093672 -0.000008) (layer "F.SilkS") (width 0.1))
    (fp_line (start 0.093672 -0.000008) (end 0.293672 -0.000008) (layer "F.SilkS") (width 0.1))
    (fp_line (start 0.093672 -0.000008) (end -0.106328 0.199992) (layer "F.SilkS") (width 0.1))
    (fp_rect (start 1.26 0.65) (end -1.26 -0.65) (layer "F.CrtYd") (width 0.05) (fill none))
    (fp_line (start -0.201 0) (end -0.201 0.202) (layer "F.Fab") (width 0.15))
    (fp_line (start 0.199 0) (end 0.597 0) (layer "F.Fab") (width 0.15))
    (fp_line (start 0.199 0.202) (end 0.199 -0.1) (layer "F.Fab") (width 0.15))
    (fp_line (start -0.201 -0.2) (end -0.201 0) (layer "F.Fab") (width 0.15))
    (fp_line (start -0.201 0.202) (end 0.101 0) (layer "F.Fab") (width 0.15))
    (fp_line (start -0.599 0) (end -0.201 0) (layer "F.Fab") (width 0.15))
    (fp_line (start 0.101 0) (end -0.201 -0.2) (layer "F.Fab") (width 0.15))
    (fp_line (start 0.199 -0.2) (end 0.199 -0.1) (layer "F.Fab") (width 0.15))
    (fp_rect (start -0.848 -0.4) (end 0.85 0.402) (layer "F.Fab") (width 0.15) (fill none))
    (pad "1" smd rect (at -0.75 0 270) (size 0.8 0.8) (layers "F.Cu" "F.Paste" "F.Mask")
      (net 380 "Net-(D32-Pad1)") (pinfunction "1") (pintype "passive"))
    (pad "2" smd rect (at 0.75 0 270) (size 0.8 0.8) (layers "F.Cu" "F.Paste" "F.Mask")
      (net 7 "GNDD") (pinfunction "2") (pintype "passive"))
  )

  (footprint "sa800u-baseboard-hw-footprints:Oscillator_SMD_Geyer_KX-7-4Pin_3.2x2.5mm" (layer "F.Cu")
    (tedit 5D7218CB)
    (at 148.188164 128.312952 -90)
    (property "Author" "Antmicro")
    (property "License" "Apache-2.0")
    (property "MPN" "ABM8G-24.000MHZ-18-D2Y-T")
    (property "Manufacturer" "Abracon")
    (property "Sheetfile" "hdmi-converter.kicad_sch")
    (property "Sheetname" "HDMI converter")
    (property "Val" "24.000MHz")
    (attr smd)
    (fp_text reference "Y2" (at -2.052952 1.828164 180) (layer "F.SilkS")
      (effects (font (size 0.7 0.7) (thickness 0.15)) (justify left bottom))
    )
    (fp_text value "ABM8G-24.000MHZ-18-D2Y-T" (at -1.75 2.548 -90) (layer "F.Fab")
      (effects (font (size 0.7 0.7) (thickness 0.15)) (justify left bottom))
    )
    (fp_text user "License: Apache-2.0" (at -1.75 6.5 -90) (layer "F.Fab") hide
      (effects (font (size 0.7 0.7) (thickness 0.15)) (justify left bottom))
    )
    (fp_text user "${REFERENCE}" (at -1.75 3.75 -90) (layer "F.Fab") hide
      (effects (font (size 0.7 0.7) (thickness 0.15)) (justify left bottom))
    )
    (fp_text user "Author: Antmicro" (at -1.75 5 -90) (layer "F.Fab") hide
      (effects (font (size 0.7 0.7) (thickness 0.15)) (justify left bottom))
    )
    (fp_line (start -0.35 -1.25) (end 0.45 -1.25) (layer "F.SilkS") (width 0.15))
    (fp_line (start -0.35 1.25) (end 0.45 1.25) (layer "F.SilkS") (width 0.15))
    (fp_line (start -1.6 0.3) (end -1.6 -0.2) (layer "F.SilkS") (width 0.15))
    (fp_line (start 1.6 0.3) (end 1.6 -0.2) (layer "F.SilkS") (width 0.15))
    (fp_circle (center -1.75 1.5) (end -1.7 1.5) (layer "F.SilkS") (width 0.15) (fill none))
    (fp_rect (start -1.907 -1.55) (end 2.006 1.649) (layer "F.CrtYd") (width 0.05) (fill none))
    (pad "1" smd roundrect (at -1.101 0.949 270) (size 1.3 1.1) (layers "F.Cu" "F.Paste" "F.Mask") (roundrect_rratio 0)
      (chamfer_ratio 0.2) (chamfer bottom_left)
      (net 190 "/HDMI converter/XTALO") (pintype "passive"))
    (pad "2" smd rect (at 1.199 0.949 270) (size 1.3 1.1) (layers "F.Cu" "F.Paste" "F.Mask")
      (net 1 "GND") (pinfunction "SH") (pintype "passive"))
    (pad "3" smd rect (at 1.199 -0.85 270) (size 1.3 1.1) (layers "F.Cu" "F.Paste" "F.Mask")
      (net 192 "/HDMI converter/XTALI") (pintype "passive"))
    (pad "4" smd rect (at -1.101 -0.85 270) (size 1.3 1.1) (layers "F.Cu" "F.Paste" "F.Mask")
      (net 1 "GND") (pinfunction "SH") (pintype "passive"))
  )

  (footprint "sa800u-baseboard-hw-footprints:Conn_Molex_NanoFit_1053131202" (layer "F.Cu")
    (tedit 6215E733)
    (at 78.25 143 -90)
    (descr "Molex Nano-Fit Power Connectors, 2 Pins per row (http://www.molex.com/pdm_docs/sd/1053131202_sd.pdf)")
    (tags "connector Molex Nano-Fit NanoFit top entry 2.50mm horizontal")
    (property "Author" "Antmicro")
    (property "License" "Apache-2.0")
    (property "MPN" "1053131202")
    (property "Manufacturer" "Molex")
    (property "Sheetfile" "psu.kicad_sch")
    (property "Sheetname" "PSU")
    (attr through_hole)
    (fp_text reference "J10" (at 1.3 3.83 -90) (layer "F.SilkS")
      (effects (font (size 0.7 0.7) (thickness 0.15)) (justify left bottom))
    )
    (fp_text value "Conn_Molex_NanoFit_1053131202" (at -3.1 5.4 -90) (layer "F.Fab")
      (effects (font (size 0.7 0.7) (thickness 0.15)) (justify left bottom))
    )
    (fp_text user "${REFERENCE}" (at -3.1 7.4 -90) (layer "F.Fab") hide
      (effects (font (size 0.7 0.7) (thickness 0.15)) (justify left bottom))
    )
    (fp_text user "License: Apache-2.0" (at -3.1 8.6 -90) (layer "F.Fab") hide
      (effects (font (size 0.7 0.7) (thickness 0.15)) (justify left bottom))
    )
    (fp_text user "Author: Antmicro" (at -3.1 9.8 -90) (layer "F.Fab") hide
      (effects (font (size 0.7 0.7) (thickness 0.15)) (justify left bottom))
    )
    (fp_rect (start 1.4 -0.299) (end 1.899 0.299) (layer "F.SilkS") (width 0.15) (fill none))
    (fp_rect (start 1.4 2.2) (end 1.899 2.798) (layer "F.SilkS") (width 0.15) (fill none))
    (fp_rect (start 10.4 -1.7) (end 1.898 4.2) (layer "F.SilkS") (width 0.15) (fill none))
    (fp_circle (center 0 -1.25) (end 0.05 -1.25) (layer "F.SilkS") (width 0.15) (fill solid))
    (fp_rect (start -1.097 -2.216) (end 12.342 4.724) (layer "F.CrtYd") (width 0.05) (fill none))
    (fp_line (start -0.35 -1.71) (end -0.595 -1.465) (layer "F.Fab") (width 0.15))
    (fp_rect (start -0.597 -1.716) (end 11.842 4.224) (layer "F.Fab") (width 0.15) (fill none))
    (pad "" np_thru_hole circle (at 7.179 0 270) (size 1.7 1.7) (drill 1.7) (layers *.Cu *.Mask))
    (pad "" np_thru_hole circle (at 7.179 2.499 270) (size 1.7 1.7) (drill 1.7) (layers *.Cu *.Mask))
    (pad "1" thru_hole custom (at 0 0 270) (size 1.417157 1.417157) (drill 1.2) (layers *.Cu *.Mask)
      (net 152 "/PSU/AUX_VDD") (pintype "input")
      (options (clearance outline) (anchor circle))
      (primitives
        (gr_poly (pts
            (xy -0.85 -0.6)
            (xy 0.85 -0.6)
            (xy 0.85 0.6)
            (xy -0.45 0.6)
            (xy -0.85 0.2)
          ) (width 0.5) (fill yes))
      ))
    (pad "2" thru_hole oval (at 0 2.499 270) (size 2.2 1.7) (drill 1.2) (layers *.Cu *.Mask)
      (net 1 "GND") (pintype "input"))
  )

  (footprint "sa800u-baseboard-hw-footprints:R_0402_1005Metric" (layer "F.Cu")
    (tedit 5FD9C158)
    (at 134.388164 125.512952)
    (descr "Resistor SMD 0402")
    (tags "resistor SMD 0402")
    (property "Author" "Antmicro")
    (property "DNP" "DNP")
    (property "License" "Apache-2.0")
    (property "MPN" "CR0402-FX-1001GLF")
    (property "Manufacturer" "Bourns")
    (property "Sheetfile" "hdmi-converter.kicad_sch")
    (property "Sheetname" "HDMI converter")
    (property "Tolerance" "1%")
    (property "Val" "1k")
    (attr exclude_from_pos_files)
    (fp_text reference "R15" (at -4.056328 0.324096) (layer "F.SilkS")
      (effects (font (size 0.7 0.7) (thickness 0.15)) (justify left bottom))
    )
    (fp_text value "R_1k_0402" (at 0 1.4) (layer "F.Fab")
      (effects (font (size 0.7 0.7) (thickness 0.15)) (justify left bottom))
    )
    (fp_text user "Author: Antmicro" (at -0.95 4.169) (layer "F.Fab") hide
      (effects (font (size 0.7 0.7) (thickness 0.15)) (justify left bottom))
    )
    (fp_text user "License: Apache-2.0" (at -0.95 5.169) (layer "F.Fab") hide
      (effects (font (size 0.7 0.7) (thickness 0.15)) (justify left bottom))
    )
    (fp_text user "${REFERENCE}" (at -0.95 3.168) (layer "F.Fab") hide
      (effects (font (size 0.7 0.7) (thickness 0.15)) (justify left bottom))
    )
    (fp_rect (start -0.93 -0.47) (end 0.93 0.47) (layer "F.CrtYd") (width 0.05) (fill none))
    (fp_rect (start -0.5 -0.25) (end 0.5 0.25) (layer "F.Fab") (width 0.15) (fill none))
    (pad "1" smd roundrect (at -0.485 0) (size 0.59 0.64) (layers "F.Cu" "F.Paste" "F.Mask") (roundrect_rratio 0.25)
      (net 131 "3V3_SYS") (pintype "passive"))
    (pad "2" smd roundrect (at 0.485 0) (size 0.59 0.64) (layers "F.Cu" "F.Paste" "F.Mask") (roundrect_rratio 0.25)
      (net 289 "/HDMI converter/I2C_ADDR") (pintype "passive"))
  )

  (footprint "sa800u-baseboard-hw-footprints:R_0402_1005Metric" (layer "F.Cu")
    (tedit 5FD9C158)
    (at 134.388164 121.491425)
    (descr "Resistor SMD 0402")
    (tags "resistor SMD 0402")
    (property "Author" "Antmicro")
    (property "License" "Apache-2.0")
    (property "MPN" "CR0402-FX-4701GLF")
    (property "Manufacturer" "Bourns")
    (property "Sheetfile" "hdmi-converter.kicad_sch")
    (property "Sheetname" "HDMI converter")
    (property "Tolerance" "1%")
    (property "Val" "4k7")
    (attr smd)
    (fp_text reference "R19" (at -3.028164 0.388575) (layer "F.SilkS")
      (effects (font (size 0.7 0.7) (thickness 0.15)) (justify left bottom))
    )
    (fp_text value "R_4k7_0402" (at 0 1.4) (layer "F.Fab")
      (effects (font (size 0.7 0.7) (thickness 0.15)) (justify left bottom))
    )
    (fp_text user "${REFERENCE}" (at -0.95 3.168) (layer "F.Fab") hide
      (effects (font (size 0.7 0.7) (thickness 0.15)) (justify left bottom))
    )
    (fp_text user "License: Apache-2.0" (at -0.95 5.169) (layer "F.Fab") hide
      (effects (font (size 0.7 0.7) (thickness 0.15)) (justify left bottom))
    )
    (fp_text user "Author: Antmicro" (at -0.95 4.169) (layer "F.Fab") hide
      (effects (font (size 0.7 0.7) (thickness 0.15)) (justify left bottom))
    )
    (fp_rect (start -0.93 -0.47) (end 0.93 0.47) (layer "F.CrtYd") (width 0.05) (fill none))
    (fp_rect (start -0.5 -0.25) (end 0.5 0.25) (layer "F.Fab") (width 0.15) (fill none))
    (pad "1" smd roundrect (at -0.485 0) (size 0.59 0.64) (layers "F.Cu" "F.Paste" "F.Mask") (roundrect_rratio 0.25)
      (net 131 "3V3_SYS") (pintype "passive"))
    (pad "2" smd roundrect (at 0.485 0) (size 0.59 0.64) (layers "F.Cu" "F.Paste" "F.Mask") (roundrect_rratio 0.25)
      (net 287 "/HDMI converter/LT9611_SCL") (pintype "passive"))
  )

  (footprint "sa800u-baseboard-hw-footprints:R_0402_1005Metric" (layer "F.Cu")
    (tedit 5FD9C158)
    (at 134.388164 122.491424)
    (descr "Resistor SMD 0402")
    (tags "resistor SMD 0402")
    (property "Author" "Antmicro")
    (property "License" "Apache-2.0")
    (property "MPN" "CR0402-FX-4701GLF")
    (property "Manufacturer" "Bourns")
    (property "Sheetfile" "hdmi-converter.kicad_sch")
    (property "Sheetname" "HDMI converter")
    (property "Tolerance" "1%")
    (property "Val" "4k7")
    (attr smd)
    (fp_text reference "R18" (at -3.028164 0.388575) (layer "F.SilkS")
      (effects (font (size 0.7 0.7) (thickness 0.15)) (justify left bottom))
    )
    (fp_text value "R_4k7_0402" (at 0 1.4) (layer "F.Fab")
      (effects (font (size 0.7 0.7) (thickness 0.15)) (justify left bottom))
    )
    (fp_text user "${REFERENCE}" (at -0.95 3.168) (layer "F.Fab") hide
      (effects (font (size 0.7 0.7) (thickness 0.15)) (justify left bottom))
    )
    (fp_text user "License: Apache-2.0" (at -0.95 5.169) (layer "F.Fab") hide
      (effects (font (size 0.7 0.7) (thickness 0.15)) (justify left bottom))
    )
    (fp_text user "Author: Antmicro" (at -0.95 4.169) (layer "F.Fab") hide
      (effects (font (size 0.7 0.7) (thickness 0.15)) (justify left bottom))
    )
    (fp_rect (start -0.93 -0.47) (end 0.93 0.47) (layer "F.CrtYd") (width 0.05) (fill none))
    (fp_rect (start -0.5 -0.25) (end 0.5 0.25) (layer "F.Fab") (width 0.15) (fill none))
    (pad "1" smd roundrect (at -0.485 0) (size 0.59 0.64) (layers "F.Cu" "F.Paste" "F.Mask") (roundrect_rratio 0.25)
      (net 131 "3V3_SYS") (pintype "passive"))
    (pad "2" smd roundrect (at 0.485 0) (size 0.59 0.64) (layers "F.Cu" "F.Paste" "F.Mask") (roundrect_rratio 0.25)
      (net 288 "/HDMI converter/LT9611_SDA") (pintype "passive"))
  )

  (footprint "sa800u-baseboard-hw-footprints:R_0402_1005Metric" (layer "F.Cu")
    (tedit 5FD9C158)
    (at 134.388164 123.491425)
    (descr "Resistor SMD 0402")
    (tags "resistor SMD 0402")
    (property "Author" "Antmicro")
    (property "License" "Apache-2.0")
    (property "MPN" "CR0402-FX-4701GLF")
    (property "Manufacturer" "Bourns")
    (property "Sheetfile" "hdmi-converter.kicad_sch")
    (property "Sheetname" "HDMI converter")
    (property "Tolerance" "1%")
    (property "Val" "4k7")
    (attr smd)
    (fp_text reference "R20" (at -3.028164 0.388575) (layer "F.SilkS")
      (effects (font (size 0.7 0.7) (thickness 0.15)) (justify left bottom))
    )
    (fp_text value "R_4k7_0402" (at 0 1.4) (layer "F.Fab")
      (effects (font (size 0.7 0.7) (thickness 0.15)) (justify left bottom))
    )
    (fp_text user "Author: Antmicro" (at -0.95 4.169) (layer "F.Fab") hide
      (effects (font (size 0.7 0.7) (thickness 0.15)) (justify left bottom))
    )
    (fp_text user "${REFERENCE}" (at -0.95 3.168) (layer "F.Fab") hide
      (effects (font (size 0.7 0.7) (thickness 0.15)) (justify left bottom))
    )
    (fp_text user "License: Apache-2.0" (at -0.95 5.169) (layer "F.Fab") hide
      (effects (font (size 0.7 0.7) (thickness 0.15)) (justify left bottom))
    )
    (fp_rect (start -0.93 -0.47) (end 0.93 0.47) (layer "F.CrtYd") (width 0.05) (fill none))
    (fp_rect (start -0.5 -0.25) (end 0.5 0.25) (layer "F.Fab") (width 0.15) (fill none))
    (pad "1" smd roundrect (at -0.485 0) (size 0.59 0.64) (layers "F.Cu" "F.Paste" "F.Mask") (roundrect_rratio 0.25)
      (net 131 "3V3_SYS") (pintype "passive"))
    (pad "2" smd roundrect (at 0.485 0) (size 0.59 0.64) (layers "F.Cu" "F.Paste" "F.Mask") (roundrect_rratio 0.25)
      (net 284 "/HDMI converter/LT9611_INTO_GPIO5") (pintype "passive"))
  )

  (footprint "sa800u-baseboard-hw-footprints:C_0402_1005Metric" (layer "F.Cu")
    (tedit 616D63CF)
    (at 134.4 120.5 180)
    (descr "Capacitor SMD 0402")
    (tags "capacitor SMD 0402")
    (property "Author" "Antmicro")
    (property "Dielectric" "")
    (property "License" "Apache-2.0")
    (property "MPN" "C1005X6S1A105K050BC")
    (property "Manufacturer" "TDK")
    (property "Sheetfile" "hdmi-converter.kicad_sch")
    (property "Sheetname" "HDMI converter")
    (property "Val" "1u")
    (property "Voltage" "")
    (attr smd)
    (fp_text reference "C34" (at 3.07 -0.42 180) (layer "F.SilkS")
      (effects (font (size 0.7 0.7) (thickness 0.15)) (justify left bottom))
    )
    (fp_text value "C_1u_0402" (at 0 1.4 180) (layer "F.Fab")
      (effects (font (size 0.7 0.7) (thickness 0.15)) (justify left bottom))
    )
    (fp_text user "Author: Antmicro" (at -0.932 4.17 180) (layer "F.Fab") hide
      (effects (font (size 0.7 0.7) (thickness 0.15)) (justify left bottom))
    )
    (fp_text user "License: Apache-2.0" (at -0.932 5.17 180) (layer "F.Fab") hide
      (effects (font (size 0.7 0.7) (thickness 0.15)) (justify left bottom))
    )
    (fp_text user "${REFERENCE}" (at -0.932 3.168 180) (layer "F.Fab") hide
      (effects (font (size 0.7 0.7) (thickness 0.15)) (justify left bottom))
    )
    (fp_rect (start -0.94 -0.47) (end 0.94 0.47) (layer "F.CrtYd") (width 0.05) (fill none))
    (fp_rect (start -0.499 -0.249) (end 0.499 0.249) (layer "F.Fab") (width 0.15) (fill none))
    (pad "1" smd roundrect (at -0.484 0 180) (size 0.59 0.64) (layers "F.Cu" "F.Paste" "F.Mask") (roundrect_rratio 0.25)
      (net 186 "/HDMI converter/LT9611_RST_N") (pintype "passive"))
    (pad "2" smd roundrect (at 0.484 0 180) (size 0.59 0.64) (layers "F.Cu" "F.Paste" "F.Mask") (roundrect_rratio 0.25)
      (net 1 "GND") (pintype "passive"))
  )

  (footprint "sa800u-baseboard-hw-footprints:R_0402_1005Metric" (layer "F.Cu")
    (tedit 5FD9C158)
    (at 134.388164 124.512952 180)
    (descr "Resistor SMD 0402")
    (tags "resistor SMD 0402")
    (property "Author" "Antmicro")
    (property "Current" "1A")
    (property "License" "Apache-2.0")
    (property "MPN" "ERJ2GE0R00X")
    (property "Manufacturer" "Panasonic")
    (property "Sheetfile" "hdmi-converter.kicad_sch")
    (property "Sheetname" "HDMI converter")
    (property "Tolerance" "")
    (property "Val" "0R")
    (attr smd)
    (fp_text reference "R16" (at 4.058164 -0.417048 180) (layer "F.SilkS")
      (effects (font (size 0.7 0.7) (thickness 0.15)) (justify left bottom))
    )
    (fp_text value "R_0R_0402" (at 0 1.4 180) (layer "F.Fab")
      (effects (font (size 0.7 0.7) (thickness 0.15)) (justify left bottom))
    )
    (fp_text user "Author: Antmicro" (at -0.95 4.169 180) (layer "F.Fab") hide
      (effects (font (size 0.7 0.7) (thickness 0.15)) (justify left bottom))
    )
    (fp_text user "License: Apache-2.0" (at -0.95 5.169 180) (layer "F.Fab") hide
      (effects (font (size 0.7 0.7) (thickness 0.15)) (justify left bottom))
    )
    (fp_text user "${REFERENCE}" (at -0.95 3.168 180) (layer "F.Fab") hide
      (effects (font (size 0.7 0.7) (thickness 0.15)) (justify left bottom))
    )
    (fp_rect (start -0.93 -0.47) (end 0.93 0.47) (layer "F.CrtYd") (width 0.05) (fill none))
    (fp_rect (start -0.5 -0.25) (end 0.5 0.25) (layer "F.Fab") (width 0.15) (fill none))
    (pad "1" smd roundrect (at -0.485 0 180) (size 0.59 0.64) (layers "F.Cu" "F.Paste" "F.Mask") (roundrect_rratio 0.25)
      (net 289 "/HDMI converter/I2C_ADDR") (pintype "passive"))
    (pad "2" smd roundrect (at 0.485 0 180) (size 0.59 0.64) (layers "F.Cu" "F.Paste" "F.Mask") (roundrect_rratio 0.25)
      (net 1 "GND") (pintype "passive"))
  )

  (footprint "sa800u-baseboard-hw-footprints:R_0402_1005Metric" (layer "F.Cu")
    (tedit 5FD9C158)
    (at 150.8 138)
    (descr "Resistor SMD 0402")
    (tags "resistor SMD 0402")
    (property "Author" "Antmicro")
    (property "License" "Apache-2.0")
    (property "MPN" "CR0402-FX-1002GLF")
    (property "Manufacturer" "Bourns")
    (property "Sheetfile" "som.kicad_sch")
    (property "Sheetname" "SoM")
    (property "Tolerance" "1%")
    (property "Val" "10k")
    (attr smd)
    (fp_text reference "R77" (at -1.19 1.3) (layer "F.SilkS")
      (effects (font (size 0.7 0.7) (thickness 0.15)) (justify left bottom))
    )
    (fp_text value "R_10k_0402" (at 0 1.4) (layer "F.Fab")
      (effects (font (size 0.7 0.7) (thickness 0.15)) (justify left bottom))
    )
    (fp_text user "Author: Antmicro" (at -0.95 4.169) (layer "F.Fab") hide
      (effects (font (size 0.7 0.7) (thickness 0.15)) (justify left bottom))
    )
    (fp_text user "License: Apache-2.0" (at -0.95 5.169) (layer "F.Fab") hide
      (effects (font (size 0.7 0.7) (thickness 0.15)) (justify left bottom))
    )
    (fp_text user "${REFERENCE}" (at -0.95 3.168) (layer "F.Fab") hide
      (effects (font (size 0.7 0.7) (thickness 0.15)) (justify left bottom))
    )
    (fp_rect (start -0.93 -0.47) (end 0.93 0.47) (layer "F.CrtYd") (width 0.05) (fill none))
    (fp_rect (start -0.5 -0.25) (end 0.5 0.25) (layer "F.Fab") (width 0.15) (fill none))
    (pad "1" smd roundrect (at -0.485 0) (size 0.59 0.64) (layers "F.Cu" "F.Paste" "F.Mask") (roundrect_rratio 0.25)
      (net 385 "Net-(Q5-Pad3)") (pintype "passive"))
    (pad "2" smd roundrect (at 0.485 0) (size 0.59 0.64) (layers "F.Cu" "F.Paste" "F.Mask") (roundrect_rratio 0.25)
      (net 371 "Net-(D14-Pad2)") (pintype "passive"))
  )

  (footprint "sa800u-baseboard-hw-footprints:SOT-23-3" (layer "F.Cu")
    (tedit 5D5D4314)
    (at 84.4 104.7 -90)
    (property "Author" "Antmicro")
    (property "License" "Apache-2.0")
    (property "MPN" "BSS84")
    (property "Manufacturer" "ON Semiconductor")
    (property "Sheetfile" "psu.kicad_sch")
    (property "Sheetname" "PSU")
    (attr smd)
    (fp_text reference "Q13" (at 1.68 -0.32) (layer "F.SilkS")
      (effects (font (size 0.7 0.7) (thickness 0.15)) (justify left bottom))
    )
    (fp_text value "BSS84" (at -1.9 2.7 -90) (layer "F.Fab")
      (effects (font (size 0.7 0.7) (thickness 0.15)) (justify left bottom))
    )
    (fp_text user "License: Apache-2.0" (at -1.8 6.8 -90) (layer "F.Fab") hide
      (effects (font (size 0.7 0.7) (thickness 0.15)) (justify left bottom))
    )
    (fp_text user "${REFERENCE}" (at -1.837 4 -90) (layer "F.Fab") hide
      (effects (font (size 0.7 0.7) (thickness 0.15)) (justify left bottom))
    )
    (fp_text user "Author: Antmicro" (at -1.837 5.3 -90) (layer "F.Fab") hide
      (effects (font (size 0.7 0.7) (thickness 0.15)) (justify left bottom))
    )
    (fp_line (start 0.7 0.4) (end 0.7 1.5) (layer "F.SilkS") (width 0.15))
    (fp_line (start 0.7 -1.5) (end -0.7 -1.5) (layer "F.SilkS") (width 0.15))
    (fp_line (start -0.85 -1.35) (end -0.7 -1.5) (layer "F.SilkS") (width 0.15))
    (fp_line (start -1.45 -1.35) (end -0.85 -1.35) (layer "F.SilkS") (width 0.15))
    (fp_line (start 0.7 1.5) (end -0.7 1.5) (layer "F.SilkS") (width 0.15))
    (fp_line (start 0.7 -0.4) (end 0.7 -1.5) (layer "F.SilkS") (width 0.15))
    (fp_line (start -0.7 1.5) (end -0.7 1.35) (layer "F.SilkS") (width 0.15))
    (fp_line (start -0.85 0.5) (end -0.85 -0.5) (layer "F.CrtYd") (width 0.05))
    (fp_line (start -0.9 -1.6) (end -0.9 -1.4) (layer "F.CrtYd") (width 0.05))
    (fp_line (start -1.75 0.5) (end -0.85 0.5) (layer "F.CrtYd") (width 0.05))
    (fp_line (start 0.85 0.45) (end 0.85 1.65) (layer "F.CrtYd") (width 0.05))
    (fp_line (start 0.825 -1.6) (end 0.825 -0.45) (layer "F.CrtYd") (width 0.05))
    (fp_line (start 1.75 0.45) (end 0.85 0.45) (layer "F.CrtYd") (width 0.05))
    (fp_line (start 0.85 1.65) (end -0.85 1.65) (layer "F.CrtYd") (width 0.05))
    (fp_line (start -0.85 1.65) (end -0.85 1.4) (layer "F.CrtYd") (width 0.05))
    (fp_line (start -0.85 1.4) (end -1.75 1.4) (layer "F.CrtYd") (width 0.05))
    (fp_line (start -0.9 -1.6) (end 0.825 -1.6) (layer "F.CrtYd") (width 0.05))
    (fp_line (start -1.75 1.4) (end -1.75 0.5) (layer "F.CrtYd") (width 0.05))
    (fp_line (start -1.75 -0.5) (end -1.75 -1.4) (layer "F.CrtYd") (width 0.05))
    (fp_line (start -0.9 -1.4) (end -1.75 -1.4) (layer "F.CrtYd") (width 0.05))
    (fp_line (start 0.825 -0.45) (end 1.75 -0.45) (layer "F.CrtYd") (width 0.05))
    (fp_line (start -0.85 -0.5) (end -1.75 -0.5) (layer "F.CrtYd") (width 0.05))
    (fp_line (start 1.75 -0.45) (end 1.75 0.45) (layer "F.CrtYd") (width 0.05))
    (fp_line (start -0.712 1.519) (end 0.688 1.519) (layer "F.Fab") (width 0.15))
    (fp_line (start -0.437 -1.526) (end 0.688 -1.526) (layer "F.Fab") (width 0.15))
    (fp_line (start -0.437 -1.526) (end -0.712 -1.325) (layer "F.Fab") (width 0.15))
    (fp_line (start 0.688 1.519) (end 0.688 -1.52) (layer "F.Fab") (width 0.15))
    (fp_line (start -0.712 -1.325) (end -0.712 1.523) (layer "F.Fab") (width 0.15))
    (pad "1" smd roundrect (at -1.1 -0.951 270) (size 1 0.6) (layers "F.Cu" "F.Paste" "F.Mask") (roundrect_rratio 0.15)
      (net 340 "/PSU/POE_VALID") (pinfunction "G") (pintype "bidirectional"))
    (pad "2" smd roundrect (at -1.1 0.949 270) (size 1 0.6) (layers "F.Cu" "F.Paste" "F.Mask") (roundrect_rratio 0.15)
      (net 1 "GND") (pinfunction "D") (pintype "bidirectional"))
    (pad "3" smd roundrect (at 1.1 -0.0005 270) (size 1 0.6) (layers "F.Cu" "F.Paste" "F.Mask") (roundrect_rratio 0.15)
      (net 347 "Net-(Q13-Pad3)") (pinfunction "S") (pintype "bidirectional"))
  )

  (footprint "sa800u-baseboard-hw-footprints:D_0201_0603Metric" (layer "F.Cu")
    (tedit 62026EA2)
    (at 91.1 138.4)
    (property "Author" "Antmicro")
    (property "License" "Apache-2.0")
    (property "MPN" "PESD18VF1BSFYL")
    (property "Manufacturer" "Nexperia")
    (property "Sheetfile" "usb-pd.kicad_sch")
    (property "Sheetname" "USB-PD")
    (attr smd)
    (fp_text reference "D33" (at -1.03 -0.43) (layer "F.SilkS")
      (effects (font (size 0.7 0.7) (thickness 0.15)) (justify left bottom))
    )
    (fp_text value "PESD18VF1BSFYL" (at 0 1.25) (layer "F.Fab")
      (effects (font (size 0.7 0.7) (thickness 0.15)) (justify left bottom))
    )
    (fp_text user "License: Apache-2.0" (at -0.72 5.281) (layer "F.Fab") hide
      (effects (font (size 0.7 0.7) (thickness 0.15)) (justify left bottom))
    )
    (fp_text user "${REFERENCE}" (at -0.72 2.882) (layer "F.Fab") hide
      (effects (font (size 0.7 0.7) (thickness 0.15)) (justify left bottom))
    )
    (fp_text user "Author: Antmicro" (at -0.72 4.081) (layer "F.Fab") hide
      (effects (font (size 0.7 0.7) (thickness 0.15)) (justify left bottom))
    )
    (fp_line (start -0.025 -0.201) (end -0.025 0.199) (layer "F.SilkS") (width 0.12))
    (fp_rect (start -0.5 -0.3) (end 0.5 0.3) (layer "F.CrtYd") (width 0.05) (fill none))
    (fp_line (start -0.32 -0.172) (end 0.32 -0.172) (layer "F.Fab") (width 0.15))
    (fp_line (start -0.32 0.17) (end 0.32 0.17) (layer "F.Fab") (width 0.15))
    (fp_line (start 0.32 -0.172) (end 0.32 0.17) (layer "F.Fab") (width 0.15))
    (fp_line (start -0.32 -0.172) (end -0.32 0.17) (layer "F.Fab") (width 0.15))
    (pad "1" smd roundrect (at -0.282 0) (size 0.38 0.4) (layers "F.Cu" "F.Paste" "F.Mask") (roundrect_rratio 0.05)
      (net 144 "/USB-PD/PD_CC2") (pinfunction "1") (pintype "input"))
    (pad "2" smd rect (at 0.28 0) (size 0.38 0.4) (layers "F.Cu" "F.Paste" "F.Mask")
      (net 1 "GND") (pinfunction "2") (pintype "input"))
  )

  (footprint "sa800u-baseboard-hw-footprints:D_0201_0603Metric" (layer "F.Cu")
    (tedit 62026EA2)
    (at 90.1 139.4 180)
    (property "Author" "Antmicro")
    (property "License" "Apache-2.0")
    (property "MPN" "PESD18VF1BSFYL")
    (property "Manufacturer" "Nexperia")
    (property "Sheetfile" "usb-pd.kicad_sch")
    (property "Sheetname" "USB-PD")
    (attr smd)
    (fp_text reference "D34" (at -0.4 -0.24 180) (layer "F.SilkS")
      (effects (font (size 0.7 0.7) (thickness 0.15)) (justify left bottom))
    )
    (fp_text value "PESD18VF1BSFYL" (at 0 1.25 180) (layer "F.Fab")
      (effects (font (size 0.7 0.7) (thickness 0.15)) (justify left bottom))
    )
    (fp_text user "Author: Antmicro" (at -0.72 4.081 180) (layer "F.Fab") hide
      (effects (font (size 0.7 0.7) (thickness 0.15)) (justify left bottom))
    )
    (fp_text user "License: Apache-2.0" (at -0.72 5.281 180) (layer "F.Fab") hide
      (effects (font (size 0.7 0.7) (thickness 0.15)) (justify left bottom))
    )
    (fp_text user "${REFERENCE}" (at -0.72 2.882 180) (layer "F.Fab") hide
      (effects (font (size 0.7 0.7) (thickness 0.15)) (justify left bottom))
    )
    (fp_line (start -0.025 -0.201) (end -0.025 0.199) (layer "F.SilkS") (width 0.12))
    (fp_rect (start -0.5 -0.3) (end 0.5 0.3) (layer "F.CrtYd") (width 0.05) (fill none))
    (fp_line (start -0.32 -0.172) (end 0.32 -0.172) (layer "F.Fab") (width 0.15))
    (fp_line (start 0.32 -0.172) (end 0.32 0.17) (layer "F.Fab") (width 0.15))
    (fp_line (start -0.32 0.17) (end 0.32 0.17) (layer "F.Fab") (width 0.15))
    (fp_line (start -0.32 -0.172) (end -0.32 0.17) (layer "F.Fab") (width 0.15))
    (pad "1" smd roundrect (at -0.282 0 180) (size 0.38 0.4) (layers "F.Cu" "F.Paste" "F.Mask") (roundrect_rratio 0.05)
      (net 143 "/USB-PD/PD_CC1") (pinfunction "1") (pintype "input"))
    (pad "2" smd rect (at 0.28 0 180) (size 0.38 0.4) (layers "F.Cu" "F.Paste" "F.Mask")
      (net 1 "GND") (pinfunction "2") (pintype "input"))
  )

  (footprint "sa800u-baseboard-hw-footprints:D_0201_0603Metric" (layer "F.Cu")
    (tedit 62026EA2)
    (at 151.65 107.95)
    (property "Author" "Antmicro")
    (property "License" "Apache-2.0")
    (property "MPN" "PESD2V5Y1BSFYL")
    (property "Manufacturer" "Nexperia")
    (property "Sheetfile" "som.kicad_sch")
    (property "Sheetname" "SoM")
    (attr smd)
    (fp_text reference "D20" (at 0.48 0.2) (layer "F.SilkS")
      (effects (font (size 0.7 0.7) (thickness 0.15)) (justify left bottom))
    )
    (fp_text value "PESD2V5Y1BSFYL" (at 0 1.25) (layer "F.Fab")
      (effects (font (size 0.7 0.7) (thickness 0.15)) (justify left bottom))
    )
    (fp_text user "Author: Antmicro" (at -0.72 4.081) (layer "F.Fab") hide
      (effects (font (size 0.7 0.7) (thickness 0.15)) (justify left bottom))
    )
    (fp_text user "License: Apache-2.0" (at -0.72 5.281) (layer "F.Fab") hide
      (effects (font (size 0.7 0.7) (thickness 0.15)) (justify left bottom))
    )
    (fp_text user "${REFERENCE}" (at -0.72 2.882) (layer "F.Fab") hide
      (effects (font (size 0.7 0.7) (thickness 0.15)) (justify left bottom))
    )
    (fp_line (start -0.025 -0.201) (end -0.025 0.199) (layer "F.SilkS") (width 0.12))
    (fp_rect (start -0.5 -0.3) (end 0.5 0.3) (layer "F.CrtYd") (width 0.05) (fill none))
    (fp_line (start -0.32 -0.172) (end -0.32 0.17) (layer "F.Fab") (width 0.15))
    (fp_line (start -0.32 -0.172) (end 0.32 -0.172) (layer "F.Fab") (width 0.15))
    (fp_line (start -0.32 0.17) (end 0.32 0.17) (layer "F.Fab") (width 0.15))
    (fp_line (start 0.32 -0.172) (end 0.32 0.17) (layer "F.Fab") (width 0.15))
    (pad "1" smd roundrect (at -0.282 0) (size 0.38 0.4) (layers "F.Cu" "F.Paste" "F.Mask") (roundrect_rratio 0.05)
      (net 343 "/SoM/VOL_DOWN_R") (pinfunction "1") (pintype "input"))
    (pad "2" smd rect (at 0.28 0) (size 0.38 0.4) (layers "F.Cu" "F.Paste" "F.Mask")
      (net 1 "GND") (pinfunction "2") (pintype "input"))
  )

  (footprint "sa800u-baseboard-hw-footprints:D_0201_0603Metric" (layer "F.Cu")
    (tedit 62026EA2)
    (at 151.9 95.9)
    (property "Author" "Antmicro")
    (property "License" "Apache-2.0")
    (property "MPN" "PESD2V5Y1BSFYL")
    (property "Manufacturer" "Nexperia")
    (property "Sheetfile" "som.kicad_sch")
    (property "Sheetname" "SoM")
    (attr smd)
    (fp_text reference "D17" (at 0.48 0.18) (layer "F.SilkS")
      (effects (font (size 0.7 0.7) (thickness 0.15)) (justify left bottom))
    )
    (fp_text value "PESD2V5Y1BSFYL" (at 0 1.25) (layer "F.Fab")
      (effects (font (size 0.7 0.7) (thickness 0.15)) (justify left bottom))
    )
    (fp_text user "License: Apache-2.0" (at -0.72 5.281) (layer "F.Fab") hide
      (effects (font (size 0.7 0.7) (thickness 0.15)) (justify left bottom))
    )
    (fp_text user "Author: Antmicro" (at -0.72 4.081) (layer "F.Fab") hide
      (effects (font (size 0.7 0.7) (thickness 0.15)) (justify left bottom))
    )
    (fp_text user "${REFERENCE}" (at -0.72 2.882) (layer "F.Fab") hide
      (effects (font (size 0.7 0.7) (thickness 0.15)) (justify left bottom))
    )
    (fp_line (start -0.025 -0.201) (end -0.025 0.199) (layer "F.SilkS") (width 0.12))
    (fp_rect (start -0.5 -0.3) (end 0.5 0.3) (layer "F.CrtYd") (width 0.05) (fill none))
    (fp_line (start 0.32 -0.172) (end 0.32 0.17) (layer "F.Fab") (width 0.15))
    (fp_line (start -0.32 -0.172) (end -0.32 0.17) (layer "F.Fab") (width 0.15))
    (fp_line (start -0.32 -0.172) (end 0.32 -0.172) (layer "F.Fab") (width 0.15))
    (fp_line (start -0.32 0.17) (end 0.32 0.17) (layer "F.Fab") (width 0.15))
    (pad "1" smd roundrect (at -0.282 0) (size 0.38 0.4) (layers "F.Cu" "F.Paste" "F.Mask") (roundrect_rratio 0.05)
      (net 344 "/SoM/HOME_KEY_R") (pinfunction "1") (pintype "input"))
    (pad "2" smd rect (at 0.28 0) (size 0.38 0.4) (layers "F.Cu" "F.Paste" "F.Mask")
      (net 1 "GND") (pinfunction "2") (pintype "input"))
  )

  (footprint "sa800u-baseboard-hw-footprints:D_0201_0603Metric" (layer "F.Cu")
    (tedit 62026EA2)
    (at 151.63 101.9)
    (property "Author" "Antmicro")
    (property "License" "Apache-2.0")
    (property "MPN" "PESD2V5Y1BSFYL")
    (property "Manufacturer" "Nexperia")
    (property "Sheetfile" "som.kicad_sch")
    (property "Sheetname" "SoM")
    (attr smd)
    (fp_text reference "D18" (at 0.42 0.25) (layer "F.SilkS")
      (effects (font (size 0.7 0.7) (thickness 0.15)) (justify left bottom))
    )
    (fp_text value "PESD2V5Y1BSFYL" (at 0 1.25) (layer "F.Fab")
      (effects (font (size 0.7 0.7) (thickness 0.15)) (justify left bottom))
    )
    (fp_text user "${REFERENCE}" (at -0.72 2.882) (layer "F.Fab") hide
      (effects (font (size 0.7 0.7) (thickness 0.15)) (justify left bottom))
    )
    (fp_text user "Author: Antmicro" (at -0.72 4.081) (layer "F.Fab") hide
      (effects (font (size 0.7 0.7) (thickness 0.15)) (justify left bottom))
    )
    (fp_text user "License: Apache-2.0" (at -0.72 5.281) (layer "F.Fab") hide
      (effects (font (size 0.7 0.7) (thickness 0.15)) (justify left bottom))
    )
    (fp_line (start -0.025 -0.201) (end -0.025 0.199) (layer "F.SilkS") (width 0.12))
    (fp_rect (start -0.5 -0.3) (end 0.5 0.3) (layer "F.CrtYd") (width 0.05) (fill none))
    (fp_line (start -0.32 -0.172) (end 0.32 -0.172) (layer "F.Fab") (width 0.15))
    (fp_line (start 0.32 -0.172) (end 0.32 0.17) (layer "F.Fab") (width 0.15))
    (fp_line (start -0.32 0.17) (end 0.32 0.17) (layer "F.Fab") (width 0.15))
    (fp_line (start -0.32 -0.172) (end -0.32 0.17) (layer "F.Fab") (width 0.15))
    (pad "1" smd roundrect (at -0.282 0) (size 0.38 0.4) (layers "F.Cu" "F.Paste" "F.Mask") (roundrect_rratio 0.05)
      (net 345 "/SoM/VOL_UP_R") (pinfunction "1") (pintype "input"))
    (pad "2" smd rect (at 0.28 0) (size 0.38 0.4) (layers "F.Cu" "F.Paste" "F.Mask")
      (net 1 "GND") (pinfunction "2") (pintype "input"))
  )

  (footprint "sa800u-baseboard-hw-footprints:D_0201_0603Metric" (layer "F.Cu")
    (tedit 62026EA2)
    (at 151.65 113.9)
    (property "Author" "Antmicro")
    (property "License" "Apache-2.0")
    (property "MPN" "PESD2V5Y1BSFYL")
    (property "Manufacturer" "Nexperia")
    (property "Sheetfile" "som.kicad_sch")
    (property "Sheetname" "SoM")
    (attr smd)
    (fp_text reference "D19" (at -0.66 1.18) (layer "F.SilkS")
      (effects (font (size 0.7 0.7) (thickness 0.15)) (justify left bottom))
    )
    (fp_text value "PESD2V5Y1BSFYL" (at 0 1.25) (layer "F.Fab")
      (effects (font (size 0.7 0.7) (thickness 0.15)) (justify left bottom))
    )
    (fp_text user "${REFERENCE}" (at -0.72 2.882) (layer "F.Fab") hide
      (effects (font (size 0.7 0.7) (thickness 0.15)) (justify left bottom))
    )
    (fp_text user "Author: Antmicro" (at -0.72 4.081) (layer "F.Fab") hide
      (effects (font (size 0.7 0.7) (thickness 0.15)) (justify left bottom))
    )
    (fp_text user "License: Apache-2.0" (at -0.72 5.281) (layer "F.Fab") hide
      (effects (font (size 0.7 0.7) (thickness 0.15)) (justify left bottom))
    )
    (fp_line (start -0.025 -0.201) (end -0.025 0.199) (layer "F.SilkS") (width 0.12))
    (fp_rect (start -0.5 -0.3) (end 0.5 0.3) (layer "F.CrtYd") (width 0.05) (fill none))
    (fp_line (start -0.32 -0.172) (end 0.32 -0.172) (layer "F.Fab") (width 0.15))
    (fp_line (start -0.32 -0.172) (end -0.32 0.17) (layer "F.Fab") (width 0.15))
    (fp_line (start -0.32 0.17) (end 0.32 0.17) (layer "F.Fab") (width 0.15))
    (fp_line (start 0.32 -0.172) (end 0.32 0.17) (layer "F.Fab") (width 0.15))
    (pad "1" smd roundrect (at -0.282 0) (size 0.38 0.4) (layers "F.Cu" "F.Paste" "F.Mask") (roundrect_rratio 0.05)
      (net 346 "/SoM/PWR_R") (pinfunction "1") (pintype "input"))
    (pad "2" smd rect (at 0.28 0) (size 0.38 0.4) (layers "F.Cu" "F.Paste" "F.Mask")
      (net 1 "GND") (pinfunction "2") (pintype "input"))
  )

  (footprint "sa800u-baseboard-hw-footprints:C_0402_1005Metric" (layer "F.Cu")
    (tedit 616D63CF)
    (at 97 101.35 -90)
    (descr "Capacitor SMD 0402")
    (tags "capacitor SMD 0402")
    (property "Author" "Antmicro")
    (property "DNP" "DNP")
    (property "Dielectric" "")
    (property "License" "Apache-2.0")
    (property "MPN" "GRM155R61A475MEAAD")
    (property "Manufacturer" "Murata")
    (property "Sheetfile" "ethernet-controller.kicad_sch")
    (property "Sheetname" "Ethernet Controller")
    (property "Val" "4u7")
    (property "Voltage" "")
    (attr exclude_from_pos_files)
    (fp_text reference "C10" (at -0.87 -0.38 -90) (layer "F.SilkS")
      (effects (font (size 0.7 0.7) (thickness 0.15)) (justify left bottom))
    )
    (fp_text value "C_4u7_0402" (at 0 1.4 -90) (layer "F.Fab")
      (effects (font (size 0.7 0.7) (thickness 0.15)) (justify left bottom))
    )
    (fp_text user "License: Apache-2.0" (at -0.932 5.17 -90) (layer "F.Fab") hide
      (effects (font (size 0.7 0.7) (thickness 0.15)) (justify left bottom))
    )
    (fp_text user "${REFERENCE}" (at -0.932 3.168 -90) (layer "F.Fab") hide
      (effects (font (size 0.7 0.7) (thickness 0.15)) (justify left bottom))
    )
    (fp_text user "Author: Antmicro" (at -0.932 4.17 -90) (layer "F.Fab") hide
      (effects (font (size 0.7 0.7) (thickness 0.15)) (justify left bottom))
    )
    (fp_rect (start -0.94 -0.47) (end 0.94 0.47) (layer "F.CrtYd") (width 0.05) (fill none))
    (fp_rect (start -0.499 -0.249) (end 0.499 0.249) (layer "F.Fab") (width 0.15) (fill none))
    (pad "1" smd roundrect (at -0.484 0 270) (size 0.59 0.64) (layers "F.Cu" "F.Paste" "F.Mask") (roundrect_rratio 0.25)
      (net 177 "/Ethernet Controller/ETH_3V3") (pintype "passive"))
    (pad "2" smd roundrect (at 0.484 0 270) (size 0.59 0.64) (layers "F.Cu" "F.Paste" "F.Mask") (roundrect_rratio 0.25)
      (net 1 "GND") (pintype "passive"))
  )

  (footprint "sa800u-baseboard-hw-footprints:C_0402_1005Metric" (layer "F.Cu")
    (tedit 616D63CF)
    (at 115.11 93.8 -90)
    (descr "Capacitor SMD 0402")
    (tags "capacitor SMD 0402")
    (property "Author" "Antmicro")
    (property "Dielectric" "X5R")
    (property "License" "Apache-2.0")
    (property "MPN" "GRM155R61H104KE14D")
    (property "Manufacturer" "Murata")
    (property "Sheetfile" "camera-interface.kicad_sch")
    (property "Sheetname" "Camera Interface")
    (property "Val" "100n")
    (property "Voltage" "50V")
    (attr smd)
    (fp_text reference "C109" (at 1.26 -1.27 -90) (layer "F.SilkS")
      (effects (font (size 0.7 0.7) (thickness 0.15)) (justify left bottom))
    )
    (fp_text value "C_100n_0402" (at 0 1.4 -90) (layer "F.Fab")
      (effects (font (size 0.7 0.7) (thickness 0.15)) (justify left bottom))
    )
    (fp_text user "Author: Antmicro" (at -0.932 4.17 -90) (layer "F.Fab") hide
      (effects (font (size 0.7 0.7) (thickness 0.15)) (justify left bottom))
    )
    (fp_text user "${REFERENCE}" (at -0.932 3.168 -90) (layer "F.Fab") hide
      (effects (font (size 0.7 0.7) (thickness 0.15)) (justify left bottom))
    )
    (fp_text user "License: Apache-2.0" (at -0.932 5.17 -90) (layer "F.Fab") hide
      (effects (font (size 0.7 0.7) (thickness 0.15)) (justify left bottom))
    )
    (fp_rect (start -0.94 -0.47) (end 0.94 0.47) (layer "F.CrtYd") (width 0.05) (fill none))
    (fp_rect (start -0.499 -0.249) (end 0.499 0.249) (layer "F.Fab") (width 0.15) (fill none))
    (pad "1" smd roundrect (at -0.484 0 270) (size 0.59 0.64) (layers "F.Cu" "F.Paste" "F.Mask") (roundrect_rratio 0.25)
      (net 231 "/Camera Interface/3V3_CAM") (pintype "passive"))
    (pad "2" smd roundrect (at 0.484 0 270) (size 0.59 0.64) (layers "F.Cu" "F.Paste" "F.Mask") (roundrect_rratio 0.25)
      (net 1 "GND") (pintype "passive"))
  )

  (footprint "sa800u-baseboard-hw-footprints:R_0603_1608Metric" (layer "F.Cu")
    (tedit 5D5D3E92)
    (at 117.6 92)
    (descr "Resistor SMD 0603")
    (tags "resistor SMD 0603")
    (property "Author" "Antmicro")
    (property "Current" "1A")
    (property "License" "Apache-2.0")
    (property "MPN" "CR0603-J/-000ELF")
    (property "Manufacturer" "Bourns")
    (property "Sheetfile" "camera-interface.kicad_sch")
    (property "Sheetname" "Camera Interface")
    (property "Tolerance" "")
    (property "Val" "0R")
    (attr smd)
    (fp_text reference "R84" (at -1.1 -0.51) (layer "F.SilkS")
      (effects (font (size 0.7 0.7) (thickness 0.15)) (justify left bottom))
    )
    (fp_text value "R_0R_0603" (at 0 1.6) (layer "F.Fab")
      (effects (font (size 0.7 0.7) (thickness 0.15)) (justify left bottom))
    )
    (fp_text user "License: Apache-2.0" (at -1.25 5.9) (layer "F.Fab") hide
      (effects (font (size 0.7 0.7) (thickness 0.15)) (justify left bottom))
    )
    (fp_text user "Author: Antmicro" (at -1.25 4.9) (layer "F.Fab") hide
      (effects (font (size 0.7 0.7) (thickness 0.15)) (justify left bottom))
    )
    (fp_text user "${REFERENCE}" (at -1.25 3.898) (layer "F.Fab") hide
      (effects (font (size 0.7 0.7) (thickness 0.15)) (justify left bottom))
    )
    (fp_line (start -0.3 -0.3) (end 0.3 -0.3) (layer "F.SilkS") (width 0.15))
    (fp_line (start -0.3 0.3) (end 0.3 0.3) (layer "F.SilkS") (width 0.15))
    (fp_rect (start -1.25 -0.7) (end 1.25 0.7) (layer "F.CrtYd") (width 0.05) (fill none))
    (fp_rect (start -0.8 -0.4) (end 0.8 0.4) (layer "F.Fab") (width 0.15) (fill none))
    (pad "1" smd roundrect (at -0.7 0) (size 0.6 0.8) (layers "F.Cu" "F.Paste" "F.Mask") (roundrect_rratio 0.2)
      (net 231 "/Camera Interface/3V3_CAM") (pintype "passive"))
    (pad "2" smd roundrect (at 0.7 0) (size 0.6 0.8) (layers "F.Cu" "F.Paste" "F.Mask") (roundrect_rratio 0.2)
      (net 131 "3V3_SYS") (pintype "passive"))
  )

  (footprint "sa800u-baseboard-hw-footprints:R_0402_1005Metric" (layer "F.Cu")
    (tedit 5FD9C158)
    (at 91 135)
    (descr "Resistor SMD 0402")
    (tags "resistor SMD 0402")
    (property "Author" "Antmicro")
    (property "License" "Apache-2.0")
    (property "MPN" "CR0402-FX-1002GLF")
    (property "Manufacturer" "Bourns")
    (property "Sheetfile" "usb-pd.kicad_sch")
    (property "Sheetname" "USB-PD")
    (property "Tolerance" "1%")
    (property "Val" "10k")
    (attr smd)
    (fp_text reference "R153" (at 0.84 0.31) (layer "F.SilkS")
      (effects (font (size 0.7 0.7) (thickness 0.15)) (justify left bottom))
    )
    (fp_text value "R_10k_0402" (at 0 1.4) (layer "F.Fab")
      (effects (font (size 0.7 0.7) (thickness 0.15)) (justify left bottom))
    )
    (fp_text user "License: Apache-2.0" (at -0.95 5.169) (layer "F.Fab") hide
      (effects (font (size 0.7 0.7) (thickness 0.15)) (justify left bottom))
    )
    (fp_text user "${REFERENCE}" (at -0.95 3.168) (layer "F.Fab") hide
      (effects (font (size 0.7 0.7) (thickness 0.15)) (justify left bottom))
    )
    (fp_text user "Author: Antmicro" (at -0.95 4.169) (layer "F.Fab") hide
      (effects (font (size 0.7 0.7) (thickness 0.15)) (justify left bottom))
    )
    (fp_rect (start -0.93 -0.47) (end 0.93 0.47) (layer "F.CrtYd") (width 0.05) (fill none))
    (fp_rect (start -0.5 -0.25) (end 0.5 0.25) (layer "F.Fab") (width 0.15) (fill none))
    (pad "1" smd roundrect (at -0.485 0) (size 0.59 0.64) (layers "F.Cu" "F.Paste" "F.Mask") (roundrect_rratio 0.25)
      (net 351 "USB_PD_DISABLE") (pintype "passive"))
    (pad "2" smd roundrect (at 0.485 0) (size 0.59 0.64) (layers "F.Cu" "F.Paste" "F.Mask") (roundrect_rratio 0.25)
      (net 1 "GND") (pintype "passive"))
  )

  (footprint "sa800u-baseboard-hw-footprints:R_0402_1005Metric" (layer "F.Cu")
    (tedit 5FD9C158)
    (at 147.95 136.9 -90)
    (descr "Resistor SMD 0402")
    (tags "resistor SMD 0402")
    (property "Author" "Antmicro")
    (property "License" "Apache-2.0")
    (property "MPN" "CR0402-FX-5100GLF")
    (property "Manufacturer" "Bourns")
    (property "Sheetfile" "hdmi-converter.kicad_sch")
    (property "Sheetname" "HDMI converter")
    (property "Tolerance" "1%")
    (property "Val" "510R")
    (attr smd)
    (fp_text reference "R56" (at -4.57 16.84 -90) (layer "F.SilkS")
      (effects (font (size 0.7 0.7) (thickness 0.15)) (justify left bottom))
    )
    (fp_text value "R_510R_0402" (at 0 1.4 -90) (layer "F.Fab")
      (effects (font (size 0.7 0.7) (thickness 0.15)) (justify left bottom))
    )
    (fp_text user "${REFERENCE}" (at -0.95 3.168 -90) (layer "F.Fab") hide
      (effects (font (size 0.7 0.7) (thickness 0.15)) (justify left bottom))
    )
    (fp_text user "Author: Antmicro" (at -0.95 4.169 -90) (layer "F.Fab") hide
      (effects (font (size 0.7 0.7) (thickness 0.15)) (justify left bottom))
    )
    (fp_text user "License: Apache-2.0" (at -0.95 5.169 -90) (layer "F.Fab") hide
      (effects (font (size 0.7 0.7) (thickness 0.15)) (justify left bottom))
    )
    (fp_rect (start -0.93 -0.47) (end 0.93 0.47) (layer "F.CrtYd") (width 0.05) (fill none))
    (fp_rect (start -0.5 -0.25) (end 0.5 0.25) (layer "F.Fab") (width 0.15) (fill none))
    (pad "1" smd roundrect (at -0.485 0 270) (size 0.59 0.64) (layers "F.Cu" "F.Paste" "F.Mask") (roundrect_rratio 0.25)
      (net 193 "/HDMI converter/HDMI_TX2_P") (pintype "passive"))
    (pad "2" smd roundrect (at 0.485 0 270) (size 0.59 0.64) (layers "F.Cu" "F.Paste" "F.Mask") (roundrect_rratio 0.25)
      (net 209 "/HDMI converter/VCOM") (pintype "passive"))
  )

  (footprint "sa800u-baseboard-hw-footprints:R_0402_1005Metric" (layer "F.Cu")
    (tedit 5FD9C158)
    (at 110.8 91.85 90)
    (descr "Resistor SMD 0402")
    (tags "resistor SMD 0402")
    (property "Author" "Antmicro")
    (property "License" "Apache-2.0")
    (property "MPN" "CR0402-FX-2001GLF")
    (property "Manufacturer" "Bourns")
    (property "Sheetfile" "camera-interface.kicad_sch")
    (property "Sheetname" "Camera Interface")
    (property "Tolerance" "1%")
    (property "Val" "2k")
    (attr smd)
    (fp_text reference "R87" (at -0.94 -1.65 90) (layer "F.SilkS")
      (effects (font (size 0.7 0.7) (thickness 0.15)) (justify left bottom))
    )
    (fp_text value "R_2k_0402" (at 0 1.4 90) (layer "F.Fab")
      (effects (font (size 0.7 0.7) (thickness 0.15)) (justify left bottom))
    )
    (fp_text user "License: Apache-2.0" (at -0.95 5.169 90) (layer "F.Fab") hide
      (effects (font (size 0.7 0.7) (thickness 0.15)) (justify left bottom))
    )
    (fp_text user "${REFERENCE}" (at -0.95 3.168 90) (layer "F.Fab") hide
      (effects (font (size 0.7 0.7) (thickness 0.15)) (justify left bottom))
    )
    (fp_text user "Author: Antmicro" (at -0.95 4.169 90) (layer "F.Fab") hide
      (effects (font (size 0.7 0.7) (thickness 0.15)) (justify left bottom))
    )
    (fp_rect (start -0.93 -0.47) (end 0.93 0.47) (layer "F.CrtYd") (width 0.05) (fill none))
    (fp_rect (start -0.5 -0.25) (end 0.5 0.25) (layer "F.Fab") (width 0.15) (fill none))
    (pad "1" smd roundrect (at -0.485 0 90) (size 0.59 0.64) (layers "F.Cu" "F.Paste" "F.Mask") (roundrect_rratio 0.25)
      (net 294 "/Camera Interface/CCI0_I2C_SCL_3V3") (pintype "passive"))
    (pad "2" smd roundrect (at 0.485 0 90) (size 0.59 0.64) (layers "F.Cu" "F.Paste" "F.Mask") (roundrect_rratio 0.25)
      (net 231 "/Camera Interface/3V3_CAM") (pintype "passive"))
  )

  (footprint "sa800u-baseboard-hw-footprints:R_0402_1005Metric" (layer "F.Cu")
    (tedit 5FD9C158)
    (at 93.75 121.7 -90)
    (descr "Resistor SMD 0402")
    (tags "resistor SMD 0402")
    (property "Author" "Antmicro")
    (property "Current" "1A")
    (property "License" "Apache-2.0")
    (property "MPN" "ERJ2GE0R00X")
    (property "Manufacturer" "Panasonic")
    (property "Sheetfile" "som.kicad_sch")
    (property "Sheetname" "SoM")
    (property "Tolerance" "")
    (property "Val" "0R")
    (attr smd)
    (fp_text reference "R176" (at 3.63 -0.37 -90) (layer "F.SilkS")
      (effects (font (size 0.7 0.7) (thickness 0.15)) (justify left bottom))
    )
    (fp_text value "R_0R_0402" (at 0 1.4 -90) (layer "F.Fab")
      (effects (font (size 0.7 0.7) (thickness 0.15)) (justify left bottom))
    )
    (fp_text user "${REFERENCE}" (at -0.95 3.168 -90) (layer "F.Fab") hide
      (effects (font (size 0.7 0.7) (thickness 0.15)) (justify left bottom))
    )
    (fp_text user "License: Apache-2.0" (at -0.95 5.169 -90) (layer "F.Fab") hide
      (effects (font (size 0.7 0.7) (thickness 0.15)) (justify left bottom))
    )
    (fp_text user "Author: Antmicro" (at -0.95 4.169 -90) (layer "F.Fab") hide
      (effects (font (size 0.7 0.7) (thickness 0.15)) (justify left bottom))
    )
    (fp_rect (start -0.93 -0.47) (end 0.93 0.47) (layer "F.CrtYd") (width 0.05) (fill none))
    (fp_rect (start -0.5 -0.25) (end 0.5 0.25) (layer "F.Fab") (width 0.15) (fill none))
    (pad "1" smd roundrect (at -0.485 0 270) (size 0.59 0.64) (layers "F.Cu" "F.Paste" "F.Mask") (roundrect_rratio 0.25)
      (net 420 "Net-(R176-Pad1)") (pintype "passive"))
    (pad "2" smd roundrect (at 0.485 0 270) (size 0.59 0.64) (layers "F.Cu" "F.Paste" "F.Mask") (roundrect_rratio 0.25)
      (net 424 "/SoM/VBAT_SOM") (pintype "passive"))
  )

  (footprint "sa800u-baseboard-hw-footprints:R_0402_1005Metric" (layer "F.Cu")
    (tedit 5FD9C158)
    (at 92.75 121.7 -90)
    (descr "Resistor SMD 0402")
    (tags "resistor SMD 0402")
    (property "Author" "Antmicro")
    (property "Current" "1A")
    (property "License" "Apache-2.0")
    (property "MPN" "ERJ2GE0R00X")
    (property "Manufacturer" "Panasonic")
    (property "Sheetfile" "som.kicad_sch")
    (property "Sheetname" "SoM")
    (property "Tolerance" "")
    (property "Val" "0R")
    (attr smd)
    (fp_text reference "R177" (at 3.63 -0.37 -90) (layer "F.SilkS")
      (effects (font (size 0.7 0.7) (thickness 0.15)) (justify left bottom))
    )
    (fp_text value "R_0R_0402" (at 0 1.4 -90) (layer "F.Fab")
      (effects (font (size 0.7 0.7) (thickness 0.15)) (justify left bottom))
    )
    (fp_text user "${REFERENCE}" (at -0.95 3.168 -90) (layer "F.Fab") hide
      (effects (font (size 0.7 0.7) (thickness 0.15)) (justify left bottom))
    )
    (fp_text user "License: Apache-2.0" (at -0.95 5.169 -90) (layer "F.Fab") hide
      (effects (font (size 0.7 0.7) (thickness 0.15)) (justify left bottom))
    )
    (fp_text user "Author: Antmicro" (at -0.95 4.169 -90) (layer "F.Fab") hide
      (effects (font (size 0.7 0.7) (thickness 0.15)) (justify left bottom))
    )
    (fp_rect (start -0.93 -0.47) (end 0.93 0.47) (layer "F.CrtYd") (width 0.05) (fill none))
    (fp_rect (start -0.5 -0.25) (end 0.5 0.25) (layer "F.Fab") (width 0.15) (fill none))
    (pad "1" smd roundrect (at -0.485 0 270) (size 0.59 0.64) (layers "F.Cu" "F.Paste" "F.Mask") (roundrect_rratio 0.25)
      (net 421 "Net-(R177-Pad1)") (pintype "passive"))
    (pad "2" smd roundrect (at 0.485 0 270) (size 0.59 0.64) (layers "F.Cu" "F.Paste" "F.Mask") (roundrect_rratio 0.25)
      (net 424 "/SoM/VBAT_SOM") (pintype "passive"))
  )

  (footprint "sa800u-baseboard-hw-footprints:R_0402_1005Metric" (layer "F.Cu")
    (tedit 5FD9C158)
    (at 91.75 121.7 -90)
    (descr "Resistor SMD 0402")
    (tags "resistor SMD 0402")
    (property "Author" "Antmicro")
    (property "Current" "1A")
    (property "License" "Apache-2.0")
    (property "MPN" "ERJ2GE0R00X")
    (property "Manufacturer" "Panasonic")
    (property "Sheetfile" "som.kicad_sch")
    (property "Sheetname" "SoM")
    (property "Tolerance" "")
    (property "Val" "0R")
    (attr smd)
    (fp_text reference "R178" (at 3.63 -0.37 -90) (layer "F.SilkS")
      (effects (font (size 0.7 0.7) (thickness 0.15)) (justify left bottom))
    )
    (fp_text value "R_0R_0402" (at 0 1.4 -90) (layer "F.Fab")
      (effects (font (size 0.7 0.7) (thickness 0.15)) (justify left bottom))
    )
    (fp_text user "License: Apache-2.0" (at -0.95 5.169 -90) (layer "F.Fab") hide
      (effects (font (size 0.7 0.7) (thickness 0.15)) (justify left bottom))
    )
    (fp_text user "Author: Antmicro" (at -0.95 4.169 -90) (layer "F.Fab") hide
      (effects (font (size 0.7 0.7) (thickness 0.15)) (justify left bottom))
    )
    (fp_text user "${REFERENCE}" (at -0.95 3.168 -90) (layer "F.Fab") hide
      (effects (font (size 0.7 0.7) (thickness 0.15)) (justify left bottom))
    )
    (fp_rect (start -0.93 -0.47) (end 0.93 0.47) (layer "F.CrtYd") (width 0.05) (fill none))
    (fp_rect (start -0.5 -0.25) (end 0.5 0.25) (layer "F.Fab") (width 0.15) (fill none))
    (pad "1" smd roundrect (at -0.485 0 270) (size 0.59 0.64) (layers "F.Cu" "F.Paste" "F.Mask") (roundrect_rratio 0.25)
      (net 422 "Net-(R178-Pad1)") (pintype "passive"))
    (pad "2" smd roundrect (at 0.485 0 270) (size 0.59 0.64) (layers "F.Cu" "F.Paste" "F.Mask") (roundrect_rratio 0.25)
      (net 424 "/SoM/VBAT_SOM") (pintype "passive"))
  )

  (footprint "sa800u-baseboard-hw-footprints:R_0402_1005Metric" (layer "F.Cu")
    (tedit 5FD9C158)
    (at 90.75 121.7 -90)
    (descr "Resistor SMD 0402")
    (tags "resistor SMD 0402")
    (property "Author" "Antmicro")
    (property "Current" "1A")
    (property "License" "Apache-2.0")
    (property "MPN" "ERJ2GE0R00X")
    (property "Manufacturer" "Panasonic")
    (property "Sheetfile" "som.kicad_sch")
    (property "Sheetname" "SoM")
    (property "Tolerance" "")
    (property "Val" "0R")
    (attr smd)
    (fp_text reference "R179" (at 3.63 -0.37 -90) (layer "F.SilkS")
      (effects (font (size 0.7 0.7) (thickness 0.15)) (justify left bottom))
    )
    (fp_text value "R_0R_0402" (at 0 1.4 -90) (layer "F.Fab")
      (effects (font (size 0.7 0.7) (thickness 0.15)) (justify left bottom))
    )
    (fp_text user "${REFERENCE}" (at -0.95 3.168 -90) (layer "F.Fab") hide
      (effects (font (size 0.7 0.7) (thickness 0.15)) (justify left bottom))
    )
    (fp_text user "Author: Antmicro" (at -0.95 4.169 -90) (layer "F.Fab") hide
      (effects (font (size 0.7 0.7) (thickness 0.15)) (justify left bottom))
    )
    (fp_text user "License: Apache-2.0" (at -0.95 5.169 -90) (layer "F.Fab") hide
      (effects (font (size 0.7 0.7) (thickness 0.15)) (justify left bottom))
    )
    (fp_rect (start -0.93 -0.47) (end 0.93 0.47) (layer "F.CrtYd") (width 0.05) (fill none))
    (fp_rect (start -0.5 -0.25) (end 0.5 0.25) (layer "F.Fab") (width 0.15) (fill none))
    (pad "1" smd roundrect (at -0.485 0 270) (size 0.59 0.64) (layers "F.Cu" "F.Paste" "F.Mask") (roundrect_rratio 0.25)
      (net 423 "Net-(R179-Pad1)") (pintype "passive"))
    (pad "2" smd roundrect (at 0.485 0 270) (size 0.59 0.64) (layers "F.Cu" "F.Paste" "F.Mask") (roundrect_rratio 0.25)
      (net 1 "GND") (pintype "passive"))
  )

  (footprint "sa800u-baseboard-hw-footprints:R_0402_1005Metric" (layer "F.Cu")
    (tedit 5FD9C158)
    (at 81.45 139.3)
    (descr "Resistor SMD 0402")
    (tags "resistor SMD 0402")
    (property "Author" "Antmicro")
    (property "License" "Apache-2.0")
    (property "MPN" "CR0402-FX-4700GLF")
    (property "Manufacturer" "Bourns")
    (property "Sheetfile" "usb-pd.kicad_sch")
    (property "Sheetname" "USB-PD")
    (property "Tolerance" "1%")
    (property "Val" "470R")
    (attr smd)
    (fp_text reference "R158" (at 0.58 -0.91) (layer "F.SilkS")
      (effects (font (size 0.7 0.7) (thickness 0.15)) (justify left bottom))
    )
    (fp_text value "R_470R_0402" (at 0 1.4) (layer "F.Fab")
      (effects (font (size 0.7 0.7) (thickness 0.15)) (justify left bottom))
    )
    (fp_text user "License: Apache-2.0" (at -0.95 5.169) (layer "F.Fab") hide
      (effects (font (size 0.7 0.7) (thickness 0.15)) (justify left bottom))
    )
    (fp_text user "${REFERENCE}" (at -0.95 3.168) (layer "F.Fab") hide
      (effects (font (size 0.7 0.7) (thickness 0.15)) (justify left bottom))
    )
    (fp_text user "Author: Antmicro" (at -0.95 4.169) (layer "F.Fab") hide
      (effects (font (size 0.7 0.7) (thickness 0.15)) (justify left bottom))
    )
    (fp_rect (start -0.93 -0.47) (end 0.93 0.47) (layer "F.CrtYd") (width 0.05) (fill none))
    (fp_rect (start -0.5 -0.25) (end 0.5 0.25) (layer "F.Fab") (width 0.15) (fill none))
    (pad "1" smd roundrect (at -0.485 0) (size 0.59 0.64) (layers "F.Cu" "F.Paste" "F.Mask") (roundrect_rratio 0.25)
      (net 107 "/USB-PD/PD_VBUS") (pintype "passive"))
    (pad "2" smd roundrect (at 0.485 0) (size 0.59 0.64) (layers "F.Cu" "F.Paste" "F.Mask") (roundrect_rratio 0.25)
      (net 364 "Net-(C153-Pad1)") (pintype "passive"))
  )

  (footprint "sa800u-baseboard-hw-footprints:C_0805_2012Metric" (layer "F.Cu")
    (tedit 5FD9C126)
    (at 91.83 92.68 -90)
    (descr "Capacitor SMD 0805")
    (tags "capacitor SMD 0805")
    (property "Author" "Antmicro")
    (property "Dielectric" "")
    (property "License" "Apache-2.0")
    (property "MPN" "GRM21BR60J107ME15L")
    (property "Manufacturer" "Murata")
    (property "Sheetfile" "som.kicad_sch")
    (property "Sheetname" "SoM")
    (property "Val" "100u")
    (property "Voltage" "")
    (attr smd)
    (fp_text reference "C100" (at 4.46 -0.38 -90) (layer "F.SilkS")
      (effects (font (size 0.7 0.7) (thickness 0.15)) (justify left bottom))
    )
    (fp_text value "C_100u_0805" (at 0 1.947 -90) (layer "F.Fab")
      (effects (font (size 0.7 0.7) (thickness 0.15)) (justify left bottom))
    )
    (fp_text user "Author: Antmicro" (at -1.9 5.947 -90) (layer "F.Fab") hide
      (effects (font (size 0.7 0.7) (thickness 0.15)) (justify left bottom))
    )
    (fp_text user "License: Apache-2.0" (at -1.9 4.947 -90) (layer "F.Fab") hide
      (effects (font (size 0.7 0.7) (thickness 0.15)) (justify left bottom))
    )
    (fp_text user "${REFERENCE}" (at -1.9 3.947 -90) (layer "F.Fab") hide
      (effects (font (size 0.7 0.7) (thickness 0.15)) (justify left bottom))
    )
    (fp_line (start -0.3 0.8) (end 0.3 0.8) (layer "F.SilkS") (width 0.15))
    (fp_line (start -0.3 -0.8) (end 0.3 -0.8) (layer "F.SilkS") (width 0.15))
    (fp_rect (start -1.9 -0.93) (end 1.9 0.93) (layer "F.CrtYd") (width 0.05) (fill none))
    (fp_rect (start -0.95 -0.675) (end 0.95 0.675) (layer "F.Fab") (width 0.15) (fill none))
    (pad "1" smd rect (at -1.05 0 270) (size 1.2 1.2) (layers "F.Cu" "F.Paste" "F.Mask")
      (net 424 "/SoM/VBAT_SOM") (pintype "passive"))
    (pad "2" smd rect (at 1.05 0 270) (size 1.2 1.2) (layers "F.Cu" "F.Paste" "F.Mask")
      (net 1 "GND") (pintype "passive"))
  )

  (footprint "sa800u-baseboard-hw-footprints:Nexperia_SOD128" (layer "F.Cu")
    (tedit 62816545)
    (at 87.37 94.2 -90)
    (property "Author" "Antmicro")
    (property "License" "Apache-2.0")
    (property "MPN" "PMEG3050EP,115")
    (property "Manufacturer" "Nexperia")
    (property "Sheetfile" "som.kicad_sch")
    (property "Sheetname" "SoM")
    (attr smd)
    (fp_text reference "D38" (at -2.72 -1.09 -90) (layer "F.SilkS")
      (effects (font (size 0.7 0.7) (thickness 0.15)) (justify left bottom))
    )
    (fp_text value "PMEG3050EP,115" (at 0 2.6 -90) (layer "F.Fab")
      (effects (font (size 0.7 0.7) (thickness 0.15)) (justify left bottom))
    )
    (fp_text user "${REFERENCE}" (at -4.37 6.9 -90) (layer "F.Fab") hide
      (effects (font (size 0.7 0.7) (thickness 0.15)) (justify left bottom))
    )
    (fp_text user "Author: Antmicro" (at -4.37 4.5 -90) (layer "F.Fab") hide
      (effects (font (size 0.7 0.7) (thickness 0.15)) (justify left bottom))
    )
    (fp_text user "License: Apache-2.0" (at -4.37 5.7 -90) (layer "F.Fab") hide
      (effects (font (size 0.7 0.7) (thickness 0.15)) (justify left bottom))
    )
    (fp_line (start -2.121 1.284) (end -2.121 1.473) (layer "F.SilkS") (width 0.15))
    (fp_line (start -1.6 -1.4) (end -1.6 1.4) (layer "F.SilkS") (width 0.12))
    (fp_line (start 2.12 1.473) (end 2.12 1.284) (layer "F.SilkS") (width 0.15))
    (fp_line (start -2.121 -1.474) (end -2.121 -1.287) (layer "F.SilkS") (width 0.15))
    (fp_line (start 2.12 -1.474) (end -2.121 -1.474) (layer "F.SilkS") (width 0.15))
    (fp_line (start 2.12 -1.287) (end 2.12 -1.474) (layer "F.SilkS") (width 0.15))
    (fp_line (start -2.121 1.473) (end 2.12 1.473) (layer "F.SilkS") (width 0.15))
    (fp_rect (start -2.8 -1.6) (end 2.8 1.6) (layer "F.CrtYd") (width 0.05) (fill none))
    (fp_line (start 1.993 0.952) (end 2.5 0.952) (layer "F.Fab") (width 0.15))
    (fp_line (start -1.994 -1.347) (end -1.994 1.346) (layer "F.Fab") (width 0.15))
    (fp_line (start 2.5 0.952) (end 2.5 -0.954) (layer "F.Fab") (width 0.15))
    (fp_line (start 1.993 -0.954) (end 1.993 0.952) (layer "F.Fab") (width 0.15))
    (fp_line (start -1.994 -0.954) (end -2.503 -0.954) (layer "F.Fab") (width 0.15))
    (fp_line (start -2.503 0.952) (end -1.994 0.952) (layer "F.Fab") (width 0.15))
    (fp_line (start 2.5 -0.954) (end 1.993 -0.954) (layer "F.Fab") (width 0.15))
    (fp_line (start 1.993 -1.347) (end -1.994 -1.347) (layer "F.Fab") (width 0.15))
    (fp_line (start -1.994 1.346) (end 1.993 1.346) (layer "F.Fab") (width 0.15))
    (fp_line (start -1.994 -0.675) (end -1.321 -1.347) (layer "F.Fab") (width 0.15))
    (fp_line (start 1.993 1.346) (end 1.993 -1.347) (layer "F.Fab") (width 0.15))
    (fp_line (start -2.503 -0.954) (end -2.503 0.952) (layer "F.Fab") (width 0.15))
    (fp_line (start -1.994 0.673) (end -1.321 1.346) (layer "F.Fab") (width 0.15))
    (fp_line (start -1.994 0.952) (end -1.994 -0.954) (layer "F.Fab") (width 0.15))
    (pad "1" smd rect (at -2.298 0 270) (size 0.8096 1.905) (layers "F.Cu" "F.Paste" "F.Mask")
      (net 424 "/SoM/VBAT_SOM") (pinfunction "1") (pintype "passive"))
    (pad "2" smd rect (at 2.297 0 270) (size 0.8096 1.905) (layers "F.Cu" "F.Paste" "F.Mask")
      (net 137 "3V8_SYS") (pinfunction "2") (pintype "passive"))
  )

  (footprint "sa800u-baseboard-hw-footprints:L_Coilcraft_XEL4030" (layer "F.Cu")
    (tedit 6215D867)
    (at 83.3 94.55 90)
    (property "Author" "Antmicro")
    (property "IMax" "")
    (property "ISat" "")
    (property "License" "Apache-2.0")
    (property "MPN" "XEL4030-222MEC")
    (property "Manufacturer" "Coilcraft")
    (property "MaxCur" "6.1A")
    (property "Sheetfile" "psu.kicad_sch")
    (property "Sheetname" "PSU")
    (property "Size" "4x4")
    (property "Val" "2u2/6.1A")
    (attr smd)
    (fp_text reference "L26" (at 2.44 0.38 180) (layer "F.SilkS")
      (effects (font (size 0.7 0.7) (thickness 0.15)) (justify left bottom))
    )
    (fp_text value "L_2u2_6.1A_XEL4030" (at 0 3.35 90) (layer "F.Fab")
      (effects (font (size 0.7 0.7) (thickness 0.15)) (justify left bottom))
    )
    (fp_text user "${REFERENCE}" (at -2.15 4.996 90) (layer "F.Fab") hide
      (effects (font (size 0.7 0.7) (thickness 0.15)) (justify left bottom))
    )
    (fp_text user "License: Apache-2.0" (at -2.15 6.996 90) (layer "F.Fab") hide
      (effects (font (size 0.7 0.7) (thickness 0.15)) (justify left bottom))
    )
    (fp_text user "Author: Antmicro" (at -2.15 5.996 90) (layer "F.Fab") hide
      (effects (font (size 0.7 0.7) (thickness 0.15)) (justify left bottom))
    )
    (fp_line (start -1.8 2.2) (end 1.85 2.199) (layer "F.SilkS") (width 0.15))
    (fp_line (start -1.8 -2.2) (end 1.85 -2.201) (layer "F.SilkS") (width 0.15))
    (fp_rect (start -2.45 -2.45) (end 2.45 2.45) (layer "F.CrtYd") (width 0.05) (fill none))
    (fp_line (start 1.999 -2) (end 1.999 1.999) (layer "F.Fab") (width 0.15))
    (fp_line (start 1.999 1.999) (end -2 1.999) (layer "F.Fab") (width 0.15))
    (fp_line (start -2 -2) (end 1.999 -2) (layer "F.Fab") (width 0.15))
    (fp_line (start -2 1.999) (end -2 -2) (layer "F.Fab") (width 0.15))
    (pad "1" smd rect (at -1.186 0 90) (size 0.98 3.4) (layers "F.Cu" "F.Paste" "F.Mask")
      (net 357 "Net-(C132-Pad2)") (pintype "passive"))
    (pad "2" smd rect (at 1.185 0 90) (size 0.98 3.4) (layers "F.Cu" "F.Paste" "F.Mask")
      (net 137 "3V8_SYS") (pintype "passive"))
  )

  (footprint "sa800u-baseboard-hw-footprints:C_0805_2012Metric" (layer "F.Cu")
    (tedit 5FD9C126)
    (at 85.75 90.3 180)
    (descr "Capacitor SMD 0805")
    (tags "capacitor SMD 0805")
    (property "Author" "Antmicro")
    (property "Dielectric" "")
    (property "License" "Apache-2.0")
    (property "MPN" "GRM21BR60J107ME15L")
    (property "Manufacturer" "Murata")
    (property "Sheetfile" "som.kicad_sch")
    (property "Sheetname" "SoM")
    (property "Val" "100u")
    (property "Voltage" "")
    (attr smd)
    (fp_text reference "C101" (at 1.38 0.93 180) (layer "F.SilkS")
      (effects (font (size 0.7 0.7) (thickness 0.15)) (justify left bottom))
    )
    (fp_text value "C_100u_0805" (at 0 1.947 180) (layer "F.Fab")
      (effects (font (size 0.7 0.7) (thickness 0.15)) (justify left bottom))
    )
    (fp_text user "License: Apache-2.0" (at -1.9 4.947 180) (layer "F.Fab") hide
      (effects (font (size 0.7 0.7) (thickness 0.15)) (justify left bottom))
    )
    (fp_text user "Author: Antmicro" (at -1.9 5.947 180) (layer "F.Fab") hide
      (effects (font (size 0.7 0.7) (thickness 0.15)) (justify left bottom))
    )
    (fp_text user "${REFERENCE}" (at -1.9 3.947 180) (layer "F.Fab") hide
      (effects (font (size 0.7 0.7) (thickness 0.15)) (justify left bottom))
    )
    (fp_line (start -0.3 0.8) (end 0.3 0.8) (layer "F.SilkS") (width 0.15))
    (fp_line (start -0.3 -0.8) (end 0.3 -0.8) (layer "F.SilkS") (width 0.15))
    (fp_rect (start -1.9 -0.93) (end 1.9 0.93) (layer "F.CrtYd") (width 0.05) (fill none))
    (fp_rect (start -0.95 -0.675) (end 0.95 0.675) (layer "F.Fab") (width 0.15) (fill none))
    (pad "1" smd rect (at -1.05 0 180) (size 1.2 1.2) (layers "F.Cu" "F.Paste" "F.Mask")
      (net 424 "/SoM/VBAT_SOM") (pintype "passive"))
    (pad "2" smd rect (at 1.05 0 180) (size 1.2 1.2) (layers "F.Cu" "F.Paste" "F.Mask")
      (net 1 "GND") (pintype "passive"))
  )

  (footprint "sa800u-baseboard-hw-footprints:C_0402_1005Metric" (layer "F.Cu")
    (tedit 616D63CF)
    (at 95.14 91.71 -90)
    (descr "Capacitor SMD 0402")
    (tags "capacitor SMD 0402")
    (property "Author" "Antmicro")
    (property "Dielectric" "X5R")
    (property "License" "Apache-2.0")
    (property "MPN" "GRM155R61H104KE14D")
    (property "Manufacturer" "Murata")
    (property "Sheetfile" "som.kicad_sch")
    (property "Sheetname" "SoM")
    (property "Val" "100n")
    (property "Voltage" "50V")
    (attr smd)
    (fp_text reference "C102" (at 3.72 -0.41 -90) (layer "F.SilkS")
      (effects (font (size 0.7 0.7) (thickness 0.15)) (justify left bottom))
    )
    (fp_text value "C_100n_0402" (at 0 1.4 -90) (layer "F.Fab")
      (effects (font (size 0.7 0.7) (thickness 0.15)) (justify left bottom))
    )
    (fp_text user "License: Apache-2.0" (at -0.932 5.17 -90) (layer "F.Fab") hide
      (effects (font (size 0.7 0.7) (thickness 0.15)) (justify left bottom))
    )
    (fp_text user "${REFERENCE}" (at -0.932 3.168 -90) (layer "F.Fab") hide
      (effects (font (size 0.7 0.7) (thickness 0.15)) (justify left bottom))
    )
    (fp_text user "Author: Antmicro" (at -0.932 4.17 -90) (layer "F.Fab") hide
      (effects (font (size 0.7 0.7) (thickness 0.15)) (justify left bottom))
    )
    (fp_rect (start -0.94 -0.47) (end 0.94 0.47) (layer "F.CrtYd") (width 0.05) (fill none))
    (fp_rect (start -0.499 -0.249) (end 0.499 0.249) (layer "F.Fab") (width 0.15) (fill none))
    (pad "1" smd roundrect (at -0.484 0 270) (size 0.59 0.64) (layers "F.Cu" "F.Paste" "F.Mask") (roundrect_rratio 0.25)
      (net 424 "/SoM/VBAT_SOM") (pintype "passive"))
    (pad "2" smd roundrect (at 0.484 0 270) (size 0.59 0.64) (layers "F.Cu" "F.Paste" "F.Mask") (roundrect_rratio 0.25)
      (net 1 "GND") (pintype "passive"))
  )

  (footprint "sa800u-baseboard-hw-footprints:C_0402_1005Metric" (layer "F.Cu")
    (tedit 616D63CF)
    (at 94.19 91.71 -90)
    (descr "Capacitor SMD 0402")
    (tags "capacitor SMD 0402")
    (property "Author" "Antmicro")
    (property "Dielectric" "")
    (property "License" "Apache-2.0")
    (property "MPN" "MC0402N330J500CT")
    (property "Manufacturer" "Multicomp")
    (property "Sheetfile" "som.kicad_sch")
    (property "Sheetname" "SoM")
    (property "Val" "33p")
    (property "Voltage" "")
    (attr smd)
    (fp_text reference "C103" (at 3.72 -0.41 -90) (layer "F.SilkS")
      (effects (font (size 0.7 0.7) (thickness 0.15)) (justify left bottom))
    )
    (fp_text value "C_33p_0402" (at 0 1.4 -90) (layer "F.Fab")
      (effects (font (size 0.7 0.7) (thickness 0.15)) (justify left bottom))
    )
    (fp_text user "License: Apache-2.0" (at -0.932 5.17 -90) (layer "F.Fab") hide
      (effects (font (size 0.7 0.7) (thickness 0.15)) (justify left bottom))
    )
    (fp_text user "${REFERENCE}" (at -0.932 3.168 -90) (layer "F.Fab") hide
      (effects (font (size 0.7 0.7) (thickness 0.15)) (justify left bottom))
    )
    (fp_text user "Author: Antmicro" (at -0.932 4.17 -90) (layer "F.Fab") hide
      (effects (font (size 0.7 0.7) (thickness 0.15)) (justify left bottom))
    )
    (fp_rect (start -0.94 -0.47) (end 0.94 0.47) (layer "F.CrtYd") (width 0.05) (fill none))
    (fp_rect (start -0.499 -0.249) (end 0.499 0.249) (layer "F.Fab") (width 0.15) (fill none))
    (pad "1" smd roundrect (at -0.484 0 270) (size 0.59 0.64) (layers "F.Cu" "F.Paste" "F.Mask") (roundrect_rratio 0.25)
      (net 424 "/SoM/VBAT_SOM") (pintype "passive"))
    (pad "2" smd roundrect (at 0.484 0 270) (size 0.59 0.64) (layers "F.Cu" "F.Paste" "F.Mask") (roundrect_rratio 0.25)
      (net 1 "GND") (pintype "passive"))
  )

  (footprint "sa800u-baseboard-hw-footprints:C_0402_1005Metric" (layer "F.Cu")
    (tedit 616D63CF)
    (at 93.24 91.71 -90)
    (descr "Capacitor SMD 0402")
    (tags "capacitor SMD 0402")
    (property "Author" "Antmicro")
    (property "Dielectric" "C0G")
    (property "License" "Apache-2.0")
    (property "MPN" "GCM1555C1H100GA16D")
    (property "Manufacturer" "Murata")
    (property "Sheetfile" "som.kicad_sch")
    (property "Sheetname" "SoM")
    (property "Val" "10p")
    (property "Voltage" "50V")
    (attr smd)
    (fp_text reference "C104" (at 3.72 -0.41 -90) (layer "F.SilkS")
      (effects (font (size 0.7 0.7) (thickness 0.15)) (justify left bottom))
    )
    (fp_text value "C_10p_0402" (at 0 1.4 -90) (layer "F.Fab")
      (effects (font (size 0.7 0.7) (thickness 0.15)) (justify left bottom))
    )
    (fp_text user "Author: Antmicro" (at -0.932 4.17 -90) (layer "F.Fab") hide
      (effects (font (size 0.7 0.7) (thickness 0.15)) (justify left bottom))
    )
    (fp_text user "${REFERENCE}" (at -0.932 3.168 -90) (layer "F.Fab") hide
      (effects (font (size 0.7 0.7) (thickness 0.15)) (justify left bottom))
    )
    (fp_text user "License: Apache-2.0" (at -0.932 5.17 -90) (layer "F.Fab") hide
      (effects (font (size 0.7 0.7) (thickness 0.15)) (justify left bottom))
    )
    (fp_rect (start -0.94 -0.47) (end 0.94 0.47) (layer "F.CrtYd") (width 0.05) (fill none))
    (fp_rect (start -0.499 -0.249) (end 0.499 0.249) (layer "F.Fab") (width 0.15) (fill none))
    (pad "1" smd roundrect (at -0.484 0 270) (size 0.59 0.64) (layers "F.Cu" "F.Paste" "F.Mask") (roundrect_rratio 0.25)
      (net 424 "/SoM/VBAT_SOM") (pintype "passive"))
    (pad "2" smd roundrect (at 0.484 0 270) (size 0.59 0.64) (layers "F.Cu" "F.Paste" "F.Mask") (roundrect_rratio 0.25)
      (net 1 "GND") (pintype "passive"))
  )

  (footprint "sa800u-baseboard-hw-footprints:C_0805_2012Metric" (layer "F.Cu")
    (tedit 5FD9C126)
    (at 89.93 92.68 -90)
    (descr "Capacitor SMD 0805")
    (tags "capacitor SMD 0805")
    (property "Author" "Antmicro")
    (property "Dielectric" "")
    (property "License" "Apache-2.0")
    (property "MPN" "GRM21BR60J107ME15L")
    (property "Manufacturer" "Murata")
    (property "Sheetfile" "som.kicad_sch")
    (property "Sheetname" "SoM")
    (property "Val" "100u")
    (property "Voltage" "")
    (attr smd)
    (fp_text reference "C99" (at 3.9 -0.36 -90) (layer "F.SilkS")
      (effects (font (size 0.7 0.7) (thickness 0.15)) (justify left bottom))
    )
    (fp_text value "C_100u_0805" (at 0 1.947 -90) (layer "F.Fab")
      (effects (font (size 0.7 0.7) (thickness 0.15)) (justify left bottom))
    )
    (fp_text user "Author: Antmicro" (at -1.9 5.947 -90) (layer "F.Fab") hide
      (effects (font (size 0.7 0.7) (thickness 0.15)) (justify left bottom))
    )
    (fp_text user "License: Apache-2.0" (at -1.9 4.947 -90) (layer "F.Fab") hide
      (effects (font (size 0.7 0.7) (thickness 0.15)) (justify left bottom))
    )
    (fp_text user "${REFERENCE}" (at -1.9 3.947 -90) (layer "F.Fab") hide
      (effects (font (size 0.7 0.7) (thickness 0.15)) (justify left bottom))
    )
    (fp_line (start -0.3 0.8) (end 0.3 0.8) (layer "F.SilkS") (width 0.15))
    (fp_line (start -0.3 -0.8) (end 0.3 -0.8) (layer "F.SilkS") (width 0.15))
    (fp_rect (start -1.9 -0.93) (end 1.9 0.93) (layer "F.CrtYd") (width 0.05) (fill none))
    (fp_rect (start -0.95 -0.675) (end 0.95 0.675) (layer "F.Fab") (width 0.15) (fill none))
    (pad "1" smd rect (at -1.05 0 270) (size 1.2 1.2) (layers "F.Cu" "F.Paste" "F.Mask")
      (net 424 "/SoM/VBAT_SOM") (pintype "passive"))
    (pad "2" smd rect (at 1.05 0 270) (size 1.2 1.2) (layers "F.Cu" "F.Paste" "F.Mask")
      (net 1 "GND") (pintype "passive"))
  )

  (footprint "sa800u-baseboard-hw-footprints:SW_DIP_SPSTx02_Slide_Copal_CVS-02xB_W5.9mm_P1mm" (layer "F.Cu")
    (tedit 5A4E1407)
    (at 146.7 113.7 90)
    (descr "SMD 2x-dip-switch SPST Copal_CVS-02xB, Slide, row spacing 5.9 mm")
    (tags "SMD DIP Switch SPST Slide 5.9mm")
    (property "Author" "Antmicro")
    (property "License" "Apache-2.0")
    (property "MPN" "CVS-02B")
    (property "Manufacturer" "Nidec")
    (property "Sheetfile" "som.kicad_sch")
    (property "Sheetname" "SoM")
    (attr smd)
    (fp_text reference "SW1" (at 0 -2.2 90) (layer "F.SilkS")
      (effects (font (size 0.7 0.7) (thickness 0.15)) (justify left bottom))
    )
    (fp_text value "SW_CVS-02B" (at 0 2.91 90) (layer "F.Fab")
      (effects (font (size 0.7 0.7) (thickness 0.15)) (justify left bottom))
    )
    (fp_text user "${REFERENCE}" (at -3.6 4.91 90) (layer "F.Fab") hide
      (effects (font (size 0.7 0.7) (thickness 0.15)) (justify left bottom))
    )
    (fp_text user "on" (at -1.5 0.739 180) (layer "F.Fab")
      (effects (font (size 0.7 0.7) (thickness 0.15)) (justify left bottom))
    )
    (fp_text user "Author: Antmicro" (at -3.6 5.908 90) (layer "F.Fab") hide
      (effects (font (size 0.7 0.7) (thickness 0.15)) (justify left bottom))
    )
    (fp_text user "License: Apache-2.0" (at -3.6 6.908 90) (layer "F.Fab") hide
      (effects (font (size 0.7 0.7) (thickness 0.15)) (justify left bottom))
    )
    (fp_line (start -1.561 1.908) (end 1.56 1.908) (layer "F.SilkS") (width 0.15))
    (fp_line (start -1.561 -1.911) (end 1.56 -1.911) (layer "F.SilkS") (width 0.15))
    (fp_circle (center -3.4 -1.1) (end -3.35 -1.06) (layer "F.SilkS") (width 0.15) (fill solid))
    (fp_rect (start -3.6 -2) (end 3.6 2) (layer "F.CrtYd") (width 0.05) (fill none))
    (fp_line (start -1 -0.75) (end -1 -0.25) (layer "F.Fab") (width 0.15))
    (fp_line (start 0.998 0.248) (end -1 0.248) (layer "F.Fab") (width 0.15))
    (fp_line (start 0.998 -0.75) (end -1 -0.75) (layer "F.Fab") (width 0.15))
    (fp_line (start -1 -0.552) (end -0.335 -0.552) (layer "F.Fab") (width 0.15))
    (fp_line (start -1 -0.452) (end -0.335 -0.452) (layer "F.Fab") (width 0.15))
    (fp_line (start -1 0.65) (end -0.335 0.65) (layer "F.Fab") (width 0.15))
    (fp_line (start -0.335 0.248) (end -0.335 0.748) (layer "F.Fab") (width 0.15))
    (fp_line (start -1 0.248) (end -1 0.748) (layer "F.Fab") (width 0.15))
    (fp_line (start -0.335 -0.75) (end -0.335 -0.25) (layer "F.Fab") (width 0.15))
    (fp_line (start -2.351 -0.5) (end -1.351 -1.5) (layer "F.Fab") (width 0.15))
    (fp_line (start -1 0.748) (end 0.998 0.748) (layer "F.Fab") (width 0.15))
    (fp_line (start -1 0.55) (end -0.335 0.55) (layer "F.Fab") (width 0.15))
    (fp_line (start -1 0.45) (end -0.335 0.45) (layer "F.Fab") (width 0.15))
    (fp_line (start -1 -0.652) (end -0.335 -0.652) (layer "F.Fab") (width 0.15))
    (fp_line (start 0.998 0.748) (end 0.998 0.248) (layer "F.Fab") (width 0.15))
    (fp_line (start -1 0.349) (end -0.335 0.349) (layer "F.Fab") (width 0.15))
    (fp_line (start 0.998 -0.25) (end 0.998 -0.75) (layer "F.Fab") (width 0.15))
    (fp_line (start -1 -0.351) (end -0.335 -0.351) (layer "F.Fab") (width 0.15))
    (fp_line (start -1 -0.25) (end 0.998 -0.25) (layer "F.Fab") (width 0.15))
    (fp_rect (start 2.35 1.499) (end -2.351 -1.5) (layer "F.Fab") (width 0.15) (fill none))
    (pad "1" smd rect (at -2.95 -0.5 90) (size 1.2 0.5) (layers "F.Cu" "F.Paste" "F.Mask")
      (net 418 "/SoM/USB_BOOT") (pintype "passive"))
    (pad "2" smd rect (at -2.95 0.5 90) (size 1.2 0.5) (layers "F.Cu" "F.Paste" "F.Mask")
      (net 419 "/SoM/AUTO_ON_N") (pintype "passive"))
    (pad "3" smd rect (at 2.95 0.5 90) (size 1.2 0.5) (layers "F.Cu" "F.Paste" "F.Mask")
      (net 397 "Net-(R69-Pad1)") (pintype "passive"))
    (pad "4" smd rect (at 2.95 -0.5 90) (size 1.2 0.5) (layers "F.Cu" "F.Paste" "F.Mask")
      (net 417 "Net-(R175-Pad2)") (pintype "passive"))
    (pad "SH" smd rect (at 2.15 -1.5 90) (size 0.7 0.7) (layers "F.Cu" "F.Paste" "F.Mask")
      (net 1 "GND") (pinfunction "SH") (pintype "power_in"))
    (pad "SH" smd rect (at -2.15 -1.5 90) (size 0.7 0.7) (layers "F.Cu" "F.Paste" "F.Mask")
      (net 1 "GND") (pinfunction "SH") (pintype "power_in"))
    (pad "SH" smd rect (at 2.15 1.5 90) (size 0.7 0.7) (layers "F.Cu" "F.Paste" "F.Mask")
      (net 1 "GND") (pinfunction "SH") (pintype "power_in"))
    (pad "SH" smd rect (at -2.15 1.5 90) (size 0.7 0.7) (layers "F.Cu" "F.Paste" "F.Mask")
      (net 1 "GND") (pinfunction "SH") (pintype "power_in"))
  )

  (footprint "sa800u-baseboard-hw-footprints:SA800U-WF" (layer "F.Cu")
    (tedit 61E0073C)
    (at 83.5 82.5)
    (property "Author" "Antmicro")
    (property "License" "Apache-2.0")
    (property "MPN" "SA800U-WF")
    (property "Manufacturer" "Quectel")
    (property "Sheetfile" "som.kicad_sch")
    (property "Sheetname" "SoM")
    (attr exclude_from_pos_files)
    (fp_text reference "A1" (at 0 -1.8) (layer "F.Fab")
      (effects (font (size 0.7 0.7) (thickness 0.15)) (justify left bottom))
    )
    (fp_text value "SA800U-WF" (at 0 -0.7) (layer "F.Fab")
      (effects (font (size 0.7 0.7) (thickness 0.15)) (justify left bottom))
    )
    (fp_text user "${REFERENCE}" (at -0.001 38.999) (layer "F.Fab") hide
      (effects (font (size 0.7 0.7) (thickness 0.15)) (justify left bottom))
    )
    (fp_text user "License: Apache-2.0" (at -0.001 41.4) (layer "F.Fab") hide
      (effects (font (size 0.7 0.7) (thickness 0.15)) (justify left bottom))
    )
    (fp_text user "Author: Antmicro" (at -0.001 40.2) (layer "F.Fab") hide
      (effects (font (size 0.7 0.7) (thickness 0.15)) (justify left bottom))
    )
  )

  (footprint "sa800u-baseboard-hw-footprints:C_0805_2012Metric" (layer "B.Cu")
    (tedit 5FD9C126)
    (at 61.1 118.5 180)
    (descr "Capacitor SMD 0805")
    (tags "capacitor SMD 0805")
    (property "Author" "Antmicro")
    (property "Dielectric" "X7R")
    (property "License" "Apache-2.0")
    (property "MPN" "CL21B104KCFNNNE")
    (property "Manufacturer" "SAMSUNG")
    (property "Sheetfile" "poe.kicad_sch")
    (property "Sheetname" "PoE")
    (property "Val" "100n/100V")
    (property "Voltage" "100V")
    (attr smd)
    (fp_text reference "C144" (at -1.37 -1.77) (layer "B.SilkS")
      (effects (font (size 0.7 0.7) (thickness 0.15)) (justify left bottom mirror))
    )
    (fp_text value "C_100n_0805_100V" (at 0 -1.947) (layer "B.Fab")
      (effects (font (size 0.7 0.7) (thickness 0.15)) (justify left bottom mirror))
    )
    (fp_text user "Author: Antmicro" (at -1.9 -5.947) (layer "B.Fab") hide
      (effects (font (size 0.7 0.7) (thickness 0.15)) (justify left bottom mirror))
    )
    (fp_text user "License: Apache-2.0" (at -1.9 -4.947) (layer "B.Fab") hide
      (effects (font (size 0.7 0.7) (thickness 0.15)) (justify left bottom mirror))
    )
    (fp_text user "${REFERENCE}" (at -1.9 -3.947) (layer "B.Fab") hide
      (effects (font (size 0.7 0.7) (thickness 0.15)) (justify left bottom mirror))
    )
    (fp_line (start -0.3 0.8) (end 0.3 0.8) (layer "B.SilkS") (width 0.15))
    (fp_line (start -0.3 -0.8) (end 0.3 -0.8) (layer "B.SilkS") (width 0.15))
    (fp_rect (start -1.9 0.93) (end 1.9 -0.93) (layer "B.CrtYd") (width 0.05) (fill none))
    (fp_rect (start -0.95 0.675) (end 0.95 -0.675) (layer "B.Fab") (width 0.15) (fill none))
    (pad "1" smd rect (at -1.05 0 180) (size 1.2 1.2) (layers "B.Cu" "B.Paste" "B.Mask")
      (net 73 "/PoE/VDD_POE") (pintype "passive"))
    (pad "2" smd rect (at 1.05 0 180) (size 1.2 1.2) (layers "B.Cu" "B.Paste" "B.Mask")
      (net 135 "/PoE/VSS_POE") (pintype "passive"))
  )

  (footprint "sa800u-baseboard-hw-footprints:C_0805_2012Metric" (layer "B.Cu")
    (tedit 5FD9C126)
    (at 79.1 101.9 90)
    (descr "Capacitor SMD 0805")
    (tags "capacitor SMD 0805")
    (property "Author" "Antmicro")
    (property "Dielectric" "")
    (property "License" "Apache-2.0")
    (property "MPN" "C0805C476M9PACTU")
    (property "Manufacturer" "KEMET")
    (property "Sheetfile" "poe.kicad_sch")
    (property "Sheetname" "PoE")
    (property "Val" "47u")
    (property "Voltage" "")
    (attr smd)
    (fp_text reference "C149" (at 4.48 0.35 270) (layer "B.SilkS")
      (effects (font (size 0.7 0.7) (thickness 0.15)) (justify left bottom mirror))
    )
    (fp_text value "C_47u_0805" (at 0 -1.947 270) (layer "B.Fab")
      (effects (font (size 0.7 0.7) (thickness 0.15)) (justify left bottom mirror))
    )
    (fp_text user "Author: Antmicro" (at -1.9 -5.947 270) (layer "B.Fab") hide
      (effects (font (size 0.7 0.7) (thickness 0.15)) (justify left bottom mirror))
    )
    (fp_text user "${REFERENCE}" (at -1.9 -3.947 270) (layer "B.Fab") hide
      (effects (font (size 0.7 0.7) (thickness 0.15)) (justify left bottom mirror))
    )
    (fp_text user "License: Apache-2.0" (at -1.9 -4.947 270) (layer "B.Fab") hide
      (effects (font (size 0.7 0.7) (thickness 0.15)) (justify left bottom mirror))
    )
    (fp_line (start -0.3 -0.8) (end 0.3 -0.8) (layer "B.SilkS") (width 0.15))
    (fp_line (start -0.3 0.8) (end 0.3 0.8) (layer "B.SilkS") (width 0.15))
    (fp_rect (start -1.9 0.93) (end 1.9 -0.93) (layer "B.CrtYd") (width 0.05) (fill none))
    (fp_rect (start -0.95 0.675) (end 0.95 -0.675) (layer "B.Fab") (width 0.15) (fill none))
    (pad "1" smd rect (at -1.05 0 90) (size 1.2 1.2) (layers "B.Cu" "B.Paste" "B.Mask")
      (net 136 "5V_POE") (pintype "passive"))
    (pad "2" smd rect (at 1.05 0 90) (size 1.2 1.2) (layers "B.Cu" "B.Paste" "B.Mask")
      (net 1 "GND") (pintype "passive"))
  )

  (footprint "sa800u-baseboard-hw-footprints:C_0402_1005Metric" (layer "B.Cu")
    (tedit 616D63CF)
    (at 73.8 102.2 90)
    (descr "Capacitor SMD 0402")
    (tags "capacitor SMD 0402")
    (property "Author" "Antmicro")
    (property "Dielectric" "X5R")
    (property "License" "Apache-2.0")
    (property "MPN" "GRM155R61H104KE14D")
    (property "Manufacturer" "Murata")
    (property "Sheetfile" "poe.kicad_sch")
    (property "Sheetname" "PoE")
    (property "Val" "100n")
    (property "Voltage" "50V")
    (attr smd)
    (fp_text reference "C151" (at 1.46 -1.67 270) (layer "B.SilkS")
      (effects (font (size 0.7 0.7) (thickness 0.15)) (justify left bottom mirror))
    )
    (fp_text value "C_100n_0402" (at 0 -1.4 270) (layer "B.Fab")
      (effects (font (size 0.7 0.7) (thickness 0.15)) (justify left bottom mirror))
    )
    (fp_text user "License: Apache-2.0" (at -0.932 -5.17 270) (layer "B.Fab") hide
      (effects (font (size 0.7 0.7) (thickness 0.15)) (justify left bottom mirror))
    )
    (fp_text user "Author: Antmicro" (at -0.932 -4.17 270) (layer "B.Fab") hide
      (effects (font (size 0.7 0.7) (thickness 0.15)) (justify left bottom mirror))
    )
    (fp_text user "${REFERENCE}" (at -0.932 -3.168 270) (layer "B.Fab") hide
      (effects (font (size 0.7 0.7) (thickness 0.15)) (justify left bottom mirror))
    )
    (fp_rect (start -0.94 0.47) (end 0.94 -0.47) (layer "B.CrtYd") (width 0.05) (fill none))
    (fp_rect (start -0.499 0.249) (end 0.499 -0.249) (layer "B.Fab") (width 0.15) (fill none))
    (pad "1" smd roundrect (at -0.484 0 90) (size 0.59 0.64) (layers "B.Cu" "B.Paste" "B.Mask") (roundrect_rratio 0.25)
      (net 136 "5V_POE") (pintype "passive"))
    (pad "2" smd roundrect (at 0.484 0 90) (size 0.59 0.64) (layers "B.Cu" "B.Paste" "B.Mask") (roundrect_rratio 0.25)
      (net 1 "GND") (pintype "passive"))
  )

  (footprint "sa800u-baseboard-hw-footprints:SOIC-4_4.2x5.0mm_P5.7mm" (layer "B.Cu")
    (tedit 6215E1D7)
    (at 58.1 125.6 -90)
    (property "Author" "Antmicro")
    (property "License" "Apache-2.0")
    (property "MPN" "MB10S")
    (property "Manufacturer" "Multicomp")
    (property "Sheetfile" "poe.kicad_sch")
    (property "Sheetname" "PoE")
    (attr smd)
    (fp_text reference "D29" (at 4.72 -0.98 180) (layer "B.SilkS")
      (effects (font (size 0.7 0.7) (thickness 0.15)) (justify left bottom mirror))
    )
    (fp_text value "MB10S" (at 0 -3.6 90) (layer "B.Fab")
      (effects (font (size 0.7 0.7) (thickness 0.15)) (justify left bottom mirror))
    )
    (fp_text user "${REFERENCE}" (at -4.111 -5.347 90) (layer "B.Fab") hide
      (effects (font (size 0.7 0.7) (thickness 0.15)) (justify left bottom mirror))
    )
    (fp_text user "Author: Antmicro" (at -4.111 -6.546 90) (layer "B.Fab") hide
      (effects (font (size 0.7 0.7) (thickness 0.15)) (justify left bottom mirror))
    )
    (fp_text user "License: Apache-2.0" (at -4.111 -7.746 90) (layer "B.Fab") hide
      (effects (font (size 0.7 0.7) (thickness 0.15)) (justify left bottom mirror))
    )
    (fp_line (start -2.1 2.5) (end 2.101 2.5) (layer "B.SilkS") (width 0.15))
    (fp_line (start -2.101 -2.479) (end 2.1 -2.479) (layer "B.SilkS") (width 0.15))
    (fp_circle (center -2.55 2) (end -2.451 2) (layer "B.SilkS") (width 0.15) (fill solid))
    (fp_rect (start -3.8 2.7) (end 3.8 -2.7) (layer "B.CrtYd") (width 0.05) (fill none))
    (fp_line (start -2.101 -2.479) (end -2.101 2.48) (layer "B.Fab") (width 0.15))
    (fp_line (start -2.101 2.48) (end 2.1 2.48) (layer "B.Fab") (width 0.15))
    (fp_line (start 2.1 2.48) (end 2.1 -2.479) (layer "B.Fab") (width 0.15))
    (fp_line (start 2.1 -2.479) (end -2.101 -2.479) (layer "B.Fab") (width 0.15))
    (pad "1" smd roundrect (at -2.851 1.226 270) (size 1.8 1) (layers "B.Cu" "B.Paste" "B.Mask") (roundrect_rratio 0.25)
      (net 175 "Net-(D29-Pad1)") (pinfunction "1") (pintype "passive"))
    (pad "2" smd roundrect (at -2.851 -1.225 270) (size 1.8 1) (layers "B.Cu" "B.Paste" "B.Mask") (roundrect_rratio 0.25)
      (net 379 "Net-(D29-Pad2)") (pinfunction "2") (pintype "passive"))
    (pad "3" smd roundrect (at 2.85 -1.225 270) (size 1.8 1) (layers "B.Cu" "B.Paste" "B.Mask") (roundrect_rratio 0.25)
      (net 5 "PAIR36") (pinfunction "3") (pintype "passive"))
    (pad "4" smd roundrect (at 2.85 1.226 270) (size 1.8 1) (layers "B.Cu" "B.Paste" "B.Mask") (roundrect_rratio 0.25)
      (net 6 "PAIR12") (pinfunction "4") (pintype "passive"))
  )

  (footprint "sa800u-baseboard-hw-footprints:SOIC-4_4.2x5.0mm_P5.7mm" (layer "B.Cu")
    (tedit 6215E1D7)
    (at 63.7 125.6 -90)
    (property "Author" "Antmicro")
    (property "License" "Apache-2.0")
    (property "MPN" "MB10S")
    (property "Manufacturer" "Multicomp")
    (property "Sheetfile" "poe.kicad_sch")
    (property "Sheetname" "PoE")
    (attr smd)
    (fp_text reference "D30" (at 4.72 -0.76 180) (layer "B.SilkS")
      (effects (font (size 0.7 0.7) (thickness 0.15)) (justify left bottom mirror))
    )
    (fp_text value "MB10S" (at 0 -3.6 90) (layer "B.Fab")
      (effects (font (size 0.7 0.7) (thickness 0.15)) (justify left bottom mirror))
    )
    (fp_text user "${REFERENCE}" (at -4.111 -5.347 90) (layer "B.Fab") hide
      (effects (font (size 0.7 0.7) (thickness 0.15)) (justify left bottom mirror))
    )
    (fp_text user "Author: Antmicro" (at -4.111 -6.546 90) (layer "B.Fab") hide
      (effects (font (size 0.7 0.7) (thickness 0.15)) (justify left bottom mirror))
    )
    (fp_text user "License: Apache-2.0" (at -4.111 -7.746 90) (layer "B.Fab") hide
      (effects (font (size 0.7 0.7) (thickness 0.15)) (justify left bottom mirror))
    )
    (fp_line (start -2.101 -2.479) (end 2.1 -2.479) (layer "B.SilkS") (width 0.15))
    (fp_line (start -2.1 2.5) (end 2.101 2.5) (layer "B.SilkS") (width 0.15))
    (fp_circle (center -2.55 2) (end -2.451 2) (layer "B.SilkS") (width 0.15) (fill solid))
    (fp_rect (start -3.8 2.7) (end 3.8 -2.7) (layer "B.CrtYd") (width 0.05) (fill none))
    (fp_line (start -2.101 2.48) (end 2.1 2.48) (layer "B.Fab") (width 0.15))
    (fp_line (start 2.1 2.48) (end 2.1 -2.479) (layer "B.Fab") (width 0.15))
    (fp_line (start 2.1 -2.479) (end -2.101 -2.479) (layer "B.Fab") (width 0.15))
    (fp_line (start -2.101 -2.479) (end -2.101 2.48) (layer "B.Fab") (width 0.15))
    (pad "1" smd roundrect (at -2.851 1.226 270) (size 1.8 1) (layers "B.Cu" "B.Paste" "B.Mask") (roundrect_rratio 0.25)
      (net 175 "Net-(D29-Pad1)") (pinfunction "1") (pintype "passive"))
    (pad "2" smd roundrect (at -2.851 -1.225 270) (size 1.8 1) (layers "B.Cu" "B.Paste" "B.Mask") (roundrect_rratio 0.25)
      (net 379 "Net-(D29-Pad2)") (pinfunction "2") (pintype "passive"))
    (pad "3" smd roundrect (at 2.85 -1.225 270) (size 1.8 1) (layers "B.Cu" "B.Paste" "B.Mask") (roundrect_rratio 0.25)
      (net 2 "PAIR78") (pinfunction "3") (pintype "passive"))
    (pad "4" smd roundrect (at 2.85 1.226 270) (size 1.8 1) (layers "B.Cu" "B.Paste" "B.Mask") (roundrect_rratio 0.25)
      (net 3 "PAIR45") (pinfunction "4") (pintype "passive"))
  )

  (footprint "sa800u-baseboard-hw-footprints:DO-214AC" (layer "B.Cu")
    (tedit 626A9B82)
    (at 61 115.9 180)
    (property "Author" "Antmicro")
    (property "License" "Apache-2.0")
    (property "MPN" "SMAJ58A-13-F")
    (property "Manufacturer" "Diodes Incorporated")
    (property "Sheetfile" "poe.kicad_sch")
    (property "Sheetname" "PoE")
    (attr smd)
    (fp_text reference "D31" (at 3.38 1.05 90) (layer "B.SilkS")
      (effects (font (size 0.7 0.7) (thickness 0.15)) (justify left bottom mirror))
    )
    (fp_text value "SMAJ58A-13-F" (at 0 -2.45) (layer "B.Fab")
      (effects (font (size 0.7 0.7) (thickness 0.15)) (justify left bottom mirror))
    )
    (fp_text user "Author: Antmicro" (at -3.301 -5.65) (layer "B.Fab") hide
      (effects (font (size 0.7 0.7) (thickness 0.15)) (justify left bottom mirror))
    )
    (fp_text user "${REFERENCE}" (at -3.301 -4.45) (layer "B.Fab") hide
      (effects (font (size 0.7 0.7) (thickness 0.15)) (justify left bottom mirror))
    )
    (fp_text user "License: Apache-2.0" (at -3.301 -6.85) (layer "B.Fab") hide
      (effects (font (size 0.7 0.7) (thickness 0.15)) (justify left bottom mirror))
    )
    (fp_line (start -0.9 -1.3) (end -0.9 1.3) (layer "B.SilkS") (width 0.15))
    (fp_rect (start -3.25 1.55) (end 3.25 -1.55) (layer "B.CrtYd") (width 0.05) (fill none))
    (fp_line (start -2.15 1.301) (end -2.15 -1.3) (layer "B.Fab") (width 0.15))
    (fp_line (start -1.363 1.301) (end -1.442 1.301) (layer "B.Fab") (width 0.15))
    (fp_line (start -2.15 1.301) (end 2.148 1.301) (layer "B.Fab") (width 0.15))
    (fp_line (start -1.442 -1.3) (end -1.365 -1.3) (layer "B.Fab") (width 0.15))
    (fp_line (start 2.148 1.301) (end 2.148 -1.3) (layer "B.Fab") (width 0.15))
    (fp_line (start -2.15 -1.3) (end 2.148 -1.3) (layer "B.Fab") (width 0.15))
    (fp_rect (start -1.363 1.301) (end -1.1 -1.3) (layer "B.Fab") (width 0.15) (fill solid))
    (pad "A" smd roundrect (at 1.999 0 180) (size 2 2.1) (layers "B.Cu" "B.Paste" "B.Mask") (roundrect_rratio 0.1)
      (net 135 "/PoE/VSS_POE") (pinfunction "A") (pintype "passive"))
    (pad "K" smd roundrect (at -2 0 180) (size 2 2.1) (layers "B.Cu" "B.Paste" "B.Mask") (roundrect_rratio 0.1)
      (net 73 "/PoE/VDD_POE") (pinfunction "K") (pintype "passive"))
  )

  (footprint "sa800u-baseboard-hw-footprints:FB_0805_2012Metric" (layer "B.Cu")
    (tedit 5D5D3F54)
    (at 64 119.5 90)
    (property "Author" "Antmicro")
    (property "License" "Apache-2.0")
    (property "MPN" "BLM21PG221SN1D")
    (property "Manufacturer" "Murata")
    (property "Sheetfile" "poe.kicad_sch")
    (property "Sheetname" "PoE")
    (attr smd)
    (fp_text reference "FB4" (at 0.96 1.71 270) (layer "B.SilkS")
      (effects (font (size 0.7 0.7) (thickness 0.15)) (justify left bottom mirror))
    )
    (fp_text value "FB_220Z_2A_0805" (at 0 -1.8 270) (layer "B.Fab")
      (effects (font (size 0.7 0.7) (thickness 0.15)) (justify left bottom mirror))
    )
    (fp_text user "License: Apache-2.0" (at -1.9 -5.75 270) (layer "B.Fab") hide
      (effects (font (size 0.7 0.7) (thickness 0.15)) (justify left bottom mirror))
    )
    (fp_text user "${REFERENCE}" (at -1.9 -3.1 270) (layer "B.Fab") hide
      (effects (font (size 0.7 0.7) (thickness 0.15)) (justify left bottom mirror))
    )
    (fp_text user "Author: Antmicro" (at -1.9 -4.4 270) (layer "B.Fab") hide
      (effects (font (size 0.7 0.7) (thickness 0.15)) (justify left bottom mirror))
    )
    (fp_line (start -0.3 0.701) (end 0.298 0.701) (layer "B.SilkS") (width 0.15))
    (fp_line (start -0.32 -0.699) (end 0.28 -0.699) (layer "B.SilkS") (width 0.15))
    (fp_rect (start -1.75 0.85) (end 1.75 -0.85) (layer "B.CrtYd") (width 0.05) (fill none))
    (fp_line (start -0.951 0.682) (end 0.949 0.682) (layer "B.Fab") (width 0.15))
    (fp_line (start -0.951 0.677) (end -0.951 -0.675) (layer "B.Fab") (width 0.15))
    (fp_line (start 0.949 0.677) (end 0.949 -0.675) (layer "B.Fab") (width 0.15))
    (fp_line (start -0.951 -0.68) (end 0.949 -0.68) (layer "B.Fab") (width 0.15))
    (pad "1" smd roundrect (at -1.1 0.001 90) (size 1 1.4) (layers "B.Cu" "B.Paste" "B.Mask") (roundrect_rratio 0.15)
      (net 175 "Net-(D29-Pad1)") (pintype "passive"))
    (pad "2" smd roundrect (at 1.1 0.001 90) (size 1 1.4) (layers "B.Cu" "B.Paste" "B.Mask") (roundrect_rratio 0.15)
      (net 73 "/PoE/VDD_POE") (pintype "passive"))
  )

  (footprint "sa800u-baseboard-hw-footprints:Conn_FFC_WE_68715014x22_ALT" locked (layer "B.Cu")
    (tedit 5D9CB84E)
    (at 105 84.75)
    (property "Author" "Antmicro")
    (property "License" "Apache-2.0")
    (property "MPN" "68715014522")
    (property "Manufacturer" "Würth Elektronik")
    (property "Sheetfile" "camera-interface.kicad_sch")
    (property "Sheetname" "Camera Interface")
    (attr smd)
    (fp_text reference "J7" (at 17.09 3.38 180) (layer "B.SilkS")
      (effects (font (size 0.7 0.7) (thickness 0.15)) (justify left bottom mirror))
    )
    (fp_text value "Conn_FFC_WE_68715014522_TWO-SIDES" (at -0.3 -3.899 180) (layer "B.Fab")
      (effects (font (size 0.7 0.7) (thickness 0.15)) (justify left bottom mirror))
    )
    (fp_text user "License: Apache-2.0" (at -15.861 -7.9 180) (layer "B.Fab") hide
      (effects (font (size 0.7 0.7) (thickness 0.15)) (justify left bottom mirror))
    )
    (fp_text user "Author: Antmicro" (at -15.861 -6.9 180) (layer "B.Fab") hide
      (effects (font (size 0.7 0.7) (thickness 0.15)) (justify left bottom mirror))
    )
    (fp_text user "${REFERENCE}" (at -15.861 -5.9 180) (layer "B.Fab") hide
      (effects (font (size 0.7 0.7) (thickness 0.15)) (justify left bottom mirror))
    )
    (fp_line (start 12.499 2.15) (end 12.499 2.976) (layer "B.SilkS") (width 0.15))
    (fp_line (start -12.5 2.15) (end -12.5 3.4) (layer "B.SilkS") (width 0.15))
    (fp_line (start 15.839 -1.29) (end 15.839 2.15) (layer "B.SilkS") (width 0.15))
    (fp_line (start -15.861 -1.298) (end -15.861 2.15) (layer "B.SilkS") (width 0.15))
    (fp_line (start -15.83 2.15) (end -12.5 2.15) (layer "B.SilkS") (width 0.15))
    (fp_line (start 12.499 1.325) (end 12.499 -1.259) (layer "B.SilkS") (width 0.15))
    (fp_line (start 12.499 -1.29) (end 15.839 -1.29) (layer "B.SilkS") (width 0.15))
    (fp_line (start -12.5 2.976) (end 12.499 2.976) (layer "B.SilkS") (width 0.15))
    (fp_line (start 15.81 2.15) (end 12.499 2.15) (layer "B.SilkS") (width 0.15))
    (fp_line (start -12.561 -1.33) (end -15.84 -1.33) (layer "B.SilkS") (width 0.15))
    (fp_line (start -12.5 1.325) (end 12.499 1.325) (layer "B.SilkS") (width 0.15))
    (fp_line (start -12.5 1.325) (end -12.5 -1.33) (layer "B.SilkS") (width 0.15))
    (fp_circle (center -12.25 3.86) (end -12.2 3.81) (layer "B.SilkS") (width 0.15) (fill solid))
    (fp_rect (start -16.201 6.001) (end 16.198 -3.548) (layer "B.CrtYd") (width 0.05) (fill none))
    (pad "1" smd roundrect locked (at -12.25 2.15) (size 0.3 1.2) (layers "B.Cu" "B.Paste" "B.Mask") (roundrect_rratio 0.25)
      (net 283 "/Camera Interface/CSI1_LN3_FFC_N") (pintype "passive"))
    (pad "2" smd roundrect locked (at -11.75 2.15) (size 0.3 1.2) (layers "B.Cu" "B.Paste" "B.Mask") (roundrect_rratio 0.25)
      (net 282 "/Camera Interface/CSI1_LN3_FFC_P") (pintype "passive"))
    (pad "3" smd roundrect locked (at -11.25 2.15) (size 0.3 1.2) (layers "B.Cu" "B.Paste" "B.Mask") (roundrect_rratio 0.25)
      (net 279 "/Camera Interface/CSI1_LN2_FFC_N") (pintype "passive"))
    (pad "4" smd roundrect locked (at -10.75 2.15) (size 0.3 1.2) (layers "B.Cu" "B.Paste" "B.Mask") (roundrect_rratio 0.25)
      (net 278 "/Camera Interface/CSI1_LN2_FFC_P") (pintype "passive"))
    (pad "5" smd roundrect locked (at -10.25 2.15) (size 0.3 1.2) (layers "B.Cu" "B.Paste" "B.Mask") (roundrect_rratio 0.25)
      (net 273 "/Camera Interface/CSI1_LN1_FFC_N") (pintype "passive"))
    (pad "6" smd roundrect locked (at -9.75 2.15) (size 0.3 1.2) (layers "B.Cu" "B.Paste" "B.Mask") (roundrect_rratio 0.25)
      (net 272 "/Camera Interface/CSI1_LN1_FFC_P") (pintype "passive"))
    (pad "7" smd roundrect locked (at -9.25 2.15) (size 0.3 1.2) (layers "B.Cu" "B.Paste" "B.Mask") (roundrect_rratio 0.25)
      (net 269 "/Camera Interface/CSI1_LN0_FFC_N") (pintype "passive"))
    (pad "8" smd roundrect locked (at -8.75 2.15) (size 0.3 1.2) (layers "B.Cu" "B.Paste" "B.Mask") (roundrect_rratio 0.25)
      (net 268 "/Camera Interface/CSI1_LN0_FFC_P") (pintype "passive"))
    (pad "9" smd roundrect locked (at -8.25 2.15) (size 0.3 1.2) (layers "B.Cu" "B.Paste" "B.Mask") (roundrect_rratio 0.25)
      (net 1 "GND") (pintype "passive"))
    (pad "10" smd roundrect locked (at -7.75 2.15) (size 0.3 1.2) (layers "B.Cu" "B.Paste" "B.Mask") (roundrect_rratio 0.25)
      (net 275 "/Camera Interface/CSI1_CLK_FFC_N") (pintype "passive"))
    (pad "11" smd roundrect locked (at -7.25 2.15) (size 0.3 1.2) (layers "B.Cu" "B.Paste" "B.Mask") (roundrect_rratio 0.25)
      (net 274 "/Camera Interface/CSI1_CLK_FFC_P") (pintype "passive"))
    (pad "12" smd roundrect locked (at -6.75 2.15) (size 0.3 1.2) (layers "B.Cu" "B.Paste" "B.Mask") (roundrect_rratio 0.25)
      (net 1 "GND") (pintype "passive"))
    (pad "13" smd roundrect locked (at -6.25 2.15) (size 0.3 1.2) (layers "B.Cu" "B.Paste" "B.Mask") (roundrect_rratio 0.25)
      (net 451 "unconnected-(J7-Pad13)") (pintype "passive+no_connect"))
    (pad "14" smd roundrect locked (at -5.75 2.15) (size 0.3 1.2) (layers "B.Cu" "B.Paste" "B.Mask") (roundrect_rratio 0.25)
      (net 450 "unconnected-(J7-Pad14)") (pintype "passive+no_connect"))
    (pad "15" smd roundrect locked (at -5.25 2.15) (size 0.3 1.2) (layers "B.Cu" "B.Paste" "B.Mask") (roundrect_rratio 0.25)
      (net 1 "GND") (pintype "passive"))
    (pad "16" smd roundrect locked (at -4.75 2.15) (size 0.3 1.2) (layers "B.Cu" "B.Paste" "B.Mask") (roundrect_rratio 0.25)
      (net 449 "unconnected-(J7-Pad16)") (pintype "passive+no_connect"))
    (pad "17" smd roundrect locked (at -4.25 2.15) (size 0.3 1.2) (layers "B.Cu" "B.Paste" "B.Mask") (roundrect_rratio 0.25)
      (net 448 "unconnected-(J7-Pad17)") (pintype "passive+no_connect"))
    (pad "18" smd roundrect locked (at -3.75 2.15) (size 0.3 1.2) (layers "B.Cu" "B.Paste" "B.Mask") (roundrect_rratio 0.25)
      (net 1 "GND") (pintype "passive"))
    (pad "19" smd roundrect locked (at -3.25 2.15) (size 0.3 1.2) (layers "B.Cu" "B.Paste" "B.Mask") (roundrect_rratio 0.25)
      (net 281 "/Camera Interface/CSI0_LN3_FFC_N") (pintype "passive"))
    (pad "20" smd roundrect locked (at -2.75 2.15) (size 0.3 1.2) (layers "B.Cu" "B.Paste" "B.Mask") (roundrect_rratio 0.25)
      (net 280 "/Camera Interface/CSI0_LN3_FFC_P") (pintype "passive"))
    (pad "21" smd roundrect locked (at -2.25 2.15) (size 0.3 1.2) (layers "B.Cu" "B.Paste" "B.Mask") (roundrect_rratio 0.25)
      (net 277 "/Camera Interface/CSI0_LN2_FFC_N") (pintype "passive"))
    (pad "22" smd roundrect locked (at -1.75 2.15) (size 0.3 1.2) (layers "B.Cu" "B.Paste" "B.Mask") (roundrect_rratio 0.25)
      (net 276 "/Camera Interface/CSI0_LN2_FFC_P") (pintype "passive"))
    (pad "23" smd roundrect locked (at -1.25 2.15) (size 0.3 1.2) (layers "B.Cu" "B.Paste" "B.Mask") (roundrect_rratio 0.25)
      (net 271 "/Camera Interface/CSI0_LN1_FFC_N") (pintype "passive"))
    (pad "24" smd roundrect locked (at -0.75 2.15) (size 0.3 1.2) (layers "B.Cu" "B.Paste" "B.Mask") (roundrect_rratio 0.25)
      (net 270 "/Camera Interface/CSI0_LN1_FFC_P") (pintype "passive"))
    (pad "25" smd roundrect locked (at -0.25 2.15) (size 0.3 1.2) (layers "B.Cu" "B.Paste" "B.Mask") (roundrect_rratio 0.25)
      (net 267 "/Camera Interface/CSI0_LN0_FFC_N") (pintype "passive"))
    (pad "26" smd roundrect locked (at 0.248 2.15) (size 0.3 1.2) (layers "B.Cu" "B.Paste" "B.Mask") (roundrect_rratio 0.25)
      (net 266 "/Camera Interface/CSI0_LN0_FFC_P") (pintype "passive"))
    (pad "27" smd roundrect locked (at 0.748 2.15) (size 0.3 1.2) (layers "B.Cu" "B.Paste" "B.Mask") (roundrect_rratio 0.25)
      (net 1 "GND") (pintype "passive"))
    (pad "28" smd roundrect locked (at 1.249 2.15) (size 0.3 1.2) (layers "B.Cu" "B.Paste" "B.Mask") (roundrect_rratio 0.25)
      (net 325 "/Camera Interface/CSI0_CLK_FFC_N") (pintype "passive"))
    (pad "29" smd roundrect locked (at 1.749 2.15) (size 0.3 1.2) (layers "B.Cu" "B.Paste" "B.Mask") (roundrect_rratio 0.25)
      (net 324 "/Camera Interface/CSI0_CLK_FFC_P") (pintype "passive"))
    (pad "30" smd roundrect locked (at 2.249 2.15) (size 0.3 1.2) (layers "B.Cu" "B.Paste" "B.Mask") (roundrect_rratio 0.25)
      (net 1 "GND") (pintype "passive"))
    (pad "31" smd roundrect locked (at 2.749 2.15) (size 0.3 1.2) (layers "B.Cu" "B.Paste" "B.Mask") (roundrect_rratio 0.25)
      (net 447 "unconnected-(J7-Pad31)") (pintype "passive+no_connect"))
    (pad "32" smd roundrect locked (at 3.249 2.15) (size 0.3 1.2) (layers "B.Cu" "B.Paste" "B.Mask") (roundrect_rratio 0.25)
      (net 14 "CAM0_PWDN") (pintype "passive"))
    (pad "33" smd roundrect locked (at 3.749 2.15) (size 0.3 1.2) (layers "B.Cu" "B.Paste" "B.Mask") (roundrect_rratio 0.25)
      (net 15 "CAM0_RST") (pintype "passive"))
    (pad "34" smd roundrect locked (at 4.248 2.15) (size 0.3 1.2) (layers "B.Cu" "B.Paste" "B.Mask") (roundrect_rratio 0.25)
      (net 16 "CAM1_PWDN") (pintype "passive"))
    (pad "35" smd roundrect locked (at 4.748 2.15) (size 0.3 1.2) (layers "B.Cu" "B.Paste" "B.Mask") (roundrect_rratio 0.25)
      (net 446 "unconnected-(J7-Pad35)") (pintype "passive+no_connect"))
    (pad "36" smd roundrect locked (at 5.248 2.15) (size 0.3 1.2) (layers "B.Cu" "B.Paste" "B.Mask") (roundrect_rratio 0.25)
      (net 445 "unconnected-(J7-Pad36)") (pintype "passive+no_connect"))
    (pad "37" smd roundrect locked (at 5.749 2.15) (size 0.3 1.2) (layers "B.Cu" "B.Paste" "B.Mask") (roundrect_rratio 0.25)
      (net 444 "unconnected-(J7-Pad37)") (pintype "passive+no_connect"))
    (pad "38" smd roundrect locked (at 6.249 2.15) (size 0.3 1.2) (layers "B.Cu" "B.Paste" "B.Mask") (roundrect_rratio 0.25)
      (net 443 "unconnected-(J7-Pad38)") (pintype "passive+no_connect"))
    (pad "39" smd roundrect locked (at 6.749 2.15) (size 0.3 1.2) (layers "B.Cu" "B.Paste" "B.Mask") (roundrect_rratio 0.25)
      (net 296 "/Camera Interface/CCI0_I2C_SDA_3V3") (pintype "passive"))
    (pad "40" smd roundrect locked (at 7.249 2.15) (size 0.3 1.2) (layers "B.Cu" "B.Paste" "B.Mask") (roundrect_rratio 0.25)
      (net 294 "/Camera Interface/CCI0_I2C_SCL_3V3") (pintype "passive"))
    (pad "41" smd roundrect locked (at 7.749 2.15) (size 0.3 1.2) (layers "B.Cu" "B.Paste" "B.Mask") (roundrect_rratio 0.25)
      (net 295 "/Camera Interface/CCI1_I2C_SDA_3V3") (pintype "passive"))
    (pad "42" smd roundrect locked (at 8.249 2.15) (size 0.3 1.2) (layers "B.Cu" "B.Paste" "B.Mask") (roundrect_rratio 0.25)
      (net 293 "/Camera Interface/CCI1_I2C_SCL_3V3") (pintype "passive"))
    (pad "43" smd roundrect locked (at 8.749 2.15) (size 0.3 1.2) (layers "B.Cu" "B.Paste" "B.Mask") (roundrect_rratio 0.25)
      (net 442 "unconnected-(J7-Pad43)") (pintype "passive+no_connect"))
    (pad "44" smd roundrect locked (at 9.249 2.15) (size 0.3 1.2) (layers "B.Cu" "B.Paste" "B.Mask") (roundrect_rratio 0.25)
      (net 441 "unconnected-(J7-Pad44)") (pintype "passive+no_connect"))
    (pad "45" smd roundrect locked (at 9.749 2.15) (size 0.3 1.2) (layers "B.Cu" "B.Paste" "B.Mask") (roundrect_rratio 0.25)
      (net 440 "unconnected-(J7-Pad45)") (pintype "passive+no_connect"))
    (pad "46" smd roundrect locked (at 10.249 2.15) (size 0.3 1.2) (layers "B.Cu" "B.Paste" "B.Mask") (roundrect_rratio 0.25)
      (net 439 "unconnected-(J7-Pad46)") (pintype "passive+no_connect"))
    (pad "47" smd roundrect locked (at 10.749 2.15) (size 0.3 1.2) (layers "B.Cu" "B.Paste" "B.Mask") (roundrect_rratio 0.25)
      (net 231 "/Camera Interface/3V3_CAM") (pintype "passive"))
    (pad "48" smd roundrect locked (at 11.249 2.15) (size 0.3 1.2) (layers "B.Cu" "B.Paste" "B.Mask") (roundrect_rratio 0.25)
      (net 231 "/Camera Interface/3V3_CAM") (pintype "passive"))
    (pad "49" smd roundrect locked (at 11.749 2.15) (size 0.3 1.2) (layers "B.Cu" "B.Paste" "B.Mask") (roundrect_rratio 0.25)
      (net 133 "5V_SYS") (pintype "passive"))
    (pad "50" smd roundrect locked (at 12.249 2.15) (size 0.3 1.2) (layers "B.Cu" "B.Paste" "B.Mask") (roundrect_rratio 0.25)
      (net 133 "5V_SYS") (pintype "passive"))
    (pad "SH1" smd roundrect locked (at -14.201 4) (size 2.7 3) (layers "B.Cu" "B.Paste" "B.Mask") (roundrect_rratio 0.05)
      (net 664 "unconnected-(J7-PadSH1)") (pinfunction "SH") (pintype "passive+no_connect"))
    (pad "SH1" smd roundrect locked (at -14.198 0.3) (size 2.7 3) (layers "B.Cu" "B.Paste" "B.Mask") (roundrect_rratio 0.05)
      (net 664 "unconnected-(J7-PadSH1)") (pinfunction "SH") (pintype "passive+no_connect"))
    (pad "SH2" smd roundrect locked (at 14.198 4) (size 2.7 3) (layers "B.Cu" "B.Paste" "B.Mask") (roundrect_rratio 0.05)
      (net 665 "unconnected-(J7-PadSH2)") (pinfunction "SH") (pintype "passive+no_connect"))
    (pad "SH2" smd roundrect locked (at 14.198 0.3) (size 2.7 3) (layers "B.Cu" "B.Paste" "B.Mask") (roundrect_rratio 0.05)
      (net 665 "unconnected-(J7-PadSH2)") (pinfunction "SH") (pintype "passive+no_connect"))
  )

  (footprint "sa800u-baseboard-hw-footprints:R_0402_1005Metric" (layer "B.Cu")
    (tedit 5FD9C158)
    (at 72.9 145.3)
    (descr "Resistor SMD 0402")
    (tags "resistor SMD 0402")
    (property "Author" "Antmicro")
    (property "License" "Apache-2.0")
    (property "MPN" "CR0402-FX-4700GLF")
    (property "Manufacturer" "Bourns")
    (property "Sheetfile" "ethernet-controller.kicad_sch")
    (property "Sheetname" "Ethernet Controller")
    (property "Tolerance" "1%")
    (property "Val" "470R")
    (attr smd)
    (fp_text reference "R13" (at 1.09 -1.55 180) (layer "B.SilkS")
      (effects (font (size 0.7 0.7) (thickness 0.15)) (justify left bottom mirror))
    )
    (fp_text value "R_470R_0402" (at 0 -1.4 180) (layer "B.Fab")
      (effects (font (size 0.7 0.7) (thickness 0.15)) (justify left bottom mirror))
    )
    (fp_text user "${REFERENCE}" (at -0.95 -3.168 180) (layer "B.Fab") hide
      (effects (font (size 0.7 0.7) (thickness 0.15)) (justify left bottom mirror))
    )
    (fp_text user "Author: Antmicro" (at -0.95 -4.169 180) (layer "B.Fab") hide
      (effects (font (size 0.7 0.7) (thickness 0.15)) (justify left bottom mirror))
    )
    (fp_text user "License: Apache-2.0" (at -0.95 -5.169 180) (layer "B.Fab") hide
      (effects (font (size 0.7 0.7) (thickness 0.15)) (justify left bottom mirror))
    )
    (fp_rect (start -0.93 0.47) (end 0.93 -0.47) (layer "B.CrtYd") (width 0.05) (fill none))
    (fp_rect (start -0.5 0.25) (end 0.5 -0.25) (layer "B.Fab") (width 0.15) (fill none))
    (pad "1" smd roundrect (at -0.485 0) (size 0.59 0.64) (layers "B.Cu" "B.Paste" "B.Mask") (roundrect_rratio 0.25)
      (net 78 "Net-(J1-Pad17)") (pintype "passive"))
    (pad "2" smd roundrect (at 0.485 0) (size 0.59 0.64) (layers "B.Cu" "B.Paste" "B.Mask") (roundrect_rratio 0.25)
      (net 177 "/Ethernet Controller/ETH_3V3") (pintype "passive"))
  )

  (footprint "sa800u-baseboard-hw-footprints:R_0402_1005Metric" (layer "B.Cu")
    (tedit 5FD9C158)
    (at 72.9 144.3)
    (descr "Resistor SMD 0402")
    (tags "resistor SMD 0402")
    (property "Author" "Antmicro")
    (property "License" "Apache-2.0")
    (property "MPN" "CR0402-FX-4700GLF")
    (property "Manufacturer" "Bourns")
    (property "Sheetfile" "ethernet-controller.kicad_sch")
    (property "Sheetname" "Ethernet Controller")
    (property "Tolerance" "1%")
    (property "Val" "470R")
    (attr smd)
    (fp_text reference "R14" (at 1.09 -1.55 180) (layer "B.SilkS")
      (effects (font (size 0.7 0.7) (thickness 0.15)) (justify left bottom mirror))
    )
    (fp_text value "R_470R_0402" (at 0 -1.4 180) (layer "B.Fab")
      (effects (font (size 0.7 0.7) (thickness 0.15)) (justify left bottom mirror))
    )
    (fp_text user "Author: Antmicro" (at -0.95 -4.169 180) (layer "B.Fab") hide
      (effects (font (size 0.7 0.7) (thickness 0.15)) (justify left bottom mirror))
    )
    (fp_text user "License: Apache-2.0" (at -0.95 -5.169 180) (layer "B.Fab") hide
      (effects (font (size 0.7 0.7) (thickness 0.15)) (justify left bottom mirror))
    )
    (fp_text user "${REFERENCE}" (at -0.95 -3.168 180) (layer "B.Fab") hide
      (effects (font (size 0.7 0.7) (thickness 0.15)) (justify left bottom mirror))
    )
    (fp_rect (start -0.93 0.47) (end 0.93 -0.47) (layer "B.CrtYd") (width 0.05) (fill none))
    (fp_rect (start -0.5 0.25) (end 0.5 -0.25) (layer "B.Fab") (width 0.15) (fill none))
    (pad "1" smd roundrect (at -0.485 0) (size 0.59 0.64) (layers "B.Cu" "B.Paste" "B.Mask") (roundrect_rratio 0.25)
      (net 77 "Net-(J1-Pad15)") (pintype "passive"))
    (pad "2" smd roundrect (at 0.485 0) (size 0.59 0.64) (layers "B.Cu" "B.Paste" "B.Mask") (roundrect_rratio 0.25)
      (net 177 "/Ethernet Controller/ETH_3V3") (pintype "passive"))
  )

  (footprint "sa800u-baseboard-hw-footprints:R_0402_1005Metric" (layer "B.Cu")
    (tedit 5FD9C158)
    (at 116.845 113.6 90)
    (descr "Resistor SMD 0402")
    (tags "resistor SMD 0402")
    (property "Author" "Antmicro")
    (property "License" "Apache-2.0")
    (property "MPN" "CR0402-FX-4701GLF")
    (property "Manufacturer" "Bourns")
    (property "Sheetfile" "hdmi-converter.kicad_sch")
    (property "Sheetname" "HDMI converter")
    (property "Tolerance" "1%")
    (property "Val" "4k7")
    (attr smd)
    (fp_text reference "R23" (at 1.12 -0.58 270) (layer "B.SilkS")
      (effects (font (size 0.7 0.7) (thickness 0.15)) (justify left bottom mirror))
    )
    (fp_text value "R_4k7_0402" (at 0 -1.4 270) (layer "B.Fab")
      (effects (font (size 0.7 0.7) (thickness 0.15)) (justify left bottom mirror))
    )
    (fp_text user "Author: Antmicro" (at -0.95 -4.169 270) (layer "B.Fab") hide
      (effects (font (size 0.7 0.7) (thickness 0.15)) (justify left bottom mirror))
    )
    (fp_text user "${REFERENCE}" (at -0.95 -3.168 270) (layer "B.Fab") hide
      (effects (font (size 0.7 0.7) (thickness 0.15)) (justify left bottom mirror))
    )
    (fp_text user "License: Apache-2.0" (at -0.95 -5.169 270) (layer "B.Fab") hide
      (effects (font (size 0.7 0.7) (thickness 0.15)) (justify left bottom mirror))
    )
    (fp_rect (start -0.93 0.47) (end 0.93 -0.47) (layer "B.CrtYd") (width 0.05) (fill none))
    (fp_rect (start -0.5 0.25) (end 0.5 -0.25) (layer "B.Fab") (width 0.15) (fill none))
    (pad "1" smd roundrect (at -0.485 0 90) (size 0.59 0.64) (layers "B.Cu" "B.Paste" "B.Mask") (roundrect_rratio 0.25)
      (net 132 "VREG_S4A_1V8") (pintype "passive"))
    (pad "2" smd roundrect (at 0.485 0 90) (size 0.59 0.64) (layers "B.Cu" "B.Paste" "B.Mask") (roundrect_rratio 0.25)
      (net 35 "LT9611_GPIO5") (pintype "passive"))
  )

  (footprint "sa800u-baseboard-hw-footprints:R_0402_1005Metric" (layer "B.Cu")
    (tedit 5FD9C158)
    (at 116.9 116.2 90)
    (descr "Resistor SMD 0402")
    (tags "resistor SMD 0402")
    (property "Author" "Antmicro")
    (property "License" "Apache-2.0")
    (property "MPN" "CR0402-FX-4701GLF")
    (property "Manufacturer" "Bourns")
    (property "Sheetfile" "hdmi-converter.kicad_sch")
    (property "Sheetname" "HDMI converter")
    (property "Tolerance" "1%")
    (property "Val" "4k7")
    (attr smd)
    (fp_text reference "R24" (at 1.15 -0.58 270) (layer "B.SilkS")
      (effects (font (size 0.7 0.7) (thickness 0.15)) (justify left bottom mirror))
    )
    (fp_text value "R_4k7_0402" (at 0 -1.4 270) (layer "B.Fab")
      (effects (font (size 0.7 0.7) (thickness 0.15)) (justify left bottom mirror))
    )
    (fp_text user "License: Apache-2.0" (at -0.95 -5.169 270) (layer "B.Fab") hide
      (effects (font (size 0.7 0.7) (thickness 0.15)) (justify left bottom mirror))
    )
    (fp_text user "${REFERENCE}" (at -0.95 -3.168 270) (layer "B.Fab") hide
      (effects (font (size 0.7 0.7) (thickness 0.15)) (justify left bottom mirror))
    )
    (fp_text user "Author: Antmicro" (at -0.95 -4.169 270) (layer "B.Fab") hide
      (effects (font (size 0.7 0.7) (thickness 0.15)) (justify left bottom mirror))
    )
    (fp_rect (start -0.93 0.47) (end 0.93 -0.47) (layer "B.CrtYd") (width 0.05) (fill none))
    (fp_rect (start -0.5 0.25) (end 0.5 -0.25) (layer "B.Fab") (width 0.15) (fill none))
    (pad "1" smd roundrect (at -0.485 0 90) (size 0.59 0.64) (layers "B.Cu" "B.Paste" "B.Mask") (roundrect_rratio 0.25)
      (net 132 "VREG_S4A_1V8") (pintype "passive"))
    (pad "2" smd roundrect (at 0.485 0 90) (size 0.59 0.64) (layers "B.Cu" "B.Paste" "B.Mask") (roundrect_rratio 0.25)
      (net 36 "LT9611_RST") (pintype "passive"))
  )

  (footprint "sa800u-baseboard-hw-footprints:R_0402_1005Metric" (layer "B.Cu")
    (tedit 5FD9C158)
    (at 120.8 113.9 90)
    (descr "Resistor SMD 0402")
    (tags "resistor SMD 0402")
    (property "Author" "Antmicro")
    (property "License" "Apache-2.0")
    (property "MPN" "CR0402-FX-4701GLF")
    (property "Manufacturer" "Bourns")
    (property "Sheetfile" "hdmi-converter.kicad_sch")
    (property "Sheetname" "HDMI converter")
    (property "Tolerance" "1%")
    (property "Val" "4k7")
    (attr smd)
    (fp_text reference "R25" (at 1.19 1.37 270) (layer "B.SilkS")
      (effects (font (size 0.7 0.7) (thickness 0.15)) (justify left bottom mirror))
    )
    (fp_text value "R_4k7_0402" (at 0 -1.4 270) (layer "B.Fab")
      (effects (font (size 0.7 0.7) (thickness 0.15)) (justify left bottom mirror))
    )
    (fp_text user "License: Apache-2.0" (at -0.95 -5.169 270) (layer "B.Fab") hide
      (effects (font (size 0.7 0.7) (thickness 0.15)) (justify left bottom mirror))
    )
    (fp_text user "${REFERENCE}" (at -0.95 -3.168 270) (layer "B.Fab") hide
      (effects (font (size 0.7 0.7) (thickness 0.15)) (justify left bottom mirror))
    )
    (fp_text user "Author: Antmicro" (at -0.95 -4.169 270) (layer "B.Fab") hide
      (effects (font (size 0.7 0.7) (thickness 0.15)) (justify left bottom mirror))
    )
    (fp_rect (start -0.93 0.47) (end 0.93 -0.47) (layer "B.CrtYd") (width 0.05) (fill none))
    (fp_rect (start -0.5 0.25) (end 0.5 -0.25) (layer "B.Fab") (width 0.15) (fill none))
    (pad "1" smd roundrect (at -0.485 0 90) (size 0.59 0.64) (layers "B.Cu" "B.Paste" "B.Mask") (roundrect_rratio 0.25)
      (net 131 "3V3_SYS") (pintype "passive"))
    (pad "2" smd roundrect (at 0.485 0 90) (size 0.59 0.64) (layers "B.Cu" "B.Paste" "B.Mask") (roundrect_rratio 0.25)
      (net 284 "/HDMI converter/LT9611_INTO_GPIO5") (pintype "passive"))
  )

  (footprint "sa800u-baseboard-hw-footprints:R_0402_1005Metric" (layer "B.Cu")
    (tedit 5FD9C158)
    (at 120.8 115.9 -90)
    (descr "Resistor SMD 0402")
    (tags "resistor SMD 0402")
    (property "Author" "Antmicro")
    (property "License" "Apache-2.0")
    (property "MPN" "CR0402-FX-4701GLF")
    (property "Manufacturer" "Bourns")
    (property "Sheetfile" "hdmi-converter.kicad_sch")
    (property "Sheetname" "HDMI converter")
    (property "Tolerance" "1%")
    (property "Val" "4k7")
    (attr smd)
    (fp_text reference "R26" (at -1.22 -2.38 90) (layer "B.SilkS")
      (effects (font (size 0.7 0.7) (thickness 0.15)) (justify left bottom mirror))
    )
    (fp_text value "R_4k7_0402" (at 0 -1.4 90) (layer "B.Fab")
      (effects (font (size 0.7 0.7) (thickness 0.15)) (justify left bottom mirror))
    )
    (fp_text user "Author: Antmicro" (at -0.95 -4.169 90) (layer "B.Fab") hide
      (effects (font (size 0.7 0.7) (thickness 0.15)) (justify left bottom mirror))
    )
    (fp_text user "License: Apache-2.0" (at -0.95 -5.169 90) (layer "B.Fab") hide
      (effects (font (size 0.7 0.7) (thickness 0.15)) (justify left bottom mirror))
    )
    (fp_text user "${REFERENCE}" (at -0.95 -3.168 90) (layer "B.Fab") hide
      (effects (font (size 0.7 0.7) (thickness 0.15)) (justify left bottom mirror))
    )
    (fp_rect (start -0.93 0.47) (end 0.93 -0.47) (layer "B.CrtYd") (width 0.05) (fill none))
    (fp_rect (start -0.5 0.25) (end 0.5 -0.25) (layer "B.Fab") (width 0.15) (fill none))
    (pad "1" smd roundrect (at -0.485 0 270) (size 0.59 0.64) (layers "B.Cu" "B.Paste" "B.Mask") (roundrect_rratio 0.25)
      (net 131 "3V3_SYS") (pintype "passive"))
    (pad "2" smd roundrect (at 0.485 0 270) (size 0.59 0.64) (layers "B.Cu" "B.Paste" "B.Mask") (roundrect_rratio 0.25)
      (net 186 "/HDMI converter/LT9611_RST_N") (pintype "passive"))
  )

  (footprint "sa800u-baseboard-hw-footprints:R_0402_1005Metric" (layer "B.Cu")
    (tedit 5FD9C158)
    (at 59.6 113.8 180)
    (descr "Resistor SMD 0402")
    (tags "resistor SMD 0402")
    (property "Author" "Antmicro")
    (property "License" "Apache-2.0")
    (property "MPN" "CR0402-FX-63R4GLF")
    (property "Manufacturer" "Bourns")
    (property "Sheetfile" "poe.kicad_sch")
    (property "Sheetname" "PoE")
    (property "Tolerance" "1%")
    (property "Val" "63R4")
    (attr smd)
    (fp_text reference "R144" (at 0.91 -0.37) (layer "B.SilkS")
      (effects (font (size 0.7 0.7) (thickness 0.15)) (justify left bottom mirror))
    )
    (fp_text value "R_63R4_0402" (at 0 -1.4) (layer "B.Fab")
      (effects (font (size 0.7 0.7) (thickness 0.15)) (justify left bottom mirror))
    )
    (fp_text user "License: Apache-2.0" (at -0.95 -5.169) (layer "B.Fab") hide
      (effects (font (size 0.7 0.7) (thickness 0.15)) (justify left bottom mirror))
    )
    (fp_text user "Author: Antmicro" (at -0.95 -4.169) (layer "B.Fab") hide
      (effects (font (size 0.7 0.7) (thickness 0.15)) (justify left bottom mirror))
    )
    (fp_text user "${REFERENCE}" (at -0.95 -3.168) (layer "B.Fab") hide
      (effects (font (size 0.7 0.7) (thickness 0.15)) (justify left bottom mirror))
    )
    (fp_rect (start -0.93 0.47) (end 0.93 -0.47) (layer "B.CrtYd") (width 0.05) (fill none))
    (fp_rect (start -0.5 0.25) (end 0.5 -0.25) (layer "B.Fab") (width 0.15) (fill none))
    (pad "1" smd roundrect (at -0.485 0 180) (size 0.59 0.64) (layers "B.Cu" "B.Paste" "B.Mask") (roundrect_rratio 0.25)
      (net 146 "/PoE/CLS") (pintype "passive"))
    (pad "2" smd roundrect (at 0.485 0 180) (size 0.59 0.64) (layers "B.Cu" "B.Paste" "B.Mask") (roundrect_rratio 0.25)
      (net 135 "/PoE/VSS_POE") (pintype "passive"))
  )

  (footprint "sa800u-baseboard-hw-footprints:R_0402_1005Metric" (layer "B.Cu")
    (tedit 5FD9C158)
    (at 75.6 96.1 -90)
    (descr "Resistor SMD 0402")
    (tags "resistor SMD 0402")
    (property "Author" "Antmicro")
    (property "Current" "1A")
    (property "DNP" "DNP")
    (property "License" "Apache-2.0")
    (property "MPN" "ERJ2GE0R00X")
    (property "Manufacturer" "Panasonic")
    (property "Sheetfile" "poe.kicad_sch")
    (property "Sheetname" "PoE")
    (property "Tolerance" "")
    (property "Val" "0R")
    (attr exclude_from_pos_files)
    (fp_text reference "R151" (at -1.27 0.57 90) (layer "B.SilkS")
      (effects (font (size 0.7 0.7) (thickness 0.15)) (justify left bottom mirror))
    )
    (fp_text value "R_0R_0402" (at 0 -1.4 90) (layer "B.Fab")
      (effects (font (size 0.7 0.7) (thickness 0.15)) (justify left bottom mirror))
    )
    (fp_text user "License: Apache-2.0" (at -0.95 -5.169 90) (layer "B.Fab") hide
      (effects (font (size 0.7 0.7) (thickness 0.15)) (justify left bottom mirror))
    )
    (fp_text user "Author: Antmicro" (at -0.95 -4.169 90) (layer "B.Fab") hide
      (effects (font (size 0.7 0.7) (thickness 0.15)) (justify left bottom mirror))
    )
    (fp_text user "${REFERENCE}" (at -0.95 -3.168 90) (layer "B.Fab") hide
      (effects (font (size 0.7 0.7) (thickness 0.15)) (justify left bottom mirror))
    )
    (fp_rect (start -0.93 0.47) (end 0.93 -0.47) (layer "B.CrtYd") (width 0.05) (fill none))
    (fp_rect (start -0.5 0.25) (end 0.5 -0.25) (layer "B.Fab") (width 0.15) (fill none))
    (pad "1" smd roundrect (at -0.485 0 270) (size 0.59 0.64) (layers "B.Cu" "B.Paste" "B.Mask") (roundrect_rratio 0.25)
      (net 153 "/PoE/TRIM") (pintype "passive"))
    (pad "2" smd roundrect (at 0.485 0 270) (size 0.59 0.64) (layers "B.Cu" "B.Paste" "B.Mask") (roundrect_rratio 0.25)
      (net 136 "5V_POE") (pintype "passive"))
  )

  (footprint "sa800u-baseboard-hw-footprints:R_0402_1005Metric" (layer "B.Cu")
    (tedit 5FD9C158)
    (at 75.6 94.1 90)
    (descr "Resistor SMD 0402")
    (tags "resistor SMD 0402")
    (property "Author" "Antmicro")
    (property "Current" "1A")
    (property "DNP" "DNP")
    (property "License" "Apache-2.0")
    (property "MPN" "ERJ2GE0R00X")
    (property "Manufacturer" "Panasonic")
    (property "Sheetfile" "poe.kicad_sch")
    (property "Sheetname" "PoE")
    (property "Tolerance" "")
    (property "Val" "0R")
    (attr exclude_from_pos_files)
    (fp_text reference "R152" (at 2 -0.57 270) (layer "B.SilkS")
      (effects (font (size 0.7 0.7) (thickness 0.15)) (justify left bottom mirror))
    )
    (fp_text value "R_0R_0402" (at 0 -1.4 270) (layer "B.Fab")
      (effects (font (size 0.7 0.7) (thickness 0.15)) (justify left bottom mirror))
    )
    (fp_text user "${REFERENCE}" (at -0.95 -3.168 270) (layer "B.Fab") hide
      (effects (font (size 0.7 0.7) (thickness 0.15)) (justify left bottom mirror))
    )
    (fp_text user "License: Apache-2.0" (at -0.95 -5.169 270) (layer "B.Fab") hide
      (effects (font (size 0.7 0.7) (thickness 0.15)) (justify left bottom mirror))
    )
    (fp_text user "Author: Antmicro" (at -0.95 -4.169 270) (layer "B.Fab") hide
      (effects (font (size 0.7 0.7) (thickness 0.15)) (justify left bottom mirror))
    )
    (fp_rect (start -0.93 0.47) (end 0.93 -0.47) (layer "B.CrtYd") (width 0.05) (fill none))
    (fp_rect (start -0.5 0.25) (end 0.5 -0.25) (layer "B.Fab") (width 0.15) (fill none))
    (pad "1" smd roundrect (at -0.485 0 90) (size 0.59 0.64) (layers "B.Cu" "B.Paste" "B.Mask") (roundrect_rratio 0.25)
      (net 153 "/PoE/TRIM") (pintype "passive"))
    (pad "2" smd roundrect (at 0.485 0 90) (size 0.59 0.64) (layers "B.Cu" "B.Paste" "B.Mask") (roundrect_rratio 0.25)
      (net 1 "GND") (pintype "passive"))
  )

  (footprint "sa800u-baseboard-hw-footprints:R_0402_1005Metric" (layer "B.Cu")
    (tedit 5FD9C158)
    (at 60.1 104.7 90)
    (descr "Resistor SMD 0402")
    (tags "resistor SMD 0402")
    (property "Author" "Antmicro")
    (property "Current" "1A")
    (property "License" "Apache-2.0")
    (property "MPN" "ERJ2GE0R00X")
    (property "Manufacturer" "Panasonic")
    (property "Sheetfile" "poe.kicad_sch")
    (property "Sheetname" "PoE")
    (property "Tolerance" "")
    (property "Val" "0R")
    (attr smd)
    (fp_text reference "R146" (at 1.38 -0.48 270) (layer "B.SilkS")
      (effects (font (size 0.7 0.7) (thickness 0.15)) (justify left bottom mirror))
    )
    (fp_text value "R_0R_0402" (at 0 -1.4 270) (layer "B.Fab")
      (effects (font (size 0.7 0.7) (thickness 0.15)) (justify left bottom mirror))
    )
    (fp_text user "Author: Antmicro" (at -0.95 -4.169 270) (layer "B.Fab") hide
      (effects (font (size 0.7 0.7) (thickness 0.15)) (justify left bottom mirror))
    )
    (fp_text user "${REFERENCE}" (at -0.95 -3.168 270) (layer "B.Fab") hide
      (effects (font (size 0.7 0.7) (thickness 0.15)) (justify left bottom mirror))
    )
    (fp_text user "License: Apache-2.0" (at -0.95 -5.169 270) (layer "B.Fab") hide
      (effects (font (size 0.7 0.7) (thickness 0.15)) (justify left bottom mirror))
    )
    (fp_rect (start -0.93 0.47) (end 0.93 -0.47) (layer "B.CrtYd") (width 0.05) (fill none))
    (fp_rect (start -0.5 0.25) (end 0.5 -0.25) (layer "B.Fab") (width 0.15) (fill none))
    (pad "1" smd roundrect (at -0.485 0 90) (size 0.59 0.64) (layers "B.Cu" "B.Paste" "B.Mask") (roundrect_rratio 0.25)
      (net 147 "/PoE/CDB") (pintype "passive"))
    (pad "2" smd roundrect (at 0.485 0 90) (size 0.59 0.64) (layers "B.Cu" "B.Paste" "B.Mask") (roundrect_rratio 0.25)
      (net 76 "/PoE/SMPS_CTRL") (pintype "passive"))
  )

  (footprint "sa800u-baseboard-hw-footprints:R_0402_1005Metric" (layer "B.Cu")
    (tedit 5FD9C158)
    (at 59.4 103.11)
    (descr "Resistor SMD 0402")
    (tags "resistor SMD 0402")
    (property "Author" "Antmicro")
    (property "DNP" "DNP")
    (property "License" "Apache-2.0")
    (property "MPN" "CR0402-FX-1003GLF")
    (property "Manufacturer" "Bourns")
    (property "Sheetfile" "poe.kicad_sch")
    (property "Sheetname" "PoE")
    (property "Tolerance" "1%")
    (property "Val" "100k")
    (attr exclude_from_pos_files)
    (fp_text reference "R147" (at 1.04 -0.51 180) (layer "B.SilkS")
      (effects (font (size 0.7 0.7) (thickness 0.15)) (justify left bottom mirror))
    )
    (fp_text value "R_100k_0402" (at 0 -1.4 180) (layer "B.Fab")
      (effects (font (size 0.7 0.7) (thickness 0.15)) (justify left bottom mirror))
    )
    (fp_text user "License: Apache-2.0" (at -0.95 -5.169 180) (layer "B.Fab") hide
      (effects (font (size 0.7 0.7) (thickness 0.15)) (justify left bottom mirror))
    )
    (fp_text user "Author: Antmicro" (at -0.95 -4.169 180) (layer "B.Fab") hide
      (effects (font (size 0.7 0.7) (thickness 0.15)) (justify left bottom mirror))
    )
    (fp_text user "${REFERENCE}" (at -0.95 -3.168 180) (layer "B.Fab") hide
      (effects (font (size 0.7 0.7) (thickness 0.15)) (justify left bottom mirror))
    )
    (fp_rect (start -0.93 0.47) (end 0.93 -0.47) (layer "B.CrtYd") (width 0.05) (fill none))
    (fp_rect (start -0.5 0.25) (end 0.5 -0.25) (layer "B.Fab") (width 0.15) (fill none))
    (pad "1" smd roundrect (at -0.485 0) (size 0.59 0.64) (layers "B.Cu" "B.Paste" "B.Mask") (roundrect_rratio 0.25)
      (net 73 "/PoE/VDD_POE") (pintype "passive"))
    (pad "2" smd roundrect (at 0.485 0) (size 0.59 0.64) (layers "B.Cu" "B.Paste" "B.Mask") (roundrect_rratio 0.25)
      (net 76 "/PoE/SMPS_CTRL") (pintype "passive"))
  )

  (footprint "sa800u-baseboard-hw-footprints:R_0402_1005Metric" (layer "B.Cu")
    (tedit 5FD9C158)
    (at 61.4 103.11)
    (descr "Resistor SMD 0402")
    (tags "resistor SMD 0402")
    (property "Author" "Antmicro")
    (property "DNP" "DNP")
    (property "License" "Apache-2.0")
    (property "MPN" "CR0402-FX-1003GLF")
    (property "Manufacturer" "Bourns")
    (property "Sheetfile" "poe.kicad_sch")
    (property "Sheetname" "PoE")
    (property "Tolerance" "1%")
    (property "Val" "100k")
    (attr exclude_from_pos_files)
    (fp_text reference "R148" (at 1.76 -0.46 180) (layer "B.SilkS")
      (effects (font (size 0.7 0.7) (thickness 0.15)) (justify left bottom mirror))
    )
    (fp_text value "R_100k_0402" (at 0 -1.4 180) (layer "B.Fab")
      (effects (font (size 0.7 0.7) (thickness 0.15)) (justify left bottom mirror))
    )
    (fp_text user "Author: Antmicro" (at -0.95 -4.169 180) (layer "B.Fab") hide
      (effects (font (size 0.7 0.7) (thickness 0.15)) (justify left bottom mirror))
    )
    (fp_text user "${REFERENCE}" (at -0.95 -3.168 180) (layer "B.Fab") hide
      (effects (font (size 0.7 0.7) (thickness 0.15)) (justify left bottom mirror))
    )
    (fp_text user "License: Apache-2.0" (at -0.95 -5.169 180) (layer "B.Fab") hide
      (effects (font (size 0.7 0.7) (thickness 0.15)) (justify left bottom mirror))
    )
    (fp_rect (start -0.93 0.47) (end 0.93 -0.47) (layer "B.CrtYd") (width 0.05) (fill none))
    (fp_rect (start -0.5 0.25) (end 0.5 -0.25) (layer "B.Fab") (width 0.15) (fill none))
    (pad "1" smd roundrect (at -0.485 0) (size 0.59 0.64) (layers "B.Cu" "B.Paste" "B.Mask") (roundrect_rratio 0.25)
      (net 76 "/PoE/SMPS_CTRL") (pintype "passive"))
    (pad "2" smd roundrect (at 0.485 0) (size 0.59 0.64) (layers "B.Cu" "B.Paste" "B.Mask") (roundrect_rratio 0.25)
      (net 7 "GNDD") (pintype "passive"))
  )

  (footprint "sa800u-baseboard-hw-footprints:FB_0805_2012Metric" (layer "B.Cu")
    (tedit 5D5D3F54)
    (at 58.25 119.5 90)
    (property "Author" "Antmicro")
    (property "License" "Apache-2.0")
    (property "MPN" "BLM21PG221SN1D")
    (property "Manufacturer" "Murata")
    (property "Sheetfile" "poe.kicad_sch")
    (property "Sheetname" "PoE")
    (attr smd)
    (fp_text reference "FB5" (at 1.02 -0.94 270) (layer "B.SilkS")
      (effects (font (size 0.7 0.7) (thickness 0.15)) (justify left bottom mirror))
    )
    (fp_text value "FB_220Z_2A_0805" (at 0 -1.8 270) (layer "B.Fab")
      (effects (font (size 0.7 0.7) (thickness 0.15)) (justify left bottom mirror))
    )
    (fp_text user "License: Apache-2.0" (at -1.9 -5.75 270) (layer "B.Fab") hide
      (effects (font (size 0.7 0.7) (thickness 0.15)) (justify left bottom mirror))
    )
    (fp_text user "Author: Antmicro" (at -1.9 -4.4 270) (layer "B.Fab") hide
      (effects (font (size 0.7 0.7) (thickness 0.15)) (justify left bottom mirror))
    )
    (fp_text user "${REFERENCE}" (at -1.9 -3.1 270) (layer "B.Fab") hide
      (effects (font (size 0.7 0.7) (thickness 0.15)) (justify left bottom mirror))
    )
    (fp_line (start -0.32 -0.699) (end 0.28 -0.699) (layer "B.SilkS") (width 0.15))
    (fp_line (start -0.3 0.701) (end 0.298 0.701) (layer "B.SilkS") (width 0.15))
    (fp_rect (start -1.75 0.85) (end 1.75 -0.85) (layer "B.CrtYd") (width 0.05) (fill none))
    (fp_line (start -0.951 0.682) (end 0.949 0.682) (layer "B.Fab") (width 0.15))
    (fp_line (start -0.951 -0.68) (end 0.949 -0.68) (layer "B.Fab") (width 0.15))
    (fp_line (start -0.951 0.677) (end -0.951 -0.675) (layer "B.Fab") (width 0.15))
    (fp_line (start 0.949 0.677) (end 0.949 -0.675) (layer "B.Fab") (width 0.15))
    (pad "1" smd roundrect (at -1.1 0.001 90) (size 1 1.4) (layers "B.Cu" "B.Paste" "B.Mask") (roundrect_rratio 0.15)
      (net 379 "Net-(D29-Pad2)") (pintype "passive"))
    (pad "2" smd roundrect (at 1.1 0.001 90) (size 1 1.4) (layers "B.Cu" "B.Paste" "B.Mask") (roundrect_rratio 0.15)
      (net 135 "/PoE/VSS_POE") (pintype "passive"))
  )

  (footprint "sa800u-baseboard-hw-footprints:MS621FE-FL11E" (layer "B.Cu")
    (tedit 60B0E4EA)
    (at 99.249 119.299 180)
    (property "Author" "Antmicro")
    (property "License" "Apache-2.0")
    (property "MPN" "MS621FE-FL11E")
    (property "Manufacturer" "Seiko")
    (property "Sheetfile" "som.kicad_sch")
    (property "Sheetname" "SoM")
    (attr smd)
    (fp_text reference "BAT1" (at 1.209 2.409) (layer "B.SilkS")
      (effects (font (size 0.7 0.7) (thickness 0.15)) (justify left bottom mirror))
    )
    (fp_text value "Battery_Holder_MS621FE-FL11E" (at -0.001 -6.2) (layer "B.Fab")
      (effects (font (size 0.7 0.7) (thickness 0.15)) (justify left bottom mirror))
    )
    (fp_text user "COPPER KEEPOUT" (at -0.2 2.45 90 unlocked) (layer "B.Fab")
      (effects (font (size 0.35 0.35) (thickness 0.0875)) (justify left bottom mirror))
    )
    (fp_text user "${REFERENCE}" (at 3.5 8.25) (layer "B.Fab") hide
      (effects (font (size 0.7 0.7) (thickness 0.15)) (justify right bottom mirror))
    )
    (fp_text user "Author: Antmicro" (at 3.5 9.45) (layer "B.Fab") hide
      (effects (font (size 0.7 0.7) (thickness 0.15)) (justify right bottom mirror))
    )
    (fp_text user "License: Apache-2.0" (at 3.5 10.65) (layer "B.Fab") hide
      (effects (font (size 0.7 0.7) (thickness 0.15)) (justify right bottom mirror))
    )
    (fp_arc (start -1.2 2.15) (mid 0 -4.834) (end 1.2 2.15) (layer "B.SilkS") (width 0.15))
    (fp_line (start 1.209 5.038) (end -1.191 5.038) (layer "B.CrtYd") (width 0.05))
    (fp_line (start -1.191 5.038) (end -1.191 2.148) (layer "B.CrtYd") (width 0.05))
    (fp_line (start 1.209 5.038) (end 1.209 2.148) (layer "B.CrtYd") (width 0.05))
    (fp_arc (start -1.191 2.148) (mid 0.009 -4.852014) (end 1.209 2.148) (layer "B.CrtYd") (width 0.05))
    (fp_line (start 1.2 5.049) (end 1.2 2.15) (layer "B.Fab") (width 0.15))
    (fp_line (start -1.2 5.049) (end -1.2 2.15) (layer "B.Fab") (width 0.15))
    (fp_line (start 1.2 5.049) (end -1.2 5.049) (layer "B.Fab") (width 0.15))
    (fp_circle (center -0.001 -1.25) (end -0.001 2.25) (layer "B.Fab") (width 0.15) (fill none))
    (pad "+" smd rect (at -0.751 4.049 270) (size 1.8 0.75) (layers "B.Cu" "B.Paste" "B.Mask")
      (net 336 "/SoM/VRTC") (pinfunction "+") (pintype "passive"))
    (pad "-" smd rect (at 0.749 4.049 270) (size 1.8 0.75) (layers "B.Cu" "B.Paste" "B.Mask")
      (net 1 "GND") (pinfunction "-") (pintype "passive"))
    (zone (net 0) (net_name "") (layers "B.Cu" "B.CrtYd") (hatch edge 0.508)
      (connect_pads (clearance 0))
      (min_thickness 0.254)
      (keepout (tracks allowed) (vias not_allowed) (pads not_allowed) (copperpour not_allowed) (footprints allowed))
      (fill (thermal_gap 0.508) (thermal_bridge_width 0.508))
      (polygon
        (pts
          (xy 100.4 121.8)
          (xy 100.4 116.16)
          (xy 98.1 116.16)
          (xy 98.1 121.8)
        )
      )
    )
  )

  (footprint "sa800u-baseboard-hw-footprints:L_Murata_025020_0605Metric" (layer "B.Cu")
    (tedit 61AA2C4F)
    (at 93.7 93.7 90)
    (property "Author" "Antmicro")
    (property "License" "Apache-2.0")
    (property "MPN" "NFP0QHB242HS2D")
    (property "Manufacturer" "Murata")
    (property "Sheetfile" "camera-interface.kicad_sch")
    (property "Sheetname" "Camera Interface")
    (attr smd)
    (fp_text reference "L17" (at -0.44 0.33 270) (layer "B.SilkS")
      (effects (font (size 0.7 0.7) (thickness 0.15)) (justify left bottom mirror))
    )
    (fp_text value "NFP0QHB242HS2D" (at 0 -1.55 270) (layer "B.Fab")
      (effects (font (size 0.7 0.7) (thickness 0.15)) (justify left bottom mirror))
    )
    (fp_text user "${REFERENCE}" (at -1.027 -3.406 270) (layer "B.Fab") hide
      (effects (font (size 0.7 0.7) (thickness 0.15)) (justify left bottom mirror))
    )
    (fp_text user "Author: Antmicro" (at -1.027 -4.605 270) (layer "B.Fab") hide
      (effects (font (size 0.7 0.7) (thickness 0.15)) (justify left bottom mirror))
    )
    (fp_text user "License: Apache-2.0" (at -1.027 -5.805 270) (layer "B.Fab") hide
      (effects (font (size 0.7 0.7) (thickness 0.15)) (justify left bottom mirror))
    )
    (fp_line (start -0.276 -0.45) (end 0.276 -0.45) (layer "B.SilkS") (width 0.15))
    (fp_line (start 0.276 0.45) (end -0.276 0.45) (layer "B.SilkS") (width 0.15))
    (fp_circle (center -0.5 0.5) (end -0.449 0.5) (layer "B.SilkS") (width 0.15) (fill solid))
    (fp_rect (start -0.5 0.6) (end 0.5 -0.6) (layer "B.CrtYd") (width 0.05) (fill none))
    (fp_line (start 0.275 -0.349) (end 0.275 0.351) (layer "B.Fab") (width 0.15))
    (fp_line (start -0.277 -0.349) (end 0.275 -0.349) (layer "B.Fab") (width 0.15))
    (fp_line (start 0.275 0.351) (end -0.277 0.351) (layer "B.Fab") (width 0.15))
    (fp_line (start -0.277 0.351) (end -0.277 -0.349) (layer "B.Fab") (width 0.15))
    (pad "1" smd rect (at -0.25 0.24 90) (size 0.3 0.23) (layers "B.Cu" "B.Paste" "B.Mask")
      (net 19 "CSI1_LN2_P") (pinfunction "1") (pintype "passive"))
    (pad "2" smd rect (at 0.248 0.24 90) (size 0.3 0.23) (layers "B.Cu" "B.Paste" "B.Mask")
      (net 278 "/Camera Interface/CSI1_LN2_FFC_P") (pinfunction "2") (pintype "passive"))
    (pad "3" smd rect (at 0.248 -0.239 90) (size 0.3 0.23) (layers "B.Cu" "B.Paste" "B.Mask")
      (net 279 "/Camera Interface/CSI1_LN2_FFC_N") (pinfunction "3") (pintype "passive"))
    (pad "4" smd rect (at -0.25 -0.239 90) (size 0.3 0.23) (layers "B.Cu" "B.Paste" "B.Mask")
      (net 20 "CSI1_LN2_N") (pinfunction "4") (pintype "passive"))
  )

  (footprint "sa800u-baseboard-hw-footprints:L_Murata_025020_0605Metric" (layer "B.Cu")
    (tedit 61AA2C4F)
    (at 96.3 93.7 90)
    (property "Author" "Antmicro")
    (property "License" "Apache-2.0")
    (property "MPN" "NFP0QHB242HS2D")
    (property "Manufacturer" "Murata")
    (property "Sheetfile" "camera-interface.kicad_sch")
    (property "Sheetname" "Camera Interface")
    (attr smd)
    (fp_text reference "L19" (at -0.44 0.33 270) (layer "B.SilkS")
      (effects (font (size 0.7 0.7) (thickness 0.15)) (justify left bottom mirror))
    )
    (fp_text value "NFP0QHB242HS2D" (at 0 -1.55 270) (layer "B.Fab")
      (effects (font (size 0.7 0.7) (thickness 0.15)) (justify left bottom mirror))
    )
    (fp_text user "License: Apache-2.0" (at -1.027 -5.805 270) (layer "B.Fab") hide
      (effects (font (size 0.7 0.7) (thickness 0.15)) (justify left bottom mirror))
    )
    (fp_text user "${REFERENCE}" (at -1.027 -3.406 270) (layer "B.Fab") hide
      (effects (font (size 0.7 0.7) (thickness 0.15)) (justify left bottom mirror))
    )
    (fp_text user "Author: Antmicro" (at -1.027 -4.605 270) (layer "B.Fab") hide
      (effects (font (size 0.7 0.7) (thickness 0.15)) (justify left bottom mirror))
    )
    (fp_line (start 0.276 0.45) (end -0.276 0.45) (layer "B.SilkS") (width 0.15))
    (fp_line (start -0.276 -0.45) (end 0.276 -0.45) (layer "B.SilkS") (width 0.15))
    (fp_circle (center -0.5 0.5) (end -0.449 0.5) (layer "B.SilkS") (width 0.15) (fill solid))
    (fp_rect (start -0.5 0.6) (end 0.5 -0.6) (layer "B.CrtYd") (width 0.05) (fill none))
    (fp_line (start 0.275 0.351) (end -0.277 0.351) (layer "B.Fab") (width 0.15))
    (fp_line (start -0.277 0.351) (end -0.277 -0.349) (layer "B.Fab") (width 0.15))
    (fp_line (start 0.275 -0.349) (end 0.275 0.351) (layer "B.Fab") (width 0.15))
    (fp_line (start -0.277 -0.349) (end 0.275 -0.349) (layer "B.Fab") (width 0.15))
    (pad "1" smd rect (at -0.25 0.24 90) (size 0.3 0.23) (layers "B.Cu" "B.Paste" "B.Mask")
      (net 24 "CSI1_LN0_P") (pinfunction "1") (pintype "passive"))
    (pad "2" smd rect (at 0.248 0.24 90) (size 0.3 0.23) (layers "B.Cu" "B.Paste" "B.Mask")
      (net 268 "/Camera Interface/CSI1_LN0_FFC_P") (pinfunction "2") (pintype "passive"))
    (pad "3" smd rect (at 0.248 -0.239 90) (size 0.3 0.23) (layers "B.Cu" "B.Paste" "B.Mask")
      (net 269 "/Camera Interface/CSI1_LN0_FFC_N") (pinfunction "3") (pintype "passive"))
    (pad "4" smd rect (at -0.25 -0.239 90) (size 0.3 0.23) (layers "B.Cu" "B.Paste" "B.Mask")
      (net 23 "CSI1_LN0_N") (pinfunction "4") (pintype "passive"))
  )

  (footprint "sa800u-baseboard-hw-footprints:L_Murata_025020_0605Metric" (layer "B.Cu")
    (tedit 61AA2C4F)
    (at 97.6 93.7 90)
    (property "Author" "Antmicro")
    (property "License" "Apache-2.0")
    (property "MPN" "NFP0QHB242HS2D")
    (property "Manufacturer" "Murata")
    (property "Sheetfile" "camera-interface.kicad_sch")
    (property "Sheetname" "Camera Interface")
    (attr smd)
    (fp_text reference "L20" (at -0.44 0.33 270) (layer "B.SilkS")
      (effects (font (size 0.7 0.7) (thickness 0.15)) (justify left bottom mirror))
    )
    (fp_text value "NFP0QHB242HS2D" (at 0 -1.55 270) (layer "B.Fab")
      (effects (font (size 0.7 0.7) (thickness 0.15)) (justify left bottom mirror))
    )
    (fp_text user "License: Apache-2.0" (at -1.027 -5.805 270) (layer "B.Fab") hide
      (effects (font (size 0.7 0.7) (thickness 0.15)) (justify left bottom mirror))
    )
    (fp_text user "Author: Antmicro" (at -1.027 -4.605 270) (layer "B.Fab") hide
      (effects (font (size 0.7 0.7) (thickness 0.15)) (justify left bottom mirror))
    )
    (fp_text user "${REFERENCE}" (at -1.027 -3.406 270) (layer "B.Fab") hide
      (effects (font (size 0.7 0.7) (thickness 0.15)) (justify left bottom mirror))
    )
    (fp_line (start 0.276 0.45) (end -0.276 0.45) (layer "B.SilkS") (width 0.15))
    (fp_line (start -0.276 -0.45) (end 0.276 -0.45) (layer "B.SilkS") (width 0.15))
    (fp_circle (center -0.5 0.5) (end -0.449 0.5) (layer "B.SilkS") (width 0.15) (fill solid))
    (fp_rect (start -0.5 0.6) (end 0.5 -0.6) (layer "B.CrtYd") (width 0.05) (fill none))
    (fp_line (start -0.277 -0.349) (end 0.275 -0.349) (layer "B.Fab") (width 0.15))
    (fp_line (start 0.275 0.351) (end -0.277 0.351) (layer "B.Fab") (width 0.15))
    (fp_line (start -0.277 0.351) (end -0.277 -0.349) (layer "B.Fab") (width 0.15))
    (fp_line (start 0.275 -0.349) (end 0.275 0.351) (layer "B.Fab") (width 0.15))
    (pad "1" smd rect (at -0.25 0.24 90) (size 0.3 0.23) (layers "B.Cu" "B.Paste" "B.Mask")
      (net 25 "CSI1_CLK_P") (pinfunction "1") (pintype "passive"))
    (pad "2" smd rect (at 0.248 0.24 90) (size 0.3 0.23) (layers "B.Cu" "B.Paste" "B.Mask")
      (net 274 "/Camera Interface/CSI1_CLK_FFC_P") (pinfunction "2") (pintype "passive"))
    (pad "3" smd rect (at 0.248 -0.239 90) (size 0.3 0.23) (layers "B.Cu" "B.Paste" "B.Mask")
      (net 275 "/Camera Interface/CSI1_CLK_FFC_N") (pinfunction "3") (pintype "passive"))
    (pad "4" smd rect (at -0.25 -0.239 90) (size 0.3 0.23) (layers "B.Cu" "B.Paste" "B.Mask")
      (net 26 "CSI1_CLK_N") (pinfunction "4") (pintype "passive"))
  )

  (footprint "sa800u-baseboard-hw-footprints:L_Murata_025020_0605Metric" (layer "B.Cu")
    (tedit 61AA2C4F)
    (at 101.8 93.7 90)
    (property "Author" "Antmicro")
    (property "License" "Apache-2.0")
    (property "MPN" "NFP0QHB242HS2D")
    (property "Manufacturer" "Murata")
    (property "Sheetfile" "camera-interface.kicad_sch")
    (property "Sheetname" "Camera Interface")
    (attr smd)
    (fp_text reference "L21" (at -0.45 0.43 270) (layer "B.SilkS")
      (effects (font (size 0.7 0.7) (thickness 0.15)) (justify left bottom mirror))
    )
    (fp_text value "NFP0QHB242HS2D" (at 0 -1.55 270) (layer "B.Fab")
      (effects (font (size 0.7 0.7) (thickness 0.15)) (justify left bottom mirror))
    )
    (fp_text user "${REFERENCE}" (at -1.027 -3.406 270) (layer "B.Fab") hide
      (effects (font (size 0.7 0.7) (thickness 0.15)) (justify left bottom mirror))
    )
    (fp_text user "License: Apache-2.0" (at -1.027 -5.805 270) (layer "B.Fab") hide
      (effects (font (size 0.7 0.7) (thickness 0.15)) (justify left bottom mirror))
    )
    (fp_text user "Author: Antmicro" (at -1.027 -4.605 270) (layer "B.Fab") hide
      (effects (font (size 0.7 0.7) (thickness 0.15)) (justify left bottom mirror))
    )
    (fp_line (start 0.276 0.45) (end -0.276 0.45) (layer "B.SilkS") (width 0.15))
    (fp_line (start -0.276 -0.45) (end 0.276 -0.45) (layer "B.SilkS") (width 0.15))
    (fp_circle (center -0.5 0.5) (end -0.449 0.5) (layer "B.SilkS") (width 0.15) (fill solid))
    (fp_rect (start -0.5 0.6) (end 0.5 -0.6) (layer "B.CrtYd") (width 0.05) (fill none))
    (fp_line (start 0.275 0.351) (end -0.277 0.351) (layer "B.Fab") (width 0.15))
    (fp_line (start 0.275 -0.349) (end 0.275 0.351) (layer "B.Fab") (width 0.15))
    (fp_line (start -0.277 -0.349) (end 0.275 -0.349) (layer "B.Fab") (width 0.15))
    (fp_line (start -0.277 0.351) (end -0.277 -0.349) (layer "B.Fab") (width 0.15))
    (pad "1" smd rect (at -0.25 0.24 90) (size 0.3 0.23) (layers "B.Cu" "B.Paste" "B.Mask")
      (net 28 "CSI0_LN3_P") (pinfunction "1") (pintype "passive"))
    (pad "2" smd rect (at 0.248 0.24 90) (size 0.3 0.23) (layers "B.Cu" "B.Paste" "B.Mask")
      (net 280 "/Camera Interface/CSI0_LN3_FFC_P") (pinfunction "2") (pintype "passive"))
    (pad "3" smd rect (at 0.248 -0.239 90) (size 0.3 0.23) (layers "B.Cu" "B.Paste" "B.Mask")
      (net 281 "/Camera Interface/CSI0_LN3_FFC_N") (pinfunction "3") (pintype "passive"))
    (pad "4" smd rect (at -0.25 -0.239 90) (size 0.3 0.23) (layers "B.Cu" "B.Paste" "B.Mask")
      (net 27 "CSI0_LN3_N") (pinfunction "4") (pintype "passive"))
  )

  (footprint "sa800u-baseboard-hw-footprints:L_Murata_025020_0605Metric" (layer "B.Cu")
    (tedit 61AA2C4F)
    (at 103.1 93.7 90)
    (property "Author" "Antmicro")
    (property "License" "Apache-2.0")
    (property "MPN" "NFP0QHB242HS2D")
    (property "Manufacturer" "Murata")
    (property "Sheetfile" "camera-interface.kicad_sch")
    (property "Sheetname" "Camera Interface")
    (attr smd)
    (fp_text reference "L22" (at -0.45 0.43 270) (layer "B.SilkS")
      (effects (font (size 0.7 0.7) (thickness 0.15)) (justify left bottom mirror))
    )
    (fp_text value "NFP0QHB242HS2D" (at 0 -1.55 270) (layer "B.Fab")
      (effects (font (size 0.7 0.7) (thickness 0.15)) (justify left bottom mirror))
    )
    (fp_text user "License: Apache-2.0" (at -1.027 -5.805 270) (layer "B.Fab") hide
      (effects (font (size 0.7 0.7) (thickness 0.15)) (justify left bottom mirror))
    )
    (fp_text user "${REFERENCE}" (at -1.027 -3.406 270) (layer "B.Fab") hide
      (effects (font (size 0.7 0.7) (thickness 0.15)) (justify left bottom mirror))
    )
    (fp_text user "Author: Antmicro" (at -1.027 -4.605 270) (layer "B.Fab") hide
      (effects (font (size 0.7 0.7) (thickness 0.15)) (justify left bottom mirror))
    )
    (fp_line (start -0.276 -0.45) (end 0.276 -0.45) (layer "B.SilkS") (width 0.15))
    (fp_line (start 0.276 0.45) (end -0.276 0.45) (layer "B.SilkS") (width 0.15))
    (fp_circle (center -0.5 0.5) (end -0.449 0.5) (layer "B.SilkS") (width 0.15) (fill solid))
    (fp_rect (start -0.5 0.6) (end 0.5 -0.6) (layer "B.CrtYd") (width 0.05) (fill none))
    (fp_line (start 0.275 -0.349) (end 0.275 0.351) (layer "B.Fab") (width 0.15))
    (fp_line (start -0.277 0.351) (end -0.277 -0.349) (layer "B.Fab") (width 0.15))
    (fp_line (start 0.275 0.351) (end -0.277 0.351) (layer "B.Fab") (width 0.15))
    (fp_line (start -0.277 -0.349) (end 0.275 -0.349) (layer "B.Fab") (width 0.15))
    (pad "1" smd rect (at -0.25 0.24 90) (size 0.3 0.23) (layers "B.Cu" "B.Paste" "B.Mask")
      (net 29 "CSI0_LN2_P") (pinfunction "1") (pintype "passive"))
    (pad "2" smd rect (at 0.248 0.24 90) (size 0.3 0.23) (layers "B.Cu" "B.Paste" "B.Mask")
      (net 276 "/Camera Interface/CSI0_LN2_FFC_P") (pinfunction "2") (pintype "passive"))
    (pad "3" smd rect (at 0.248 -0.239 90) (size 0.3 0.23) (layers "B.Cu" "B.Paste" "B.Mask")
      (net 277 "/Camera Interface/CSI0_LN2_FFC_N") (pinfunction "3") (pintype "passive"))
    (pad "4" smd rect (at -0.25 -0.239 90) (size 0.3 0.23) (layers "B.Cu" "B.Paste" "B.Mask")
      (net 30 "CSI0_LN2_N") (pinfunction "4") (pintype "passive"))
  )

  (footprint "sa800u-baseboard-hw-footprints:L_Murata_025020_0605Metric" (layer "B.Cu")
    (tedit 61AA2C4F)
    (at 104.4 93.7 90)
    (property "Author" "Antmicro")
    (property "License" "Apache-2.0")
    (property "MPN" "NFP0QHB242HS2D")
    (property "Manufacturer" "Murata")
    (property "Sheetfile" "camera-interface.kicad_sch")
    (property "Sheetname" "Camera Interface")
    (attr smd)
    (fp_text reference "L23" (at -0.45 0.43 270) (layer "B.SilkS")
      (effects (font (size 0.7 0.7) (thickness 0.15)) (justify left bottom mirror))
    )
    (fp_text value "NFP0QHB242HS2D" (at 0 -1.55 270) (layer "B.Fab")
      (effects (font (size 0.7 0.7) (thickness 0.15)) (justify left bottom mirror))
    )
    (fp_text user "${REFERENCE}" (at -1.027 -3.406 270) (layer "B.Fab") hide
      (effects (font (size 0.7 0.7) (thickness 0.15)) (justify left bottom mirror))
    )
    (fp_text user "License: Apache-2.0" (at -1.027 -5.805 270) (layer "B.Fab") hide
      (effects (font (size 0.7 0.7) (thickness 0.15)) (justify left bottom mirror))
    )
    (fp_text user "Author: Antmicro" (at -1.027 -4.605 270) (layer "B.Fab") hide
      (effects (font (size 0.7 0.7) (thickness 0.15)) (justify left bottom mirror))
    )
    (fp_line (start -0.276 -0.45) (end 0.276 -0.45) (layer "B.SilkS") (width 0.15))
    (fp_line (start 0.276 0.45) (end -0.276 0.45) (layer "B.SilkS") (width 0.15))
    (fp_circle (center -0.5 0.5) (end -0.449 0.5) (layer "B.SilkS") (width 0.15) (fill solid))
    (fp_rect (start -0.5 0.6) (end 0.5 -0.6) (layer "B.CrtYd") (width 0.05) (fill none))
    (fp_line (start 0.275 -0.349) (end 0.275 0.351) (layer "B.Fab") (width 0.15))
    (fp_line (start 0.275 0.351) (end -0.277 0.351) (layer "B.Fab") (width 0.15))
    (fp_line (start -0.277 -0.349) (end 0.275 -0.349) (layer "B.Fab") (width 0.15))
    (fp_line (start -0.277 0.351) (end -0.277 -0.349) (layer "B.Fab") (width 0.15))
    (pad "1" smd rect (at -0.25 0.24 90) (size 0.3 0.23) (layers "B.Cu" "B.Paste" "B.Mask")
      (net 32 "CSI0_LN1_P") (pinfunction "1") (pintype "passive"))
    (pad "2" smd rect (at 0.248 0.24 90) (size 0.3 0.23) (layers "B.Cu" "B.Paste" "B.Mask")
      (net 270 "/Camera Interface/CSI0_LN1_FFC_P") (pinfunction "2") (pintype "passive"))
    (pad "3" smd rect (at 0.248 -0.239 90) (size 0.3 0.23) (layers "B.Cu" "B.Paste" "B.Mask")
      (net 271 "/Camera Interface/CSI0_LN1_FFC_N") (pinfunction "3") (pintype "passive"))
    (pad "4" smd rect (at -0.25 -0.239 90) (size 0.3 0.23) (layers "B.Cu" "B.Paste" "B.Mask")
      (net 31 "CSI0_LN1_N") (pinfunction "4") (pintype "passive"))
  )

  (footprint "sa800u-baseboard-hw-footprints:L_Murata_025020_0605Metric" (layer "B.Cu")
    (tedit 61AA2C4F)
    (at 105.7 93.7 90)
    (property "Author" "Antmicro")
    (property "License" "Apache-2.0")
    (property "MPN" "NFP0QHB242HS2D")
    (property "Manufacturer" "Murata")
    (property "Sheetfile" "camera-interface.kicad_sch")
    (property "Sheetname" "Camera Interface")
    (attr smd)
    (fp_text reference "L24" (at -0.45 0.43 270) (layer "B.SilkS")
      (effects (font (size 0.7 0.7) (thickness 0.15)) (justify left bottom mirror))
    )
    (fp_text value "NFP0QHB242HS2D" (at 0 -1.55 270) (layer "B.Fab")
      (effects (font (size 0.7 0.7) (thickness 0.15)) (justify left bottom mirror))
    )
    (fp_text user "License: Apache-2.0" (at -1.027 -5.805 270) (layer "B.Fab") hide
      (effects (font (size 0.7 0.7) (thickness 0.15)) (justify left bottom mirror))
    )
    (fp_text user "${REFERENCE}" (at -1.027 -3.406 270) (layer "B.Fab") hide
      (effects (font (size 0.7 0.7) (thickness 0.15)) (justify left bottom mirror))
    )
    (fp_text user "Author: Antmicro" (at -1.027 -4.605 270) (layer "B.Fab") hide
      (effects (font (size 0.7 0.7) (thickness 0.15)) (justify left bottom mirror))
    )
    (fp_line (start 0.276 0.45) (end -0.276 0.45) (layer "B.SilkS") (width 0.15))
    (fp_line (start -0.276 -0.45) (end 0.276 -0.45) (layer "B.SilkS") (width 0.15))
    (fp_circle (center -0.5 0.5) (end -0.449 0.5) (layer "B.SilkS") (width 0.15) (fill solid))
    (fp_rect (start -0.5 0.6) (end 0.5 -0.6) (layer "B.CrtYd") (width 0.05) (fill none))
    (fp_line (start -0.277 -0.349) (end 0.275 -0.349) (layer "B.Fab") (width 0.15))
    (fp_line (start 0.275 -0.349) (end 0.275 0.351) (layer "B.Fab") (width 0.15))
    (fp_line (start 0.275 0.351) (end -0.277 0.351) (layer "B.Fab") (width 0.15))
    (fp_line (start -0.277 0.351) (end -0.277 -0.349) (layer "B.Fab") (width 0.15))
    (pad "1" smd rect (at -0.25 0.24 90) (size 0.3 0.23) (layers "B.Cu" "B.Paste" "B.Mask")
      (net 34 "CSI0_LN0_P") (pinfunction "1") (pintype "passive"))
    (pad "2" smd rect (at 0.248 0.24 90) (size 0.3 0.23) (layers "B.Cu" "B.Paste" "B.Mask")
      (net 266 "/Camera Interface/CSI0_LN0_FFC_P") (pinfunction "2") (pintype "passive"))
    (pad "3" smd rect (at 0.248 -0.239 90) (size 0.3 0.23) (layers "B.Cu" "B.Paste" "B.Mask")
      (net 267 "/Camera Interface/CSI0_LN0_FFC_N") (pinfunction "3") (pintype "passive"))
    (pad "4" smd rect (at -0.25 -0.239 90) (size 0.3 0.23) (layers "B.Cu" "B.Paste" "B.Mask")
      (net 33 "CSI0_LN0_N") (pinfunction "4") (pintype "passive"))
  )

  (footprint "sa800u-baseboard-hw-footprints:L_Murata_025020_0605Metric" (layer "B.Cu")
    (tedit 61AA2C4F)
    (at 107 93.7 90)
    (property "Author" "Antmicro")
    (property "License" "Apache-2.0")
    (property "MPN" "NFP0QHB242HS2D")
    (property "Manufacturer" "Murata")
    (property "Sheetfile" "camera-interface.kicad_sch")
    (property "Sheetname" "Camera Interface")
    (attr smd)
    (fp_text reference "L25" (at -0.45 0.43 270) (layer "B.SilkS")
      (effects (font (size 0.7 0.7) (thickness 0.15)) (justify left bottom mirror))
    )
    (fp_text value "NFP0QHB242HS2D" (at 0 -1.55 270) (layer "B.Fab")
      (effects (font (size 0.7 0.7) (thickness 0.15)) (justify left bottom mirror))
    )
    (fp_text user "${REFERENCE}" (at -1.027 -3.406 270) (layer "B.Fab") hide
      (effects (font (size 0.7 0.7) (thickness 0.15)) (justify left bottom mirror))
    )
    (fp_text user "Author: Antmicro" (at -1.027 -4.605 270) (layer "B.Fab") hide
      (effects (font (size 0.7 0.7) (thickness 0.15)) (justify left bottom mirror))
    )
    (fp_text user "License: Apache-2.0" (at -1.027 -5.805 270) (layer "B.Fab") hide
      (effects (font (size 0.7 0.7) (thickness 0.15)) (justify left bottom mirror))
    )
    (fp_line (start -0.276 -0.45) (end 0.276 -0.45) (layer "B.SilkS") (width 0.15))
    (fp_line (start 0.276 0.45) (end -0.276 0.45) (layer "B.SilkS") (width 0.15))
    (fp_circle (center -0.5 0.5) (end -0.449 0.5) (layer "B.SilkS") (width 0.15) (fill solid))
    (fp_rect (start -0.5 0.6) (end 0.5 -0.6) (layer "B.CrtYd") (width 0.05) (fill none))
    (fp_line (start -0.277 0.351) (end -0.277 -0.349) (layer "B.Fab") (width 0.15))
    (fp_line (start 0.275 -0.349) (end 0.275 0.351) (layer "B.Fab") (width 0.15))
    (fp_line (start -0.277 -0.349) (end 0.275 -0.349) (layer "B.Fab") (width 0.15))
    (fp_line (start 0.275 0.351) (end -0.277 0.351) (layer "B.Fab") (width 0.15))
    (pad "1" smd rect (at -0.25 0.24 90) (size 0.3 0.23) (layers "B.Cu" "B.Paste" "B.Mask")
      (net 13 "CSI0_CLK_P") (pinfunction "1") (pintype "passive"))
    (pad "2" smd rect (at 0.248 0.24 90) (size 0.3 0.23) (layers "B.Cu" "B.Paste" "B.Mask")
      (net 324 "/Camera Interface/CSI0_CLK_FFC_P") (pinfunction "2") (pintype "passive"))
    (pad "3" smd rect (at 0.248 -0.239 90) (size 0.3 0.23) (layers "B.Cu" "B.Paste" "B.Mask")
      (net 325 "/Camera Interface/CSI0_CLK_FFC_N") (pinfunction "3") (pintype "passive"))
    (pad "4" smd rect (at -0.25 -0.239 90) (size 0.3 0.23) (layers "B.Cu" "B.Paste" "B.Mask")
      (net 12 "CSI0_CLK_N") (pinfunction "4") (pintype "passive"))
  )

  (footprint "sa800u-baseboard-hw-footprints:C_0402_1005Metric" (layer "B.Cu")
    (tedit 616D63CF)
    (at 63.5 138.9 -90)
    (descr "Capacitor SMD 0402")
    (tags "capacitor SMD 0402")
    (property "Author" "Antmicro")
    (property "Dielectric" "X7R")
    (property "License" "Apache-2.0")
    (property "MPN" "GRM155R71H103KA88D")
    (property "Manufacturer" "Murata")
    (property "Sheetfile" "ethernet-controller.kicad_sch")
    (property "Sheetname" "Ethernet Controller")
    (property "Val" "10n")
    (property "Voltage" "50V")
    (attr smd)
    (fp_text reference "C16" (at -1.12 0.62 90) (layer "B.SilkS")
      (effects (font (size 0.7 0.7) (thickness 0.15)) (justify left bottom mirror))
    )
    (fp_text value "C_10n_0402" (at 0 -1.4 90) (layer "B.Fab")
      (effects (font (size 0.7 0.7) (thickness 0.15)) (justify left bottom mirror))
    )
    (fp_text user "${REFERENCE}" (at -0.932 -3.168 90) (layer "B.Fab") hide
      (effects (font (size 0.7 0.7) (thickness 0.15)) (justify left bottom mirror))
    )
    (fp_text user "License: Apache-2.0" (at -0.932 -5.17 90) (layer "B.Fab") hide
      (effects (font (size 0.7 0.7) (thickness 0.15)) (justify left bottom mirror))
    )
    (fp_text user "Author: Antmicro" (at -0.932 -4.17 90) (layer "B.Fab") hide
      (effects (font (size 0.7 0.7) (thickness 0.15)) (justify left bottom mirror))
    )
    (fp_rect (start -0.94 0.47) (end 0.94 -0.47) (layer "B.CrtYd") (width 0.05) (fill none))
    (fp_rect (start -0.499 0.249) (end 0.499 -0.249) (layer "B.Fab") (width 0.15) (fill none))
    (pad "1" smd roundrect (at -0.484 0 270) (size 0.59 0.64) (layers "B.Cu" "B.Paste" "B.Mask") (roundrect_rratio 0.25)
      (net 63 "Net-(C16-Pad1)") (pintype "passive"))
    (pad "2" smd roundrect (at 0.484 0 270) (size 0.59 0.64) (layers "B.Cu" "B.Paste" "B.Mask") (roundrect_rratio 0.25)
      (net 4 "Earth") (pintype "passive"))
  )

  (footprint "sa800u-baseboard-hw-footprints:C_0603_1608Metric" (layer "B.Cu")
    (tedit 5D5E94D2)
    (at 82.9 98.3 90)
    (descr "Capacitor SMD 0603")
    (tags "capacitor 0603")
    (property "Author" "Antmicro")
    (property "Dielectric" "")
    (property "License" "Apache-2.0")
    (property "MPN" "GRM188R60J226MEA0D")
    (property "Manufacturer" "Murata")
    (property "Sheetfile" "psu.kicad_sch")
    (property "Sheetname" "PSU")
    (property "Val" "22u")
    (property "Voltage" "")
    (attr smd)
    (fp_text reference "C128" (at 1.46 -0.86 270) (layer "B.SilkS")
      (effects (font (size 0.7 0.7) (thickness 0.15)) (justify left bottom mirror))
    )
    (fp_text value "C_22u_0603" (at 0 -1.6 270) (layer "B.Fab")
      (effects (font (size 0.7 0.7) (thickness 0.15)) (justify left bottom mirror))
    )
    (fp_text user "${REFERENCE}" (at -1.682 -3.895 270) (layer "B.Fab") hide
      (effects (font (size 0.7 0.7) (thickness 0.15)) (justify left bottom mirror))
    )
    (fp_text user "License: Apache-2.0" (at -1.682 -5.895 270) (layer "B.Fab") hide
      (effects (font (size 0.7 0.7) (thickness 0.15)) (justify left bottom mirror))
    )
    (fp_text user "Author: Antmicro" (at -1.682 -4.894 270) (layer "B.Fab") hide
      (effects (font (size 0.7 0.7) (thickness 0.15)) (justify left bottom mirror))
    )
    (fp_line (start -0.3 -0.3) (end 0.3 -0.3) (layer "B.SilkS") (width 0.15))
    (fp_line (start -0.3 0.3) (end 0.3 0.3) (layer "B.SilkS") (width 0.15))
    (fp_rect (start -1.24 0.7) (end 1.24 -0.7) (layer "B.CrtYd") (width 0.05) (fill none))
    (fp_rect (start -0.8 0.4) (end 0.8 -0.4) (layer "B.Fab") (width 0.15) (fill none))
    (pad "1" smd roundrect (at -0.7 0 90) (size 0.6 0.8) (layers "B.Cu" "B.Paste" "B.Mask") (roundrect_rratio 0.2)
      (net 74 "VDD") (pintype "passive"))
    (pad "2" smd roundrect (at 0.7 0 90) (size 0.6 0.8) (layers "B.Cu" "B.Paste" "B.Mask") (roundrect_rratio 0.2)
      (net 1 "GND") (pintype "passive"))
  )

  (footprint "sa800u-baseboard-hw-footprints:SOT-23-5" (layer "B.Cu")
    (tedit 5D64D240)
    (at 78.7 121.55)
    (property "Author" "Antmicro")
    (property "License" "Apache-2.0")
    (property "MPN" "LMV431IM5")
    (property "Manufacturer" "Texas Instruments")
    (property "Sheetfile" "psu.kicad_sch")
    (property "Sheetname" "PSU")
    (attr smd)
    (fp_text reference "U18" (at -3.04 2.38) (layer "B.SilkS")
      (effects (font (size 0.7 0.7) (thickness 0.15)) (justify right bottom mirror))
    )
    (fp_text value "LMV431_SOT-23-5" (at 0.002 -2.799) (layer "B.Fab")
      (effects (font (size 0.7 0.7) (thickness 0.15)) (justify right bottom mirror))
    )
    (fp_text user "Author: Antmicro" (at -1.898 -5.499) (layer "B.Fab") hide
      (effects (font (size 0.7 0.7) (thickness 0.15)) (justify right bottom mirror))
    )
    (fp_text user "License: Apache-2.0" (at -1.898 -6.7) (layer "B.Fab") hide
      (effects (font (size 0.7 0.7) (thickness 0.15)) (justify right bottom mirror))
    )
    (fp_text user "${REFERENCE}" (at -1.898 -4.299) (layer "B.Fab") hide
      (effects (font (size 0.7 0.7) (thickness 0.15)) (justify right bottom mirror))
    )
    (fp_line (start -0.8 1.6) (end -0.8 1.3) (layer "B.SilkS") (width 0.15))
    (fp_line (start -0.8 1.6) (end -0.5 1.6) (layer "B.SilkS") (width 0.15))
    (fp_line (start 0.8 -1.3) (end 0.8 -1.599) (layer "B.SilkS") (width 0.15))
    (fp_line (start 0.8 -0.55) (end 0.8 0.55) (layer "B.SilkS") (width 0.15))
    (fp_line (start 0.8 1.6) (end 0.5 1.6) (layer "B.SilkS") (width 0.15))
    (fp_line (start -0.85 -1.6) (end -0.85 -1.301) (layer "B.SilkS") (width 0.15))
    (fp_line (start -0.55 -1.6) (end -0.85 -1.6) (layer "B.SilkS") (width 0.15))
    (fp_line (start 0.8 1.3) (end 0.8 1.6) (layer "B.SilkS") (width 0.15))
    (fp_line (start 0.8 -1.599) (end 0.549 -1.599) (layer "B.SilkS") (width 0.15))
    (fp_circle (center -1.25 1.5) (end -1.2 1.5) (layer "B.SilkS") (width 0.15) (fill solid))
    (fp_rect (start 1.9 1.76) (end -1.9 -1.75) (layer "B.CrtYd") (width 0.05) (fill none))
    (fp_line (start -0.398 1.526) (end -0.874 1.05) (layer "B.Fab") (width 0.15))
    (fp_rect (start 0.874 -1.523) (end -0.873 1.525) (layer "B.Fab") (width 0.15) (fill none))
    (pad "1" smd rect (at -1.351 0.951 90) (size 0.55 1) (layers "B.Cu" "B.Paste" "B.Mask")
      (net 666 "unconnected-(U18-Pad1)") (pinfunction "NC") (pintype "no_connect"))
    (pad "2" smd rect (at -1.351 0 90) (size 0.55 1) (layers "B.Cu" "B.Paste" "B.Mask")
      (net 667 "unconnected-(U18-Pad2)") (pinfunction "NC") (pintype "no_connect"))
    (pad "3" smd rect (at -1.351 -0.949 90) (size 0.55 1) (layers "B.Cu" "B.Paste" "B.Mask")
      (net 406 "Net-(R125-Pad2)") (pintype "passive"))
    (pad "4" smd rect (at 1.35 -0.949 90) (size 0.55 1) (layers "B.Cu" "B.Paste" "B.Mask")
      (net 405 "Net-(R123-Pad2)") (pintype "passive"))
    (pad "5" smd rect (at 1.35 0.951 90) (size 0.55 1) (layers "B.Cu" "B.Paste" "B.Mask")
      (net 1 "GND") (pintype "passive"))
  )

  (footprint "sa800u-baseboard-hw-footprints:L_Murata_025020_0605Metric" (layer "B.Cu")
    (tedit 61AA2C4F)
    (at 92.4 93.7 90)
    (property "Author" "Antmicro")
    (property "License" "Apache-2.0")
    (property "MPN" "NFP0QHB242HS2D")
    (property "Manufacturer" "Murata")
    (property "Sheetfile" "camera-interface.kicad_sch")
    (property "Sheetname" "Camera Interface")
    (attr smd)
    (fp_text reference "L16" (at -0.44 0.33 270) (layer "B.SilkS")
      (effects (font (size 0.7 0.7) (thickness 0.15)) (justify left bottom mirror))
    )
    (fp_text value "NFP0QHB242HS2D" (at 0 -1.55 270) (layer "B.Fab")
      (effects (font (size 0.7 0.7) (thickness 0.15)) (justify left bottom mirror))
    )
    (fp_text user "${REFERENCE}" (at -1.027 -3.406 270) (layer "B.Fab") hide
      (effects (font (size 0.7 0.7) (thickness 0.15)) (justify left bottom mirror))
    )
    (fp_text user "Author: Antmicro" (at -1.027 -4.605 270) (layer "B.Fab") hide
      (effects (font (size 0.7 0.7) (thickness 0.15)) (justify left bottom mirror))
    )
    (fp_text user "License: Apache-2.0" (at -1.027 -5.805 270) (layer "B.Fab") hide
      (effects (font (size 0.7 0.7) (thickness 0.15)) (justify left bottom mirror))
    )
    (fp_line (start -0.276 -0.45) (end 0.276 -0.45) (layer "B.SilkS") (width 0.15))
    (fp_line (start 0.276 0.45) (end -0.276 0.45) (layer "B.SilkS") (width 0.15))
    (fp_circle (center -0.5 0.5) (end -0.449 0.5) (layer "B.SilkS") (width 0.15) (fill solid))
    (fp_rect (start -0.5 0.6) (end 0.5 -0.6) (layer "B.CrtYd") (width 0.05) (fill none))
    (fp_line (start 0.275 0.351) (end -0.277 0.351) (layer "B.Fab") (width 0.15))
    (fp_line (start 0.275 -0.349) (end 0.275 0.351) (layer "B.Fab") (width 0.15))
    (fp_line (start -0.277 -0.349) (end 0.275 -0.349) (layer "B.Fab") (width 0.15))
    (fp_line (start -0.277 0.351) (end -0.277 -0.349) (layer "B.Fab") (width 0.15))
    (pad "1" smd rect (at -0.25 0.24 90) (size 0.3 0.23) (layers "B.Cu" "B.Paste" "B.Mask")
      (net 17 "CSI1_LN3_P") (pinfunction "1") (pintype "passive"))
    (pad "2" smd rect (at 0.248 0.24 90) (size 0.3 0.23) (layers "B.Cu" "B.Paste" "B.Mask")
      (net 282 "/Camera Interface/CSI1_LN3_FFC_P") (pinfunction "2") (pintype "passive"))
    (pad "3" smd rect (at 0.248 -0.239 90) (size 0.3 0.23) (layers "B.Cu" "B.Paste" "B.Mask")
      (net 283 "/Camera Interface/CSI1_LN3_FFC_N") (pinfunction "3") (pintype "passive"))
    (pad "4" smd rect (at -0.25 -0.239 90) (size 0.3 0.23) (layers "B.Cu" "B.Paste" "B.Mask")
      (net 18 "CSI1_LN3_N") (pinfunction "4") (pintype "passive"))
  )

  (footprint "sa800u-baseboard-hw-footprints:C_0402_1005Metric" (layer "B.Cu")
    (tedit 616D63CF)
    (at 131.2 103.3)
    (descr "Capacitor SMD 0402")
    (tags "capacitor SMD 0402")
    (property "Author" "Antmicro")
    (property "Dielectric" "C0G")
    (property "License" "Apache-2.0")
    (property "MPN" "GCM1555C1H100GA16D")
    (property "Manufacturer" "Murata")
    (property "Sheetfile" "other-interfaces.kicad_sch")
    (property "Sheetname" "Other Interfaces")
    (property "Val" "10p")
    (property "Voltage" "50V")
    (attr smd)
    (fp_text reference "C118" (at 1.29 -0.55 180) (layer "B.SilkS")
      (effects (font (size 0.7 0.7) (thickness 0.15)) (justify left bottom mirror))
    )
    (fp_text value "C_10p_0402" (at 0 -1.4 180) (layer "B.Fab")
      (effects (font (size 0.7 0.7) (thickness 0.15)) (justify left bottom mirror))
    )
    (fp_text user "Author: Antmicro" (at -0.932 -4.17 180) (layer "B.Fab") hide
      (effects (font (size 0.7 0.7) (thickness 0.15)) (justify left bottom mirror))
    )
    (fp_text user "License: Apache-2.0" (at -0.932 -5.17 180) (layer "B.Fab") hide
      (effects (font (size 0.7 0.7) (thickness 0.15)) (justify left bottom mirror))
    )
    (fp_text user "${REFERENCE}" (at -0.932 -3.168 180) (layer "B.Fab") hide
      (effects (font (size 0.7 0.7) (thickness 0.15)) (justify left bottom mirror))
    )
    (fp_rect (start -0.94 0.47) (end 0.94 -0.47) (layer "B.CrtYd") (width 0.05) (fill none))
    (fp_rect (start -0.499 0.249) (end 0.499 -0.249) (layer "B.Fab") (width 0.15) (fill none))
    (pad "1" smd roundrect (at -0.484 0) (size 0.59 0.64) (layers "B.Cu" "B.Paste" "B.Mask") (roundrect_rratio 0.25)
      (net 227 "/Other Interfaces/SD_VDD_R") (pintype "passive"))
    (pad "2" smd roundrect (at 0.484 0) (size 0.59 0.64) (layers "B.Cu" "B.Paste" "B.Mask") (roundrect_rratio 0.25)
      (net 1 "GND") (pintype "passive"))
  )

  (footprint "sa800u-baseboard-hw-footprints:C_0603_1608Metric" (layer "B.Cu")
    (tedit 5D5E94D2)
    (at 131.5 104.5)
    (descr "Capacitor SMD 0603")
    (tags "capacitor 0603")
    (property "Author" "Antmicro")
    (property "Dielectric" "")
    (property "License" "Apache-2.0")
    (property "MPN" "C1608X5R1V225K080AC")
    (property "Manufacturer" "TDK")
    (property "Sheetfile" "other-interfaces.kicad_sch")
    (property "Sheetname" "Other Interfaces")
    (property "Val" "2u2")
    (property "Voltage" "")
    (attr smd)
    (fp_text reference "C119" (at -1.23 0.66 180) (layer "B.SilkS")
      (effects (font (size 0.7 0.7) (thickness 0.15)) (justify left bottom mirror))
    )
    (fp_text value "C_2u2_0603" (at 0 -1.6 180) (layer "B.Fab")
      (effects (font (size 0.7 0.7) (thickness 0.15)) (justify left bottom mirror))
    )
    (fp_text user "License: Apache-2.0" (at -1.682 -5.895 180) (layer "B.Fab") hide
      (effects (font (size 0.7 0.7) (thickness 0.15)) (justify left bottom mirror))
    )
    (fp_text user "${REFERENCE}" (at -1.682 -3.895 180) (layer "B.Fab") hide
      (effects (font (size 0.7 0.7) (thickness 0.15)) (justify left bottom mirror))
    )
    (fp_text user "Author: Antmicro" (at -1.682 -4.894 180) (layer "B.Fab") hide
      (effects (font (size 0.7 0.7) (thickness 0.15)) (justify left bottom mirror))
    )
    (fp_line (start -0.3 0.3) (end 0.3 0.3) (layer "B.SilkS") (width 0.15))
    (fp_line (start -0.3 -0.3) (end 0.3 -0.3) (layer "B.SilkS") (width 0.15))
    (fp_rect (start -1.24 0.7) (end 1.24 -0.7) (layer "B.CrtYd") (width 0.05) (fill none))
    (fp_rect (start -0.8 0.4) (end 0.8 -0.4) (layer "B.Fab") (width 0.15) (fill none))
    (pad "1" smd roundrect (at -0.7 0) (size 0.6 0.8) (layers "B.Cu" "B.Paste" "B.Mask") (roundrect_rratio 0.2)
      (net 227 "/Other Interfaces/SD_VDD_R") (pintype "passive"))
    (pad "2" smd roundrect (at 0.7 0) (size 0.6 0.8) (layers "B.Cu" "B.Paste" "B.Mask") (roundrect_rratio 0.2)
      (net 1 "GND") (pintype "passive"))
  )

  (footprint "sa800u-baseboard-hw-footprints:R_0402_1005Metric" (layer "B.Cu")
    (tedit 5FD9C158)
    (at 128.8 103.6)
    (descr "Resistor SMD 0402")
    (tags "resistor SMD 0402")
    (property "Author" "Antmicro")
    (property "Current" "1A")
    (property "License" "Apache-2.0")
    (property "MPN" "ERJ2GE0R00X")
    (property "Manufacturer" "Panasonic")
    (property "Sheetfile" "other-interfaces.kicad_sch")
    (property "Sheetname" "Other Interfaces")
    (property "Tolerance" "")
    (property "Val" "0R")
    (attr smd)
    (fp_text reference "R99" (at -0.77 0.43 180) (layer "B.SilkS")
      (effects (font (size 0.7 0.7) (thickness 0.15)) (justify left bottom mirror))
    )
    (fp_text value "R_0R_0402" (at 0 -1.4 180) (layer "B.Fab")
      (effects (font (size 0.7 0.7) (thickness 0.15)) (justify left bottom mirror))
    )
    (fp_text user "License: Apache-2.0" (at -0.95 -5.169 180) (layer "B.Fab") hide
      (effects (font (size 0.7 0.7) (thickness 0.15)) (justify left bottom mirror))
    )
    (fp_text user "${REFERENCE}" (at -0.95 -3.168 180) (layer "B.Fab") hide
      (effects (font (size 0.7 0.7) (thickness 0.15)) (justify left bottom mirror))
    )
    (fp_text user "Author: Antmicro" (at -0.95 -4.169 180) (layer "B.Fab") hide
      (effects (font (size 0.7 0.7) (thickness 0.15)) (justify left bottom mirror))
    )
    (fp_rect (start -0.93 0.47) (end 0.93 -0.47) (layer "B.CrtYd") (width 0.05) (fill none))
    (fp_rect (start -0.5 0.25) (end 0.5 -0.25) (layer "B.Fab") (width 0.15) (fill none))
    (pad "1" smd roundrect (at -0.485 0) (size 0.59 0.64) (layers "B.Cu" "B.Paste" "B.Mask") (roundrect_rratio 0.25)
      (net 106 "SD_LDO21A") (pintype "passive"))
    (pad "2" smd roundrect (at 0.485 0) (size 0.59 0.64) (layers "B.Cu" "B.Paste" "B.Mask") (roundrect_rratio 0.25)
      (net 227 "/Other Interfaces/SD_VDD_R") (pintype "passive"))
  )

  (footprint "sa800u-baseboard-hw-footprints:C_0402_1005Metric" (layer "B.Cu")
    (tedit 616D63CF)
    (at 132.6 105.95 180)
    (descr "Capacitor SMD 0402")
    (tags "capacitor SMD 0402")
    (property "Author" "Antmicro")
    (property "Dielectric" "X5R")
    (property "License" "Apache-2.0")
    (property "MPN" "GRM155R61H104KE14D")
    (property "Manufacturer" "Murata")
    (property "Sheetfile" "hdmi-converter.kicad_sch")
    (property "Sheetname" "HDMI converter")
    (property "Val" "100n")
    (property "Voltage" "50V")
    (attr smd)
    (fp_text reference "C44" (at -1.97 0.54) (layer "B.SilkS")
      (effects (font (size 0.7 0.7) (thickness 0.15)) (justify left bottom mirror))
    )
    (fp_text value "C_100n_0402" (at 0 -1.4) (layer "B.Fab")
      (effects (font (size 0.7 0.7) (thickness 0.15)) (justify left bottom mirror))
    )
    (fp_text user "Author: Antmicro" (at -0.932 -4.17) (layer "B.Fab") hide
      (effects (font (size 0.7 0.7) (thickness 0.15)) (justify left bottom mirror))
    )
    (fp_text user "${REFERENCE}" (at -0.932 -3.168) (layer "B.Fab") hide
      (effects (font (size 0.7 0.7) (thickness 0.15)) (justify left bottom mirror))
    )
    (fp_text user "License: Apache-2.0" (at -0.932 -5.17) (layer "B.Fab") hide
      (effects (font (size 0.7 0.7) (thickness 0.15)) (justify left bottom mirror))
    )
    (fp_rect (start -0.94 0.47) (end 0.94 -0.47) (layer "B.CrtYd") (width 0.05) (fill none))
    (fp_rect (start -0.499 0.249) (end 0.499 -0.249) (layer "B.Fab") (width 0.15) (fill none))
    (pad "1" smd roundrect (at -0.484 0 180) (size 0.59 0.64) (layers "B.Cu" "B.Paste" "B.Mask") (roundrect_rratio 0.25)
      (net 132 "VREG_S4A_1V8") (pintype "passive"))
    (pad "2" smd roundrect (at 0.484 0 180) (size 0.59 0.64) (layers "B.Cu" "B.Paste" "B.Mask") (roundrect_rratio 0.25)
      (net 1 "GND") (pintype "passive"))
  )

  (footprint "sa800u-baseboard-hw-footprints:C_0402_1005Metric" (layer "B.Cu")
    (tedit 616D63CF)
    (at 134.5 105.95)
    (descr "Capacitor SMD 0402")
    (tags "capacitor SMD 0402")
    (property "Author" "Antmicro")
    (property "Dielectric" "X5R")
    (property "License" "Apache-2.0")
    (property "MPN" "GRM155R61H104KE14D")
    (property "Manufacturer" "Murata")
    (property "Sheetfile" "hdmi-converter.kicad_sch")
    (property "Sheetname" "HDMI converter")
    (property "Val" "100n")
    (property "Voltage" "50V")
    (attr smd)
    (fp_text reference "C54" (at 2.16 -0.54 180) (layer "B.SilkS")
      (effects (font (size 0.7 0.7) (thickness 0.15)) (justify left bottom mirror))
    )
    (fp_text value "C_100n_0402" (at 0 -1.4 180) (layer "B.Fab")
      (effects (font (size 0.7 0.7) (thickness 0.15)) (justify left bottom mirror))
    )
    (fp_text user "Author: Antmicro" (at -0.932 -4.17 180) (layer "B.Fab") hide
      (effects (font (size 0.7 0.7) (thickness 0.15)) (justify left bottom mirror))
    )
    (fp_text user "License: Apache-2.0" (at -0.932 -5.17 180) (layer "B.Fab") hide
      (effects (font (size 0.7 0.7) (thickness 0.15)) (justify left bottom mirror))
    )
    (fp_text user "${REFERENCE}" (at -0.932 -3.168 180) (layer "B.Fab") hide
      (effects (font (size 0.7 0.7) (thickness 0.15)) (justify left bottom mirror))
    )
    (fp_rect (start -0.94 0.47) (end 0.94 -0.47) (layer "B.CrtYd") (width 0.05) (fill none))
    (fp_rect (start -0.499 0.249) (end 0.499 -0.249) (layer "B.Fab") (width 0.15) (fill none))
    (pad "1" smd roundrect (at -0.484 0) (size 0.59 0.64) (layers "B.Cu" "B.Paste" "B.Mask") (roundrect_rratio 0.25)
      (net 131 "3V3_SYS") (pintype "passive"))
    (pad "2" smd roundrect (at 0.484 0) (size 0.59 0.64) (layers "B.Cu" "B.Paste" "B.Mask") (roundrect_rratio 0.25)
      (net 1 "GND") (pintype "passive"))
  )

  (footprint "sa800u-baseboard-hw-footprints:C_0402_1005Metric" (layer "B.Cu")
    (tedit 616D63CF)
    (at 140.34 91.44 180)
    (descr "Capacitor SMD 0402")
    (tags "capacitor SMD 0402")
    (property "Author" "Antmicro")
    (property "Dielectric" "")
    (property "License" "Apache-2.0")
    (property "MPN" "C1005X6S1A105K050BC")
    (property "Manufacturer" "TDK")
    (property "Sheetfile" "m2.kicad_sch")
    (property "Sheetname" "M2")
    (property "Val" "1u")
    (property "Voltage" "")
    (attr smd)
    (fp_text reference "C111" (at -0.82 0.61) (layer "B.SilkS")
      (effects (font (size 0.7 0.7) (thickness 0.15)) (justify left bottom mirror))
    )
    (fp_text value "C_1u_0402" (at 0 -1.4) (layer "B.Fab")
      (effects (font (size 0.7 0.7) (thickness 0.15)) (justify left bottom mirror))
    )
    (fp_text user "${REFERENCE}" (at -0.932 -3.168) (layer "B.Fab") hide
      (effects (font (size 0.7 0.7) (thickness 0.15)) (justify left bottom mirror))
    )
    (fp_text user "License: Apache-2.0" (at -0.932 -5.17) (layer "B.Fab") hide
      (effects (font (size 0.7 0.7) (thickness 0.15)) (justify left bottom mirror))
    )
    (fp_text user "Author: Antmicro" (at -0.932 -4.17) (layer "B.Fab") hide
      (effects (font (size 0.7 0.7) (thickness 0.15)) (justify left bottom mirror))
    )
    (fp_rect (start -0.94 0.47) (end 0.94 -0.47) (layer "B.CrtYd") (width 0.05) (fill none))
    (fp_rect (start -0.499 0.249) (end 0.499 -0.249) (layer "B.Fab") (width 0.15) (fill none))
    (pad "1" smd roundrect (at -0.484 0 180) (size 0.59 0.64) (layers "B.Cu" "B.Paste" "B.Mask") (roundrect_rratio 0.25)
      (net 131 "3V3_SYS") (pintype "passive"))
    (pad "2" smd roundrect (at 0.484 0 180) (size 0.59 0.64) (layers "B.Cu" "B.Paste" "B.Mask") (roundrect_rratio 0.25)
      (net 1 "GND") (pintype "passive"))
  )

  (footprint "sa800u-baseboard-hw-footprints:C_0402_1005Metric" (layer "B.Cu")
    (tedit 616D63CF)
    (at 140.345 105.6 180)
    (descr "Capacitor SMD 0402")
    (tags "capacitor SMD 0402")
    (property "Author" "Antmicro")
    (property "Dielectric" "")
    (property "License" "Apache-2.0")
    (property "MPN" "C1005X6S1A105K050BC")
    (property "Manufacturer" "TDK")
    (property "Sheetfile" "m2.kicad_sch")
    (property "Sheetname" "M2")
    (property "Val" "1u")
    (property "Voltage" "")
    (attr smd)
    (fp_text reference "C112" (at 0.81 -0.35) (layer "B.SilkS")
      (effects (font (size 0.7 0.7) (thickness 0.15)) (justify left bottom mirror))
    )
    (fp_text value "C_1u_0402" (at 0 -1.4) (layer "B.Fab")
      (effects (font (size 0.7 0.7) (thickness 0.15)) (justify left bottom mirror))
    )
    (fp_text user "Author: Antmicro" (at -0.932 -4.17) (layer "B.Fab") hide
      (effects (font (size 0.7 0.7) (thickness 0.15)) (justify left bottom mirror))
    )
    (fp_text user "License: Apache-2.0" (at -0.932 -5.17) (layer "B.Fab") hide
      (effects (font (size 0.7 0.7) (thickness 0.15)) (justify left bottom mirror))
    )
    (fp_text user "${REFERENCE}" (at -0.932 -3.168) (layer "B.Fab") hide
      (effects (font (size 0.7 0.7) (thickness 0.15)) (justify left bottom mirror))
    )
    (fp_rect (start -0.94 0.47) (end 0.94 -0.47) (layer "B.CrtYd") (width 0.05) (fill none))
    (fp_rect (start -0.499 0.249) (end 0.499 -0.249) (layer "B.Fab") (width 0.15) (fill none))
    (pad "1" smd roundrect (at -0.484 0 180) (size 0.59 0.64) (layers "B.Cu" "B.Paste" "B.Mask") (roundrect_rratio 0.25)
      (net 131 "3V3_SYS") (pintype "passive"))
    (pad "2" smd roundrect (at 0.484 0 180) (size 0.59 0.64) (layers "B.Cu" "B.Paste" "B.Mask") (roundrect_rratio 0.25)
      (net 1 "GND") (pintype "passive"))
  )

  (footprint "sa800u-baseboard-hw-footprints:C_0402_1005Metric" (layer "B.Cu")
    (tedit 616D63CF)
    (at 140.34 109.05 180)
    (descr "Capacitor SMD 0402")
    (tags "capacitor SMD 0402")
    (property "Author" "Antmicro")
    (property "Dielectric" "")
    (property "License" "Apache-2.0")
    (property "MPN" "C1005X6S1A105K050BC")
    (property "Manufacturer" "TDK")
    (property "Sheetfile" "m2.kicad_sch")
    (property "Sheetname" "M2")
    (property "Val" "1u")
    (property "Voltage" "")
    (attr smd)
    (fp_text reference "C114" (at -1.01 -1.31) (layer "B.SilkS")
      (effects (font (size 0.7 0.7) (thickness 0.15)) (justify left bottom mirror))
    )
    (fp_text value "C_1u_0402" (at 0 -1.4) (layer "B.Fab")
      (effects (font (size 0.7 0.7) (thickness 0.15)) (justify left bottom mirror))
    )
    (fp_text user "Author: Antmicro" (at -0.932 -4.17) (layer "B.Fab") hide
      (effects (font (size 0.7 0.7) (thickness 0.15)) (justify left bottom mirror))
    )
    (fp_text user "License: Apache-2.0" (at -0.932 -5.17) (layer "B.Fab") hide
      (effects (font (size 0.7 0.7) (thickness 0.15)) (justify left bottom mirror))
    )
    (fp_text user "${REFERENCE}" (at -0.932 -3.168) (layer "B.Fab") hide
      (effects (font (size 0.7 0.7) (thickness 0.15)) (justify left bottom mirror))
    )
    (fp_rect (start -0.94 0.47) (end 0.94 -0.47) (layer "B.CrtYd") (width 0.05) (fill none))
    (fp_rect (start -0.499 0.249) (end 0.499 -0.249) (layer "B.Fab") (width 0.15) (fill none))
    (pad "1" smd roundrect (at -0.484 0 180) (size 0.59 0.64) (layers "B.Cu" "B.Paste" "B.Mask") (roundrect_rratio 0.25)
      (net 131 "3V3_SYS") (pintype "passive"))
    (pad "2" smd roundrect (at 0.484 0 180) (size 0.59 0.64) (layers "B.Cu" "B.Paste" "B.Mask") (roundrect_rratio 0.25)
      (net 1 "GND") (pintype "passive"))
  )

  (footprint "sa800u-baseboard-hw-footprints:SC70-3" (layer "B.Cu")
    (tedit 615FF353)
    (at 118.745 113.6)
    (property "Author" "Antmicro")
    (property "License" "Apache-2.0")
    (property "MPN" "BSS138PW")
    (property "Manufacturer" "Nexperia")
    (property "Sheetfile" "hdmi-converter.kicad_sch")
    (property "Sheetname" "HDMI converter")
    (attr smd)
    (fp_text reference "Q1" (at 0.48 -1.42 180) (layer "B.SilkS")
      (effects (font (size 0.7 0.7) (thickness 0.15)) (justify left bottom mirror))
    )
    (fp_text value "BSS138PW" (at 0 -2.3 180) (layer "B.Fab")
      (effects (font (size 0.7 0.7) (thickness 0.15)) (justify left bottom mirror))
    )
    (fp_text user "${REFERENCE}" (at -1.45 -4.783 180) (layer "B.Fab") hide
      (effects (font (size 0.7 0.7) (thickness 0.15)) (justify left bottom mirror))
    )
    (fp_text user "License: Apache-2.0" (at -1.45 -6.782 180) (layer "B.Fab") hide
      (effects (font (size 0.7 0.7) (thickness 0.15)) (justify left bottom mirror))
    )
    (fp_text user "Author: Antmicro" (at -1.45 -5.782 180) (layer "B.Fab") hide
      (effects (font (size 0.7 0.7) (thickness 0.15)) (justify left bottom mirror))
    )
    (fp_line (start 0.627 0.6) (end 0.627 0.999) (layer "B.SilkS") (width 0.15))
    (fp_line (start -0.3 -1) (end 0.627 -1.001) (layer "B.SilkS") (width 0.15))
    (fp_line (start 0.627 -0.6) (end 0.627 -1.001) (layer "B.SilkS") (width 0.15))
    (fp_line (start -0.3 1) (end 0.627 0.999) (layer "B.SilkS") (width 0.15))
    (fp_line (start -1.4 -1) (end -1.4 1) (layer "B.CrtYd") (width 0.05))
    (fp_line (start 0.9 -0.4) (end 0.9 -1.3) (layer "B.CrtYd") (width 0.05))
    (fp_line (start 0.9 -1.3) (end -0.9 -1.3) (layer "B.CrtYd") (width 0.05))
    (fp_line (start 1.4 0.4) (end 1.4 -0.4) (layer "B.CrtYd") (width 0.05))
    (fp_line (start -0.9 1.3) (end 0.9 1.3) (layer "B.CrtYd") (width 0.05))
    (fp_line (start -0.9 1.3) (end -0.9 1) (layer "B.CrtYd") (width 0.05))
    (fp_line (start -0.9 1) (end -1.4 1) (layer "B.CrtYd") (width 0.05))
    (fp_line (start 0.9 0.4) (end 1.4 0.4) (layer "B.CrtYd") (width 0.05))
    (fp_line (start -0.9 -1) (end -1.4 -1) (layer "B.CrtYd") (width 0.05))
    (fp_line (start 1.4 -0.4) (end 0.9 -0.4) (layer "B.CrtYd") (width 0.05))
    (fp_line (start -0.9 -1.3) (end -0.9 -1) (layer "B.CrtYd") (width 0.05))
    (fp_line (start 0.9 1.3) (end 0.9 0.4) (layer "B.CrtYd") (width 0.05))
    (fp_rect (start -0.623 0.999) (end 0.627 -1.001) (layer "B.Fab") (width 0.15) (fill none))
    (pad "1" smd rect (at -1.051 0.65 270) (size 0.6 0.6) (layers "B.Cu" "B.Paste" "B.Mask")
      (net 132 "VREG_S4A_1V8") (pinfunction "G") (pintype "bidirectional"))
    (pad "2" smd rect (at -1.051 -0.65 270) (size 0.6 0.6) (layers "B.Cu" "B.Paste" "B.Mask")
      (net 35 "LT9611_GPIO5") (pinfunction "S") (pintype "bidirectional"))
    (pad "3" smd rect (at 1.05 0 270) (size 0.6 0.6) (layers "B.Cu" "B.Paste" "B.Mask")
      (net 284 "/HDMI converter/LT9611_INTO_GPIO5") (pinfunction "D") (pintype "bidirectional"))
  )

  (footprint "sa800u-baseboard-hw-footprints:SC70-3" (layer "B.Cu")
    (tedit 615FF353)
    (at 118.8 116.2)
    (property "Author" "Antmicro")
    (property "License" "Apache-2.0")
    (property "MPN" "BSS138PW")
    (property "Manufacturer" "Nexperia")
    (property "Sheetfile" "hdmi-converter.kicad_sch")
    (property "Sheetname" "HDMI converter")
    (attr smd)
    (fp_text reference "Q2" (at 0.59 1.95 180) (layer "B.SilkS")
      (effects (font (size 0.7 0.7) (thickness 0.15)) (justify left bottom mirror))
    )
    (fp_text value "BSS138PW" (at 0 -2.3 180) (layer "B.Fab")
      (effects (font (size 0.7 0.7) (thickness 0.15)) (justify left bottom mirror))
    )
    (fp_text user "Author: Antmicro" (at -1.45 -5.782 180) (layer "B.Fab") hide
      (effects (font (size 0.7 0.7) (thickness 0.15)) (justify left bottom mirror))
    )
    (fp_text user "License: Apache-2.0" (at -1.45 -6.782 180) (layer "B.Fab") hide
      (effects (font (size 0.7 0.7) (thickness 0.15)) (justify left bottom mirror))
    )
    (fp_text user "${REFERENCE}" (at -1.45 -4.783 180) (layer "B.Fab") hide
      (effects (font (size 0.7 0.7) (thickness 0.15)) (justify left bottom mirror))
    )
    (fp_line (start -0.3 1) (end 0.627 0.999) (layer "B.SilkS") (width 0.15))
    (fp_line (start 0.627 -0.6) (end 0.627 -1.001) (layer "B.SilkS") (width 0.15))
    (fp_line (start -0.3 -1) (end 0.627 -1.001) (layer "B.SilkS") (width 0.15))
    (fp_line (start 0.627 0.6) (end 0.627 0.999) (layer "B.SilkS") (width 0.15))
    (fp_line (start 1.4 0.4) (end 1.4 -0.4) (layer "B.CrtYd") (width 0.05))
    (fp_line (start 0.9 -0.4) (end 0.9 -1.3) (layer "B.CrtYd") (width 0.05))
    (fp_line (start -0.9 -1.3) (end -0.9 -1) (layer "B.CrtYd") (width 0.05))
    (fp_line (start -0.9 1) (end -1.4 1) (layer "B.CrtYd") (width 0.05))
    (fp_line (start -0.9 1.3) (end -0.9 1) (layer "B.CrtYd") (width 0.05))
    (fp_line (start 1.4 -0.4) (end 0.9 -0.4) (layer "B.CrtYd") (width 0.05))
    (fp_line (start -0.9 -1) (end -1.4 -1) (layer "B.CrtYd") (width 0.05))
    (fp_line (start -1.4 -1) (end -1.4 1) (layer "B.CrtYd") (width 0.05))
    (fp_line (start 0.9 -1.3) (end -0.9 -1.3) (layer "B.CrtYd") (width 0.05))
    (fp_line (start 0.9 0.4) (end 1.4 0.4) (layer "B.CrtYd") (width 0.05))
    (fp_line (start -0.9 1.3) (end 0.9 1.3) (layer "B.CrtYd") (width 0.05))
    (fp_line (start 0.9 1.3) (end 0.9 0.4) (layer "B.CrtYd") (width 0.05))
    (fp_rect (start -0.623 0.999) (end 0.627 -1.001) (layer "B.Fab") (width 0.15) (fill none))
    (pad "1" smd rect (at -1.051 0.65 270) (size 0.6 0.6) (layers "B.Cu" "B.Paste" "B.Mask")
      (net 132 "VREG_S4A_1V8") (pinfunction "G") (pintype "bidirectional"))
    (pad "2" smd rect (at -1.051 -0.65 270) (size 0.6 0.6) (layers "B.Cu" "B.Paste" "B.Mask")
      (net 36 "LT9611_RST") (pinfunction "S") (pintype "bidirectional"))
    (pad "3" smd rect (at 1.05 0 270) (size 0.6 0.6) (layers "B.Cu" "B.Paste" "B.Mask")
      (net 186 "/HDMI converter/LT9611_RST_N") (pinfunction "D") (pintype "bidirectional"))
  )

  (footprint "sa800u-baseboard-hw-footprints:PowerPak-1212" (layer "B.Cu")
    (tedit 625E61BE)
    (at 76.8 136.75 180)
    (property "Author" "Antmicro")
    (property "License" "Apache-2.0")
    (property "MPN" "SI7223DN-T1-GE3")
    (property "Manufacturer" "Vishay")
    (property "Sheetfile" "psu.kicad_sch")
    (property "Sheetname" "PSU")
    (attr smd)
    (fp_text reference "Q9" (at 0 2.5) (layer "B.SilkS")
      (effects (font (size 0.65 0.65) (thickness 0.15)) (justify mirror))
    )
    (fp_text value "Si7223DN" (at 0 -3) (layer "B.Fab") hide
      (effects (font (size 0.65 0.65) (thickness 0.15)) (justify mirror))
    )
    (fp_text user "Author: Antmicro" (at -2.667 -7.4) (layer "B.Fab") hide
      (effects (font (size 0.7 0.7) (thickness 0.15)) (justify left bottom mirror))
    )
    (fp_text user "${REFERENCE}" (at 0 0) (layer "B.Fab") hide
      (effects (font (size 0.65 0.65) (thickness 0.15)) (justify mirror))
    )
    (fp_text user "License: Apache-2.0" (at -2.667 -8.599) (layer "B.Fab") hide
      (effects (font (size 0.7 0.7) (thickness 0.15)) (justify left bottom mirror))
    )
    (fp_poly (pts
        (xy 1.699 -1.178)
        (xy 1.699 -0.771)
        (xy 1.14 -0.771)
        (xy 1.14 -0.528)
        (xy 1.699 -0.528)
        (xy 1.699 -0.121)
        (xy 1.14 -0.121)
        (xy 1.14 -0.174)
        (xy -0.387 -0.174)
        (xy -0.387 -1.119)
        (xy -0.386607 -1.698508)
        (xy -0.047 -1.699)
        (xy -0.047 -1.119)
        (xy 1.14 -1.119)
        (xy 1.14 -1.178)
      ) (layer "B.Paste") (width 0.1) (fill solid))
    (fp_poly (pts
        (xy 1.699 0.122)
        (xy 1.699 0.529)
        (xy 1.14 0.529)
        (xy 1.14 0.772)
        (xy 1.699 0.772)
        (xy 1.699 1.179)
        (xy 1.14 1.179)
        (xy 1.14 1.12)
        (xy -0.047 1.12)
        (xy -0.047 1.7)
        (xy -0.387 1.7)
        (xy -0.387 1.12)
        (xy -0.386607 0.174507)
        (xy 1.14 0.175)
        (xy 1.14 0.122)
      ) (layer "B.Paste") (width 0.1) (fill solid))
    (fp_line (start -1.702 -1.701) (end -1.702 -1.51) (layer "B.SilkS") (width 0.15))
    (fp_line (start -1.702 1.702) (end -0.6 1.7) (layer "B.SilkS") (width 0.15))
    (fp_line (start 1.701 -1.701) (end 0.2 -1.7) (layer "B.SilkS") (width 0.15))
    (fp_line (start -0.6 -1.7) (end -1.702 -1.701) (layer "B.SilkS") (width 0.15))
    (fp_line (start -1.702 1.511) (end -1.702 1.702) (layer "B.SilkS") (width 0.15))
    (fp_line (start 1.701 -1.51) (end 1.701 -1.701) (layer "B.SilkS") (width 0.15))
    (fp_line (start 1.701 1.702) (end 1.701 1.511) (layer "B.SilkS") (width 0.15))
    (fp_line (start 0.2 1.702) (end 1.701 1.702) (layer "B.SilkS") (width 0.15))
    (fp_circle (center -1.85 1.3) (end -1.8 1.3) (layer "B.SilkS") (width 0.15) (fill solid))
    (fp_poly (pts
        (xy -0.387 -0.174)
        (xy -0.387 -1.699)
        (xy -0.047 -1.699)
        (xy -0.047 -1.119)
        (xy 1.14 -1.119)
        (xy 1.14 -1.178)
        (xy 1.699 -1.178)
        (xy 1.699 -0.771)
        (xy 1.14 -0.771)
        (xy 1.14 -0.528)
        (xy 1.699 -0.528)
        (xy 1.699 -0.121)
        (xy 1.14 -0.121)
        (xy 1.14 -0.174)
      ) (layer "B.Mask") (width 0.1) (fill solid))
    (fp_poly (pts
        (xy 1.699 1.179)
        (xy 1.14 1.179)
        (xy 1.14 1.12)
        (xy -0.047 1.12)
        (xy -0.047 1.7)
        (xy -0.387 1.7)
        (xy -0.387 0.175)
        (xy 1.14 0.175)
        (xy 1.14 0.122)
        (xy 1.699 0.122)
        (xy 1.699 0.529)
        (xy 1.14 0.529)
        (xy 1.14 0.772)
        (xy 1.699 0.772)
      ) (layer "B.Mask") (width 0.1) (fill solid))
    (fp_line (start 1.95 -1.95) (end -1.96 -1.95) (layer "B.CrtYd") (width 0.05))
    (fp_line (start -1.96 -1.95) (end -1.96 1.96) (layer "B.CrtYd") (width 0.05))
    (fp_line (start 1.95 1.96) (end 1.95 -1.95) (layer "B.CrtYd") (width 0.05))
    (fp_line (start -1.96 1.96) (end 1.95 1.96) (layer "B.CrtYd") (width 0.05))
    (fp_line (start -1.575 1.575) (end 1.574 1.575) (layer "B.Fab") (width 0.15))
    (fp_line (start -1.575 -1.574) (end -1.575 1.575) (layer "B.Fab") (width 0.15))
    (fp_line (start 1.574 1.575) (end 1.574 -1.574) (layer "B.Fab") (width 0.15))
    (fp_line (start 1.574 -1.574) (end -1.575 -1.574) (layer "B.Fab") (width 0.15))
    (fp_circle (center 0.99 0.975) (end 0.914 0.975) (layer "B.Fab") (width 0.15) (fill none))
    (pad "1" smd rect (at -1.446 0.975 180) (size 0.508 0.4064) (layers "B.Cu" "B.Paste" "B.Mask")
      (net 157 "/PSU/VS1") (pinfunction "S1") (pintype "passive"))
    (pad "2" smd rect (at -1.446 0.325 180) (size 0.508 0.4064) (layers "B.Cu" "B.Paste" "B.Mask")
      (net 354 "/PSU/G1") (pinfunction "G1") (pintype "passive"))
    (pad "3" smd rect (at -1.446 -0.324 180) (size 0.508 0.4064) (layers "B.Cu" "B.Paste" "B.Mask")
      (net 157 "/PSU/VS1") (pinfunction "S2") (pintype "passive"))
    (pad "4" smd rect (at -1.446 -0.974 180) (size 0.508 0.4064) (layers "B.Cu" "B.Paste" "B.Mask")
      (net 354 "/PSU/G1") (pinfunction "G2") (pintype "passive"))
    (pad "5" smd rect (at 1.42 -0.974 180) (size 0.5588 0.4064) (layers "B.Cu" "B.Paste" "B.Mask")
      (net 152 "/PSU/AUX_VDD") (pinfunction "D2") (pintype "passive"))
    (pad "6" smd custom (at 1.42 -0.324 180) (size 0.5588 0.4064) (layers "B.Cu" "B.Paste" "B.Mask")
      (net 152 "/PSU/AUX_VDD") (pinfunction "D2") (pintype "passive") (zone_connect 2)
      (options (clearance outline) (anchor rect))
      (primitives
        (gr_poly (pts
            (xy 0.2794 -0.853186)
            (xy 0.2794 -0.446786)
            (xy -0.2794 -0.446786)
            (xy -0.2794 -0.2032)
            (xy 0.2794 -0.2032)
            (xy 0.2794 0.2032)
            (xy -0.2794 0.2032)
            (xy -0.279407 0.150493)
            (xy -1.806607 0.150493)
            (xy -1.806607 -1.374508)
            (xy -1.466602 -1.374508)
            (xy -1.466602 -0.794499)
            (xy -0.279407 -0.794507)
            (xy -0.2794 -0.853186)
          ) (width 0.1) (fill yes))
      ))
    (pad "7" smd custom (at 1.42 0.325 180) (size 0.5588 0.4064) (layers "B.Cu" "B.Paste" "B.Mask")
      (net 74 "VDD") (pinfunction "D1") (pintype "passive") (zone_connect 2)
      (options (clearance outline) (anchor rect))
      (primitives
        (gr_poly (pts
            (xy 0.2794 0.446786)
            (xy 0.2794 0.853186)
            (xy -0.2794 0.853186)
            (xy -0.279407 0.794507)
            (xy -1.466602 0.794499)
            (xy -1.466602 1.374508)
            (xy -1.806607 1.374508)
            (xy -1.806607 -0.150493)
            (xy -0.279407 -0.150493)
            (xy -0.2794 -0.2032)
            (xy 0.2794 -0.2032)
            (xy 0.2794 0.2032)
            (xy -0.2794 0.2032)
            (xy -0.2794 0.446786)
          ) (width 0.1) (fill yes))
      ))
    (pad "8" smd rect (at 1.42 0.975 180) (size 0.5588 0.4064) (layers "B.Cu" "B.Paste" "B.Mask")
      (net 74 "VDD") (pinfunction "D1") (pintype "passive"))
  )

  (footprint "sa800u-baseboard-hw-footprints:Vishay_PowerPAK_1212-8_Single" (layer "B.Cu")
    (tedit 61E93346)
    (at 78.7 117.6)
    (descr "PowerPAK 1212-8 Single")
    (tags "Vishay PowerPAK 1212-8 Single")
    (property "Author" "Antmicro")
    (property "License" "Apache-2.0")
    (property "MPN" "SQS401EN-T1_BE3")
    (property "Manufacturer" "Vishay")
    (property "Sheetfile" "psu.kicad_sch")
    (property "Sheetname" "PSU")
    (attr smd)
    (fp_text reference "Q16" (at 2.25 -1.84 180) (layer "B.SilkS")
      (effects (font (size 0.7 0.7) (thickness 0.15)) (justify left bottom mirror))
    )
    (fp_text value "SQS401EN-T1_BE3" (at -8 -2.7 180) (layer "B.Fab")
      (effects (font (size 0.7 0.7) (thickness 0.15)) (justify left bottom mirror))
    )
    (fp_text user "License: Apache-2.0" (at -8 -7.1 180) (layer "B.Fab") hide
      (effects (font (size 0.7 0.7) (thickness 0.15)) (justify left bottom mirror))
    )
    (fp_text user "Author: Antmicro" (at -8 -5.9 180) (layer "B.Fab") hide
      (effects (font (size 0.7 0.7) (thickness 0.15)) (justify left bottom mirror))
    )
    (fp_text user "${REFERENCE}" (at -8 -4.7 180) (layer "B.Fab") hide
      (effects (font (size 0.7 0.7) (thickness 0.15)) (justify left bottom mirror))
    )
    (fp_line (start -1.635 -1.3) (end -1.635 -1.634) (layer "B.SilkS") (width 0.15))
    (fp_line (start 1.634 -1.3) (end 1.634 -1.634) (layer "B.SilkS") (width 0.15))
    (fp_line (start -1.651 1.651) (end 1.648 1.651) (layer "B.SilkS") (width 0.15))
    (fp_line (start -1.635 -1.634) (end 1.634 -1.634) (layer "B.SilkS") (width 0.15))
    (fp_line (start -1.651 1.651) (end -1.651 1.317) (layer "B.SilkS") (width 0.15))
    (fp_line (start 1.648 1.651) (end 1.648 1.317) (layer "B.SilkS") (width 0.15))
    (fp_circle (center -1.9 1.4) (end -1.85 1.4) (layer "B.SilkS") (width 0.15) (fill solid))
    (fp_rect (start -2 1.8) (end 2 -1.798) (layer "B.CrtYd") (width 0.05) (fill none))
    (fp_line (start -1.6425 1.4175) (end -1.4175 1.6425) (layer "B.Fab") (width 0.15))
    (fp_rect (start -1.651 1.651) (end 1.648 -1.648) (layer "B.Fab") (width 0.15) (fill none))
    (pad "1" smd rect (at -1.436 0.99) (size 0.99 0.405) (layers "B.Cu" "B.Paste" "B.Mask")
      (net 74 "VDD") (pinfunction "S") (pintype "bidirectional"))
    (pad "2" smd rect (at -1.436 0.332) (size 0.99 0.405) (layers "B.Cu" "B.Paste" "B.Mask")
      (net 74 "VDD") (pinfunction "S") (pintype "bidirectional"))
    (pad "3" smd rect (at -1.436 -0.33) (size 0.99 0.405) (layers "B.Cu" "B.Paste" "B.Mask")
      (net 74 "VDD") (pinfunction "S") (pintype "bidirectional"))
    (pad "4" smd rect (at -1.436 -0.988) (size 0.99 0.405) (layers "B.Cu" "B.Paste" "B.Mask")
      (net 156 "/PSU/BYPASS_EN") (pinfunction "G") (pintype "bidirectional"))
    (pad "5" smd custom (at 0.557 0) (size 1.725 2.235) (layers "B.Cu" "B.Paste" "B.Mask")
      (net 133 "5V_SYS") (pinfunction "D") (pintype "bidirectional") (zone_connect 2)
      (options (clearance outline) (anchor rect))
      (primitives
        (gr_poly (pts
            (xy 0.8625 -0.1275)
            (xy 0.8625 0.1275)
            (xy 1.3725 0.1275)
            (xy 1.3725 0.5325)
            (xy 0.8625 0.5325)
            (xy 0.8625 0.7875)
            (xy 1.3725 0.7875)
            (xy 1.3725 1.195)
            (xy 0.6125 1.195)
            (xy 0.6125 -1.195)
            (xy 1.3725 -1.195)
            (xy 1.3725 -0.7875)
            (xy 0.8625 -0.7875)
            (xy 0.8625 -0.5325)
            (xy 1.3725 -0.5325)
            (xy 1.3725 -0.1275)
          ) (width 0) (fill yes))
      ))
  )

  (footprint "sa800u-baseboard-hw-footprints:R_0402_1005Metric" (layer "B.Cu")
    (tedit 5FD9C158)
    (at 148 83)
    (descr "Resistor SMD 0402")
    (tags "resistor SMD 0402")
    (property "Author" "Antmicro")
    (property "Current" "1A")
    (property "DNP" "DNP")
    (property "License" "Apache-2.0")
    (property "MPN" "ERJ2GE0R00X")
    (property "Manufacturer" "Panasonic")
    (property "Sheetfile" "sa800u-baseboard-hw.kicad_sch")
    (property "Sheetname" "")
    (property "Tolerance" "")
    (property "Val" "0R")
    (attr exclude_from_pos_files)
    (fp_text reference "R1" (at 0.6 1.37 180) (layer "B.SilkS")
      (effects (font (size 0.7 0.7) (thickness 0.15)) (justify left bottom mirror))
    )
    (fp_text value "R_0R_0402" (at 0 -1.4 180) (layer "B.Fab")
      (effects (font (size 0.7 0.7) (thickness 0.15)) (justify left bottom mirror))
    )
    (fp_text user "${REFERENCE}" (at -0.95 -3.168 180) (layer "B.Fab") hide
      (effects (font (size 0.7 0.7) (thickness 0.15)) (justify left bottom mirror))
    )
    (fp_text user "License: Apache-2.0" (at -0.95 -5.169 180) (layer "B.Fab") hide
      (effects (font (size 0.7 0.7) (thickness 0.15)) (justify left bottom mirror))
    )
    (fp_text user "Author: Antmicro" (at -0.95 -4.169 180) (layer "B.Fab") hide
      (effects (font (size 0.7 0.7) (thickness 0.15)) (justify left bottom mirror))
    )
    (fp_rect (start -0.93 0.47) (end 0.93 -0.47) (layer "B.CrtYd") (width 0.05) (fill none))
    (fp_rect (start -0.5 0.25) (end 0.5 -0.25) (layer "B.Fab") (width 0.15) (fill none))
    (pad "1" smd roundrect (at -0.485 0) (size 0.59 0.64) (layers "B.Cu" "B.Paste" "B.Mask") (roundrect_rratio 0.25)
      (net 1 "GND") (pintype "passive"))
    (pad "2" smd roundrect (at 0.485 0) (size 0.59 0.64) (layers "B.Cu" "B.Paste" "B.Mask") (roundrect_rratio 0.25)
      (net 392 "Net-(R1-Pad2)") (pintype "passive"))
  )

  (footprint "sa800u-baseboard-hw-footprints:R_0402_1005Metric" (layer "B.Cu")
    (tedit 5FD9C158)
    (at 61 151)
    (descr "Resistor SMD 0402")
    (tags "resistor SMD 0402")
    (property "Author" "Antmicro")
    (property "Current" "1A")
    (property "DNP" "DNP")
    (property "License" "Apache-2.0")
    (property "MPN" "ERJ2GE0R00X")
    (property "Manufacturer" "Panasonic")
    (property "Sheetfile" "sa800u-baseboard-hw.kicad_sch")
    (property "Sheetname" "")
    (property "Tolerance" "")
    (property "Val" "0R")
    (attr exclude_from_pos_files)
    (fp_text reference "R4" (at 0.74 -0.63 180) (layer "B.SilkS")
      (effects (font (size 0.7 0.7) (thickness 0.15)) (justify left bottom mirror))
    )
    (fp_text value "R_0R_0402" (at 0 -1.4 180) (layer "B.Fab")
      (effects (font (size 0.7 0.7) (thickness 0.15)) (justify left bottom mirror))
    )
    (fp_text user "License: Apache-2.0" (at -0.95 -5.169 180) (layer "B.Fab") hide
      (effects (font (size 0.7 0.7) (thickness 0.15)) (justify left bottom mirror))
    )
    (fp_text user "${REFERENCE}" (at -0.95 -3.168 180) (layer "B.Fab") hide
      (effects (font (size 0.7 0.7) (thickness 0.15)) (justify left bottom mirror))
    )
    (fp_text user "Author: Antmicro" (at -0.95 -4.169 180) (layer "B.Fab") hide
      (effects (font (size 0.7 0.7) (thickness 0.15)) (justify left bottom mirror))
    )
    (fp_rect (start -0.93 0.47) (end 0.93 -0.47) (layer "B.CrtYd") (width 0.05) (fill none))
    (fp_rect (start -0.5 0.25) (end 0.5 -0.25) (layer "B.Fab") (width 0.15) (fill none))
    (pad "1" smd roundrect (at -0.485 0) (size 0.59 0.64) (layers "B.Cu" "B.Paste" "B.Mask") (roundrect_rratio 0.25)
      (net 4 "Earth") (pintype "passive"))
    (pad "2" smd roundrect (at 0.485 0) (size 0.59 0.64) (layers "B.Cu" "B.Paste" "B.Mask") (roundrect_rratio 0.25)
      (net 39 "Net-(R4-Pad2)") (pintype "passive"))
  )

  (footprint "sa800u-baseboard-hw-footprints:R_0402_1005Metric" (layer "B.Cu")
    (tedit 5FD9C158)
    (at 68.75 85.5 180)
    (descr "Resistor SMD 0402")
    (tags "resistor SMD 0402")
    (property "Author" "Antmicro")
    (property "Current" "1A")
    (property "DNP" "DNP")
    (property "License" "Apache-2.0")
    (property "MPN" "ERJ2GE0R00X")
    (property "Manufacturer" "Panasonic")
    (property "Sheetfile" "sa800u-baseboard-hw.kicad_sch")
    (property "Sheetname" "")
    (property "Tolerance" "")
    (property "Val" "0R")
    (attr exclude_from_pos_files)
    (fp_text reference "R3" (at -0.57 0.68) (layer "B.SilkS")
      (effects (font (size 0.7 0.7) (thickness 0.15)) (justify left bottom mirror))
    )
    (fp_text value "R_0R_0402" (at 0 -1.4) (layer "B.Fab")
      (effects (font (size 0.7 0.7) (thickness 0.15)) (justify left bottom mirror))
    )
    (fp_text user "${REFERENCE}" (at -0.95 -3.168) (layer "B.Fab") hide
      (effects (font (size 0.7 0.7) (thickness 0.15)) (justify left bottom mirror))
    )
    (fp_text user "License: Apache-2.0" (at -0.95 -5.169) (layer "B.Fab") hide
      (effects (font (size 0.7 0.7) (thickness 0.15)) (justify left bottom mirror))
    )
    (fp_text user "Author: Antmicro" (at -0.95 -4.169) (layer "B.Fab") hide
      (effects (font (size 0.7 0.7) (thickness 0.15)) (justify left bottom mirror))
    )
    (fp_rect (start -0.93 0.47) (end 0.93 -0.47) (layer "B.CrtYd") (width 0.05) (fill none))
    (fp_rect (start -0.5 0.25) (end 0.5 -0.25) (layer "B.Fab") (width 0.15) (fill none))
    (pad "1" smd roundrect (at -0.485 0 180) (size 0.59 0.64) (layers "B.Cu" "B.Paste" "B.Mask") (roundrect_rratio 0.25)
      (net 1 "GND") (pintype "passive"))
    (pad "2" smd roundrect (at 0.485 0 180) (size 0.59 0.64) (layers "B.Cu" "B.Paste" "B.Mask") (roundrect_rratio 0.25)
      (net 38 "Net-(R3-Pad2)") (pintype "passive"))
  )

  (footprint "sa800u-baseboard-hw-footprints:R_0402_1005Metric" (layer "B.Cu")
    (tedit 5FD9C158)
    (at 131 108.1 180)
    (descr "Resistor SMD 0402")
    (tags "resistor SMD 0402")
    (property "Author" "Antmicro")
    (property "License" "Apache-2.0")
    (property "MPN" "CR0402-FX-2001GLF")
    (property "Manufacturer" "Bourns")
    (property "Sheetfile" "hdmi-converter.kicad_sch")
    (property "Sheetname" "HDMI converter")
    (property "Tolerance" "1%")
    (property "Val" "2k")
    (attr smd)
    (fp_text reference "R34" (at 0.86 -0.39) (layer "B.SilkS")
      (effects (font (size 0.7 0.7) (thickness 0.15)) (justify left bottom mirror))
    )
    (fp_text value "R_2k_0402" (at 0 -1.4) (layer "B.Fab")
      (effects (font (size 0.7 0.7) (thickness 0.15)) (justify left bottom mirror))
    )
    (fp_text user "License: Apache-2.0" (at -0.95 -5.169) (layer "B.Fab") hide
      (effects (font (size 0.7 0.7) (thickness 0.15)) (justify left bottom mirror))
    )
    (fp_text user "Author: Antmicro" (at -0.95 -4.169) (layer "B.Fab") hide
      (effects (font (size 0.7 0.7) (thickness 0.15)) (justify left bottom mirror))
    )
    (fp_text user "${REFERENCE}" (at -0.95 -3.168) (layer "B.Fab") hide
      (effects (font (size 0.7 0.7) (thickness 0.15)) (justify left bottom mirror))
    )
    (fp_rect (start -0.93 0.47) (end 0.93 -0.47) (layer "B.CrtYd") (width 0.05) (fill none))
    (fp_rect (start -0.5 0.25) (end 0.5 -0.25) (layer "B.Fab") (width 0.15) (fill none))
    (pad "1" smd roundrect (at -0.485 0 180) (size 0.59 0.64) (layers "B.Cu" "B.Paste" "B.Mask") (roundrect_rratio 0.25)
      (net 40 "I2C4_SDA") (pintype "passive"))
    (pad "2" smd roundrect (at 0.485 0 180) (size 0.59 0.64) (layers "B.Cu" "B.Paste" "B.Mask") (roundrect_rratio 0.25)
      (net 132 "VREG_S4A_1V8") (pintype "passive"))
  )

  (footprint "sa800u-baseboard-hw-footprints:R_0402_1005Metric" (layer "B.Cu")
    (tedit 5FD9C158)
    (at 131 107.1 180)
    (descr "Resistor SMD 0402")
    (tags "resistor SMD 0402")
    (property "Author" "Antmicro")
    (property "License" "Apache-2.0")
    (property "MPN" "CR0402-FX-2001GLF")
    (property "Manufacturer" "Bourns")
    (property "Sheetfile" "hdmi-converter.kicad_sch")
    (property "Sheetname" "HDMI converter")
    (property "Tolerance" "1%")
    (property "Val" "2k")
    (attr smd)
    (fp_text reference "R36" (at 0.86 -0.39) (layer "B.SilkS")
      (effects (font (size 0.7 0.7) (thickness 0.15)) (justify left bottom mirror))
    )
    (fp_text value "R_2k_0402" (at 0 -1.4) (layer "B.Fab")
      (effects (font (size 0.7 0.7) (thickness 0.15)) (justify left bottom mirror))
    )
    (fp_text user "License: Apache-2.0" (at -0.95 -5.169) (layer "B.Fab") hide
      (effects (font (size 0.7 0.7) (thickness 0.15)) (justify left bottom mirror))
    )
    (fp_text user "Author: Antmicro" (at -0.95 -4.169) (layer "B.Fab") hide
      (effects (font (size 0.7 0.7) (thickness 0.15)) (justify left bottom mirror))
    )
    (fp_text user "${REFERENCE}" (at -0.95 -3.168) (layer "B.Fab") hide
      (effects (font (size 0.7 0.7) (thickness 0.15)) (justify left bottom mirror))
    )
    (fp_rect (start -0.93 0.47) (end 0.93 -0.47) (layer "B.CrtYd") (width 0.05) (fill none))
    (fp_rect (start -0.5 0.25) (end 0.5 -0.25) (layer "B.Fab") (width 0.15) (fill none))
    (pad "1" smd roundrect (at -0.485 0 180) (size 0.59 0.64) (layers "B.Cu" "B.Paste" "B.Mask") (roundrect_rratio 0.25)
      (net 41 "I2C4_SCL") (pintype "passive"))
    (pad "2" smd roundrect (at 0.485 0 180) (size 0.59 0.64) (layers "B.Cu" "B.Paste" "B.Mask") (roundrect_rratio 0.25)
      (net 132 "VREG_S4A_1V8") (pintype "passive"))
  )

  (footprint "sa800u-baseboard-hw-footprints:R_0402_1005Metric" (layer "B.Cu")
    (tedit 5FD9C158)
    (at 136.1 107.15)
    (descr "Resistor SMD 0402")
    (tags "resistor SMD 0402")
    (property "Author" "Antmicro")
    (property "License" "Apache-2.0")
    (property "MPN" "CR0402-FX-2001GLF")
    (property "Manufacturer" "Bourns")
    (property "Sheetfile" "hdmi-converter.kicad_sch")
    (property "Sheetname" "HDMI converter")
    (property "Tolerance" "1%")
    (property "Val" "2k")
    (attr smd)
    (fp_text reference "R44" (at 1.05 2.35 180) (layer "B.SilkS")
      (effects (font (size 0.7 0.7) (thickness 0.15)) (justify left bottom mirror))
    )
    (fp_text value "R_2k_0402" (at 0 -1.4 180) (layer "B.Fab")
      (effects (font (size 0.7 0.7) (thickness 0.15)) (justify left bottom mirror))
    )
    (fp_text user "Author: Antmicro" (at -0.95 -4.169 180) (layer "B.Fab") hide
      (effects (font (size 0.7 0.7) (thickness 0.15)) (justify left bottom mirror))
    )
    (fp_text user "License: Apache-2.0" (at -0.95 -5.169 180) (layer "B.Fab") hide
      (effects (font (size 0.7 0.7) (thickness 0.15)) (justify left bottom mirror))
    )
    (fp_text user "${REFERENCE}" (at -0.95 -3.168 180) (layer "B.Fab") hide
      (effects (font (size 0.7 0.7) (thickness 0.15)) (justify left bottom mirror))
    )
    (fp_rect (start -0.93 0.47) (end 0.93 -0.47) (layer "B.CrtYd") (width 0.05) (fill none))
    (fp_rect (start -0.5 0.25) (end 0.5 -0.25) (layer "B.Fab") (width 0.15) (fill none))
    (pad "1" smd roundrect (at -0.485 0) (size 0.59 0.64) (layers "B.Cu" "B.Paste" "B.Mask") (roundrect_rratio 0.25)
      (net 287 "/HDMI converter/LT9611_SCL") (pintype "passive"))
    (pad "2" smd roundrect (at 0.485 0) (size 0.59 0.64) (layers "B.Cu" "B.Paste" "B.Mask") (roundrect_rratio 0.25)
      (net 131 "3V3_SYS") (pintype "passive"))
  )

  (footprint "sa800u-baseboard-hw-footprints:R_0402_1005Metric" (layer "B.Cu")
    (tedit 5FD9C158)
    (at 136.1 108.15)
    (descr "Resistor SMD 0402")
    (tags "resistor SMD 0402")
    (property "Author" "Antmicro")
    (property "License" "Apache-2.0")
    (property "MPN" "CR0402-FX-2001GLF")
    (property "Manufacturer" "Bourns")
    (property "Sheetfile" "hdmi-converter.kicad_sch")
    (property "Sheetname" "HDMI converter")
    (property "Tolerance" "1%")
    (property "Val" "2k")
    (attr smd)
    (fp_text reference "R46" (at 1.05 2.35 180) (layer "B.SilkS")
      (effects (font (size 0.7 0.7) (thickness 0.15)) (justify left bottom mirror))
    )
    (fp_text value "R_2k_0402" (at 0 -1.4 180) (layer "B.Fab")
      (effects (font (size 0.7 0.7) (thickness 0.15)) (justify left bottom mirror))
    )
    (fp_text user "License: Apache-2.0" (at -0.95 -5.169 180) (layer "B.Fab") hide
      (effects (font (size 0.7 0.7) (thickness 0.15)) (justify left bottom mirror))
    )
    (fp_text user "Author: Antmicro" (at -0.95 -4.169 180) (layer "B.Fab") hide
      (effects (font (size 0.7 0.7) (thickness 0.15)) (justify left bottom mirror))
    )
    (fp_text user "${REFERENCE}" (at -0.95 -3.168 180) (layer "B.Fab") hide
      (effects (font (size 0.7 0.7) (thickness 0.15)) (justify left bottom mirror))
    )
    (fp_rect (start -0.93 0.47) (end 0.93 -0.47) (layer "B.CrtYd") (width 0.05) (fill none))
    (fp_rect (start -0.5 0.25) (end 0.5 -0.25) (layer "B.Fab") (width 0.15) (fill none))
    (pad "1" smd roundrect (at -0.485 0) (size 0.59 0.64) (layers "B.Cu" "B.Paste" "B.Mask") (roundrect_rratio 0.25)
      (net 288 "/HDMI converter/LT9611_SDA") (pintype "passive"))
    (pad "2" smd roundrect (at 0.485 0) (size 0.59 0.64) (layers "B.Cu" "B.Paste" "B.Mask") (roundrect_rratio 0.25)
      (net 131 "3V3_SYS") (pintype "passive"))
  )

  (footprint "sa800u-baseboard-hw-footprints:Spacer_SMD_M2.5_H6mm_Wurth_9774060151" (layer "B.Cu")
    (tedit 61168484)
    (at 151.5 85.5)
    (property "Author" "Antmicro")
    (property "License" "Apache-2.0")
    (property "MPN" "9774060151")
    (property "Manufacturer" "Würth Elektronik")
    (property "Sheetfile" "sa800u-baseboard-hw.kicad_sch")
    (property "Sheetname" "")
    (attr smd)
    (fp_text reference "SP1" (at -3.09 0.43 180) (layer "B.SilkS")
      (effects (font (size 0.7 0.7) (thickness 0.15)) (justify left bottom mirror))
    )
    (fp_text value "Spacer_H6mm_9774060151" (at -2.575 -4 180) (layer "B.Fab")
      (effects (font (size 0.7 0.7) (thickness 0.15)) (justify left bottom mirror))
    )
    (fp_text user "Author: Antmicro" (at -2.551 -6.5 180) (layer "B.Fab") hide
      (effects (font (size 0.7 0.7) (thickness 0.15)) (justify left bottom mirror))
    )
    (fp_text user "License: Apache-2.0" (at -2.551 -7.75 180) (layer "B.Fab") hide
      (effects (font (size 0.7 0.7) (thickness 0.15)) (justify left bottom mirror))
    )
    (fp_text user "${REFERENCE}" (at -2.551 -5.25 180) (layer "B.Fab") hide
      (effects (font (size 0.7 0.7) (thickness 0.15)) (justify left bottom mirror))
    )
    (fp_circle (center 0 0) (end 2.522481 0) (layer "B.Paste") (width 0.8) (fill none))
    (fp_circle (center -0.001 0) (end 2.548 0) (layer "B.Fab") (width 0.15) (fill none))
    (pad "1" smd circle (at 0 0) (size 6 6) (layers "B.Cu" "B.Mask")
      (net 392 "Net-(R1-Pad2)") (pintype "passive"))
    (pad "1" thru_hole circle (at -0.001 0) (size 4.1 4.1) (drill 3.7) (layers *.Cu *.Mask)
      (net 392 "Net-(R1-Pad2)") (pintype "passive"))
  )

  (footprint "sa800u-baseboard-hw-footprints:Spacer_SMD_M2.5_H6mm_Wurth_9774060151" (layer "B.Cu")
    (tedit 61168484)
    (at 151.5 148.5)
    (property "Author" "Antmicro")
    (property "License" "Apache-2.0")
    (property "MPN" "9774060151")
    (property "Manufacturer" "Würth Elektronik")
    (property "Sheetfile" "sa800u-baseboard-hw.kicad_sch")
    (property "Sheetname" "")
    (attr smd)
    (fp_text reference "SP2" (at 0.96 -3.11 180) (layer "B.SilkS")
      (effects (font (size 0.7 0.7) (thickness 0.15)) (justify left bottom mirror))
    )
    (fp_text value "Spacer_H6mm_9774060151" (at -2.575 -4 180) (layer "B.Fab")
      (effects (font (size 0.7 0.7) (thickness 0.15)) (justify left bottom mirror))
    )
    (fp_text user "${REFERENCE}" (at -2.551 -5.25 180) (layer "B.Fab") hide
      (effects (font (size 0.7 0.7) (thickness 0.15)) (justify left bottom mirror))
    )
    (fp_text user "Author: Antmicro" (at -2.551 -6.5 180) (layer "B.Fab") hide
      (effects (font (size 0.7 0.7) (thickness 0.15)) (justify left bottom mirror))
    )
    (fp_text user "License: Apache-2.0" (at -2.551 -7.75 180) (layer "B.Fab") hide
      (effects (font (size 0.7 0.7) (thickness 0.15)) (justify left bottom mirror))
    )
    (fp_circle (center 0 0) (end 2.522481 0) (layer "B.Paste") (width 0.8) (fill none))
    (fp_circle (center -0.001 0) (end 2.548 0) (layer "B.Fab") (width 0.15) (fill none))
    (pad "1" smd circle (at 0 0) (size 6 6) (layers "B.Cu" "B.Mask")
      (net 37 "Net-(R2-Pad2)") (pintype "passive"))
    (pad "1" thru_hole circle (at -0.001 0) (size 4.1 4.1) (drill 3.7) (layers *.Cu *.Mask)
      (net 37 "Net-(R2-Pad2)") (pintype "passive"))
  )

  (footprint "sa800u-baseboard-hw-footprints:Spacer_SMD_M2.5_H6mm_Wurth_9774060151" (layer "B.Cu")
    (tedit 61168484)
    (at 64.5 148.5)
    (property "Author" "Antmicro")
    (property "License" "Apache-2.0")
    (property "MPN" "9774060151")
    (property "Manufacturer" "Würth Elektronik")
    (property "Sheetfile" "sa800u-baseboard-hw.kicad_sch")
    (property "Sheetname" "")
    (attr smd)
    (fp_text reference "SP4" (at 0.95 -3.12 180) (layer "B.SilkS")
      (effects (font (size 0.7 0.7) (thickness 0.15)) (justify left bottom mirror))
    )
    (fp_text value "Spacer_H6mm_9774060151" (at -2.575 -4 180) (layer "B.Fab")
      (effects (font (size 0.7 0.7) (thickness 0.15)) (justify left bottom mirror))
    )
    (fp_text user "Author: Antmicro" (at -2.551 -6.5 180) (layer "B.Fab") hide
      (effects (font (size 0.7 0.7) (thickness 0.15)) (justify left bottom mirror))
    )
    (fp_text user "${REFERENCE}" (at -2.551 -5.25 180) (layer "B.Fab") hide
      (effects (font (size 0.7 0.7) (thickness 0.15)) (justify left bottom mirror))
    )
    (fp_text user "License: Apache-2.0" (at -2.551 -7.75 180) (layer "B.Fab") hide
      (effects (font (size 0.7 0.7) (thickness 0.15)) (justify left bottom mirror))
    )
    (fp_circle (center 0 0) (end 2.522481 0) (layer "B.Paste") (width 0.8) (fill none))
    (fp_circle (center -0.001 0) (end 2.548 0) (layer "B.Fab") (width 0.15) (fill none))
    (pad "1" smd circle (at 0 0) (size 6 6) (layers "B.Cu" "B.Mask")
      (net 39 "Net-(R4-Pad2)") (pintype "passive"))
    (pad "1" thru_hole circle (at -0.001 0) (size 4.1 4.1) (drill 3.7) (layers *.Cu *.Mask)
      (net 39 "Net-(R4-Pad2)") (pintype "passive"))
  )

  (footprint "sa800u-baseboard-hw-footprints:Spacer_SMD_M2.5_H6mm_Wurth_9774060151" (layer "B.Cu")
    (tedit 61168484)
    (at 64.5 85.5)
    (property "Author" "Antmicro")
    (property "License" "Apache-2.0")
    (property "MPN" "9774060151")
    (property "Manufacturer" "Würth Elektronik")
    (property "Sheetfile" "sa800u-baseboard-hw.kicad_sch")
    (property "Sheetname" "")
    (attr smd)
    (fp_text reference "SP3" (at 0.86 3.89 180) (layer "B.SilkS")
      (effects (font (size 0.7 0.7) (thickness 0.15)) (justify left bottom mirror))
    )
    (fp_text value "Spacer_H6mm_9774060151" (at -2.575 -4 180) (layer "B.Fab")
      (effects (font (size 0.7 0.7) (thickness 0.15)) (justify left bottom mirror))
    )
    (fp_text user "License: Apache-2.0" (at -2.551 -7.75 180) (layer "B.Fab") hide
      (effects (font (size 0.7 0.7) (thickness 0.15)) (justify left bottom mirror))
    )
    (fp_text user "Author: Antmicro" (at -2.551 -6.5 180) (layer "B.Fab") hide
      (effects (font (size 0.7 0.7) (thickness 0.15)) (justify left bottom mirror))
    )
    (fp_text user "${REFERENCE}" (at -2.551 -5.25 180) (layer "B.Fab") hide
      (effects (font (size 0.7 0.7) (thickness 0.15)) (justify left bottom mirror))
    )
    (fp_circle (center 0 0) (end 2.522481 0) (layer "B.Paste") (width 0.8) (fill none))
    (fp_circle (center -0.001 0) (end 2.548 0) (layer "B.Fab") (width 0.15) (fill none))
    (pad "1" smd circle (at 0 0) (size 6 6) (layers "B.Cu" "B.Mask")
      (net 38 "Net-(R3-Pad2)") (pintype "passive"))
    (pad "1" thru_hole circle (at -0.001 0) (size 4.1 4.1) (drill 3.7) (layers *.Cu *.Mask)
      (net 38 "Net-(R3-Pad2)") (pintype "passive"))
  )

  (footprint "sa800u-baseboard-hw-footprints:XSON-8_1x1.95mm_P0.5mm" (layer "B.Cu")
    (tedit 5DCD5522)
    (at 133.55 107.55 90)
    (property "Author" "Antmicro")
    (property "License" "Apache-2.0")
    (property "MPN" "NTS0102GT")
    (property "Manufacturer" "NXP")
    (property "Sheetfile" "hdmi-converter.kicad_sch")
    (property "Sheetname" "HDMI converter")
    (attr smd)
    (fp_text reference "U4" (at -1.65 0.95) (layer "B.SilkS")
      (effects (font (size 0.7 0.7) (thickness 0.15)) (justify left bottom mirror))
    )
    (fp_text value "NTS0102_XSON" (at 0 -2.2 270) (layer "B.Fab")
      (effects (font (size 0.7 0.7) (thickness 0.15)) (justify left bottom mirror))
    )
    (fp_text user "Author: Antmicro" (at -0.527 -7.105 270) (layer "B.Fab") hide
      (effects (font (size 0.7 0.7) (thickness 0.15)) (justify left bottom mirror))
    )
    (fp_text user "${REFERENCE}" (at -0.527 -5.905 270) (layer "B.Fab") hide
      (effects (font (size 0.7 0.7) (thickness 0.15)) (justify left bottom mirror))
    )
    (fp_text user "License: Apache-2.0" (at -0.527 -8.306 270) (layer "B.Fab") hide
      (effects (font (size 0.7 0.7) (thickness 0.15)) (justify left bottom mirror))
    )
    (fp_line (start -0.5 1.1) (end 0.5 1.1) (layer "B.SilkS") (width 0.15))
    (fp_line (start 0.5 -1.1) (end -0.5 -1.1) (layer "B.SilkS") (width 0.15))
    (fp_circle (center -0.7 0.95) (end -0.651 0.95) (layer "B.SilkS") (width 0.15) (fill none))
    (fp_rect (start -0.8 1.2) (end 0.8 -1.2) (layer "B.CrtYd") (width 0.05) (fill none))
    (fp_line (start -0.5305 -1) (end -0.5305 1.001) (layer "B.Fab") (width 0.15))
    (fp_line (start 0.5305 1.001) (end 0.5305 -1) (layer "B.Fab") (width 0.15))
    (fp_line (start 0.5305 -1) (end -0.5305 -1) (layer "B.Fab") (width 0.15))
    (fp_line (start -0.5305 1.001) (end 0.5305 1.001) (layer "B.Fab") (width 0.15))
    (pad "1" smd rect (at -0.33 0.75 90) (size 0.5 0.31) (layers "B.Cu" "B.Paste" "B.Mask")
      (net 288 "/HDMI converter/LT9611_SDA") (pinfunction "B_{2}") (pintype "bidirectional"))
    (pad "2" smd rect (at -0.33 0.25 90) (size 0.5 0.31) (layers "B.Cu" "B.Paste" "B.Mask")
      (net 1 "GND") (pinfunction "GND") (pintype "power_in"))
    (pad "3" smd rect (at -0.33 -0.25 90) (size 0.5 0.31) (layers "B.Cu" "B.Paste" "B.Mask")
      (net 132 "VREG_S4A_1V8") (pinfunction "VCC_{A}") (pintype "power_in"))
    (pad "4" smd rect (at -0.33 -0.75 90) (size 0.5 0.31) (layers "B.Cu" "B.Paste" "B.Mask")
      (net 40 "I2C4_SDA") (pinfunction "A_{2}") (pintype "bidirectional"))
    (pad "5" smd rect (at 0.33 -0.75 270) (size 0.5 0.31) (layers "B.Cu" "B.Paste" "B.Mask")
      (net 41 "I2C4_SCL") (pinfunction "A_{1}") (pintype "bidirectional"))
    (pad "6" smd rect (at 0.33 -0.25 270) (size 0.5 0.31) (layers "B.Cu" "B.Paste" "B.Mask")
      (net 132 "VREG_S4A_1V8") (pinfunction "OE") (pintype "input"))
    (pad "7" smd rect (at 0.33 0.25 270) (size 0.5 0.31) (layers "B.Cu" "B.Paste" "B.Mask")
      (net 131 "3V3_SYS") (pinfunction "VCC_{B}") (pintype "power_in"))
    (pad "8" smd rect (at 0.33 0.75 270) (size 0.5 0.31) (layers "B.Cu" "B.Paste" "B.Mask")
      (net 287 "/HDMI converter/LT9611_SCL") (pinfunction "B_{1}") (pintype "bidirectional"))
  )

  (footprint "sa800u-baseboard-hw-footprints:Mech_M2_2280_H4mm" locked (layer "B.Cu")
    (tedit 616E8740)
    (at 66.81 100.31 -90)
    (property "Author" "Antmicro")
    (property "DNP" "DNP")
    (property "License" "Apache-2.0")
    (property "MPN" "")
    (property "Manufacturer" "")
    (property "Sheetfile" "m2.kicad_sch")
    (property "Sheetname" "M2")
    (attr exclude_from_pos_files)
    (fp_text reference "M2" (at -4.31 0.73 180) (layer "B.SilkS")
      (effects (font (size 0.7 0.7) (thickness 0.15)) (justify right bottom mirror))
    )
    (fp_text value "Mech_M2_2280_H4mm" (at 0 -6.857 90) (layer "B.Fab")
      (effects (font (size 0.7 0.7) (thickness 0.15)) (justify right bottom mirror))
    )
    (fp_text user "DNP" (at 0 0 90) (layer "B.SilkS") hide
      (effects (font (size 1 1) (thickness 0.15)) (justify mirror))
    )
    (fp_text user "Author: Antmicro" (at -12.2428 -83.1912 90) (layer "B.Fab") hide
      (effects (font (size 0.7 0.7) (thickness 0.15)) (justify left bottom mirror))
    )
    (fp_text user "License: Apache-2.0" (at -12.2428 -84.3922 90) (layer "B.Fab") hide
      (effects (font (size 0.7 0.7) (thickness 0.15)) (justify left bottom mirror))
    )
    (fp_text user "${REFERENCE}" (at -12.2428 -81.9912 90) (layer "B.Fab") hide
      (effects (font (size 0.7 0.7) (thickness 0.15)) (justify left bottom mirror))
    )
    (fp_rect (start -10.922 -0.0508) (end 11.0236 -80.0608) (layer "B.Fab") (width 0.15) (fill none))
  )

  (footprint "sa800u-baseboard-hw-footprints:Vishay_PowerPAK_1212-8_Single" (layer "B.Cu")
    (tedit 61E93346)
    (at 82.35 141 90)
    (descr "PowerPAK 1212-8 Single")
    (tags "Vishay PowerPAK 1212-8 Single")
    (property "Author" "Antmicro")
    (property "License" "Apache-2.0")
    (property "MPN" "SQS401EN-T1_BE3")
    (property "Manufacturer" "Vishay")
    (property "Sheetfile" "usb-pd.kicad_sch")
    (property "Sheetname" "USB-PD")
    (attr smd)
    (fp_text reference "Q17" (at -2.93 0.83) (layer "B.SilkS")
      (effects (font (size 0.7 0.7) (thickness 0.15)) (justify left bottom mirror))
    )
    (fp_text value "SQS401EN-T1_BE3" (at -8 -2.7 270) (layer "B.Fab")
      (effects (font (size 0.7 0.7) (thickness 0.15)) (justify left bottom mirror))
    )
    (fp_text user "License: Apache-2.0" (at -8 -7.1 270) (layer "B.Fab") hide
      (effects (font (size 0.7 0.7) (thickness 0.15)) (justify left bottom mirror))
    )
    (fp_text user "${REFERENCE}" (at -8 -4.7 270) (layer "B.Fab") hide
      (effects (font (size 0.7 0.7) (thickness 0.15)) (justify left bottom mirror))
    )
    (fp_text user "Author: Antmicro" (at -8 -5.9 270) (layer "B.Fab") hide
      (effects (font (size 0.7 0.7) (thickness 0.15)) (justify left bottom mirror))
    )
    (fp_line (start -1.651 1.651) (end -1.651 1.317) (layer "B.SilkS") (width 0.15))
    (fp_line (start -1.635 -1.634) (end 1.634 -1.634) (layer "B.SilkS") (width 0.15))
    (fp_line (start 1.634 -1.3) (end 1.634 -1.634) (layer "B.SilkS") (width 0.15))
    (fp_line (start 1.648 1.651) (end 1.648 1.317) (layer "B.SilkS") (width 0.15))
    (fp_line (start -1.635 -1.3) (end -1.635 -1.634) (layer "B.SilkS") (width 0.15))
    (fp_line (start -1.651 1.651) (end 1.648 1.651) (layer "B.SilkS") (width 0.15))
    (fp_circle (center -1.9 1.4) (end -1.85 1.4) (layer "B.SilkS") (width 0.15) (fill solid))
    (fp_rect (start -2 1.8) (end 2 -1.798) (layer "B.CrtYd") (width 0.05) (fill none))
    (fp_line (start -1.6425 1.4175) (end -1.4175 1.6425) (layer "B.Fab") (width 0.15))
    (fp_rect (start -1.651 1.651) (end 1.648 -1.648) (layer "B.Fab") (width 0.15) (fill none))
    (pad "1" smd rect (at -1.436 0.99 90) (size 0.99 0.405) (layers "B.Cu" "B.Paste" "B.Mask")
      (net 107 "/USB-PD/PD_VBUS") (pinfunction "S") (pintype "bidirectional"))
    (pad "2" smd rect (at -1.436 0.332 90) (size 0.99 0.405) (layers "B.Cu" "B.Paste" "B.Mask")
      (net 107 "/USB-PD/PD_VBUS") (pinfunction "S") (pintype "bidirectional"))
    (pad "3" smd rect (at -1.436 -0.33 90) (size 0.99 0.405) (layers "B.Cu" "B.Paste" "B.Mask")
      (net 107 "/USB-PD/PD_VBUS") (pinfunction "S") (pintype "bidirectional"))
    (pad "4" smd rect (at -1.436 -0.988 90) (size 0.99 0.405) (layers "B.Cu" "B.Paste" "B.Mask")
      (net 391 "Net-(Q17-Pad4)") (pinfunction "G") (pintype "bidirectional"))
    (pad "5" smd custom (at 0.557 0 90) (size 1.725 2.235) (layers "B.Cu" "B.Paste" "B.Mask")
      (net 142 "PD_VDD") (pinfunction "D") (pintype "bidirectional") (zone_connect 2)
      (options (clearance outline) (anchor rect))
      (primitives
        (gr_poly (pts
            (xy 0.8625 -0.1275)
            (xy 0.8625 0.1275)
            (xy 1.3725 0.1275)
            (xy 1.3725 0.5325)
            (xy 0.8625 0.5325)
            (xy 0.8625 0.7875)
            (xy 1.3725 0.7875)
            (xy 1.3725 1.195)
            (xy 0.6125 1.195)
            (xy 0.6125 -1.195)
            (xy 1.3725 -1.195)
            (xy 1.3725 -0.7875)
            (xy 0.8625 -0.7875)
            (xy 0.8625 -0.5325)
            (xy 1.3725 -0.5325)
            (xy 1.3725 -0.1275)
          ) (width 0) (fill yes))
      ))
  )

  (footprint "sa800u-baseboard-hw-footprints:C_0603_1608Metric" (layer "B.Cu")
    (tedit 5D5E94D2)
    (at 84.9 141.2 90)
    (descr "Capacitor SMD 0603")
    (tags "capacitor 0603")
    (property "Author" "Antmicro")
    (property "Dielectric" "")
    (property "License" "Apache-2.0")
    (property "MPN" "C1608X5R1V475M080AC")
    (property "Manufacturer" "TDK")
    (property "Sheetfile" "usb-pd.kicad_sch")
    (property "Sheetname" "USB-PD")
    (property "Val" "4u7")
    (property "Voltage" "")
    (attr smd)
    (fp_text reference "C152" (at 1.45 1.38 270) (layer "B.SilkS")
      (effects (font (size 0.7 0.7) (thickness 0.15)) (justify left bottom mirror))
    )
    (fp_text value "C_4u7_0603" (at 0 -1.6 270) (layer "B.Fab")
      (effects (font (size 0.7 0.7) (thickness 0.15)) (justify left bottom mirror))
    )
    (fp_text user "License: Apache-2.0" (at -1.682 -5.895 270) (layer "B.Fab") hide
      (effects (font (size 0.7 0.7) (thickness 0.15)) (justify left bottom mirror))
    )
    (fp_text user "Author: Antmicro" (at -1.682 -4.894 270) (layer "B.Fab") hide
      (effects (font (size 0.7 0.7) (thickness 0.15)) (justify left bottom mirror))
    )
    (fp_text user "${REFERENCE}" (at -1.682 -3.895 270) (layer "B.Fab") hide
      (effects (font (size 0.7 0.7) (thickness 0.15)) (justify left bottom mirror))
    )
    (fp_line (start -0.3 0.3) (end 0.3 0.3) (layer "B.SilkS") (width 0.15))
    (fp_line (start -0.3 -0.3) (end 0.3 -0.3) (layer "B.SilkS") (width 0.15))
    (fp_rect (start -1.24 0.7) (end 1.24 -0.7) (layer "B.CrtYd") (width 0.05) (fill none))
    (fp_rect (start -0.8 0.4) (end 0.8 -0.4) (layer "B.Fab") (width 0.15) (fill none))
    (pad "1" smd roundrect (at -0.7 0 90) (size 0.6 0.8) (layers "B.Cu" "B.Paste" "B.Mask") (roundrect_rratio 0.2)
      (net 107 "/USB-PD/PD_VBUS") (pintype "passive"))
    (pad "2" smd roundrect (at 0.7 0 90) (size 0.6 0.8) (layers "B.Cu" "B.Paste" "B.Mask") (roundrect_rratio 0.2)
      (net 1 "GND") (pintype "passive"))
  )

  (footprint "sa800u-baseboard-hw-footprints:R_0402_1005Metric" (layer "B.Cu")
    (tedit 5FD9C158)
    (at 62.6 104.7 -90)
    (descr "Resistor SMD 0402")
    (tags "resistor SMD 0402")
    (property "Author" "Antmicro")
    (property "Current" "1A")
    (property "License" "Apache-2.0")
    (property "MPN" "ERJ2GE0R00X")
    (property "Manufacturer" "Panasonic")
    (property "Sheetfile" "poe.kicad_sch")
    (property "Sheetname" "PoE")
    (property "Tolerance" "")
    (property "Val" "0R")
    (attr smd)
    (fp_text reference "R145" (at -1.53 -1.34 90) (layer "B.SilkS")
      (effects (font (size 0.7 0.7) (thickness 0.15)) (justify left bottom mirror))
    )
    (fp_text value "R_0R_0402" (at 0 -1.4 90) (layer "B.Fab")
      (effects (font (size 0.7 0.7) (thickness 0.15)) (justify left bottom mirror))
    )
    (fp_text user "License: Apache-2.0" (at -0.95 -5.169 90) (layer "B.Fab") hide
      (effects (font (size 0.7 0.7) (thickness 0.15)) (justify left bottom mirror))
    )
    (fp_text user "${REFERENCE}" (at -0.95 -3.168 90) (layer "B.Fab") hide
      (effects (font (size 0.7 0.7) (thickness 0.15)) (justify left bottom mirror))
    )
    (fp_text user "Author: Antmicro" (at -0.95 -4.169 90) (layer "B.Fab") hide
      (effects (font (size 0.7 0.7) (thickness 0.15)) (justify left bottom mirror))
    )
    (fp_rect (start -0.93 0.47) (end 0.93 -0.47) (layer "B.CrtYd") (width 0.05) (fill none))
    (fp_rect (start -0.5 0.25) (end 0.5 -0.25) (layer "B.Fab") (width 0.15) (fill none))
    (pad "1" smd roundrect (at -0.485 0 270) (size 0.59 0.64) (layers "B.Cu" "B.Paste" "B.Mask") (roundrect_rratio 0.25)
      (net 7 "GNDD") (pintype "passive"))
    (pad "2" smd roundrect (at 0.485 0 270) (size 0.59 0.64) (layers "B.Cu" "B.Paste" "B.Mask") (roundrect_rratio 0.25)
      (net 174 "/PoE/APD") (pintype "passive"))
  )

  (footprint "sa800u-baseboard-hw-footprints:C_0402_1005Metric" (layer "B.Cu")
    (tedit 616D63CF)
    (at 140.345 106.6 180)
    (descr "Capacitor SMD 0402")
    (tags "capacitor SMD 0402")
    (property "Author" "Antmicro")
    (property "Dielectric" "")
    (property "License" "Apache-2.0")
    (property "MPN" "C1005X6S1A105K050BC")
    (property "Manufacturer" "TDK")
    (property "Sheetfile" "m2.kicad_sch")
    (property "Sheetname" "M2")
    (property "Val" "1u")
    (property "Voltage" "")
    (attr smd)
    (fp_text reference "C113" (at 0.765 -0.29) (layer "B.SilkS")
      (effects (font (size 0.7 0.7) (thickness 0.15)) (justify left bottom mirror))
    )
    (fp_text value "C_1u_0402" (at 0 -1.4) (layer "B.Fab")
      (effects (font (size 0.7 0.7) (thickness 0.15)) (justify left bottom mirror))
    )
    (fp_text user "Author: Antmicro" (at -0.932 -4.17) (layer "B.Fab") hide
      (effects (font (size 0.7 0.7) (thickness 0.15)) (justify left bottom mirror))
    )
    (fp_text user "${REFERENCE}" (at -0.932 -3.168) (layer "B.Fab") hide
      (effects (font (size 0.7 0.7) (thickness 0.15)) (justify left bottom mirror))
    )
    (fp_text user "License: Apache-2.0" (at -0.932 -5.17) (layer "B.Fab") hide
      (effects (font (size 0.7 0.7) (thickness 0.15)) (justify left bottom mirror))
    )
    (fp_rect (start -0.94 0.47) (end 0.94 -0.47) (layer "B.CrtYd") (width 0.05) (fill none))
    (fp_rect (start -0.499 0.249) (end 0.499 -0.249) (layer "B.Fab") (width 0.15) (fill none))
    (pad "1" smd roundrect (at -0.484 0 180) (size 0.59 0.64) (layers "B.Cu" "B.Paste" "B.Mask") (roundrect_rratio 0.25)
      (net 131 "3V3_SYS") (pintype "passive"))
    (pad "2" smd roundrect (at 0.484 0 180) (size 0.59 0.64) (layers "B.Cu" "B.Paste" "B.Mask") (roundrect_rratio 0.25)
      (net 1 "GND") (pintype "passive"))
  )

  (footprint "sa800u-baseboard-hw-footprints:R_0402_1005Metric" (layer "B.Cu")
    (tedit 5FD9C158)
    (at 140.215 98.85)
    (descr "Resistor SMD 0402")
    (tags "resistor SMD 0402")
    (property "Author" "Antmicro")
    (property "License" "Apache-2.0")
    (property "MPN" "CR0402-FX-1002GLF")
    (property "Manufacturer" "Bourns")
    (property "Sheetfile" "m2.kicad_sch")
    (property "Sheetname" "M2")
    (property "Tolerance" "1%")
    (property "Val" "10k")
    (attr smd)
    (fp_text reference "R93" (at 1.025 -0.62 180) (layer "B.SilkS")
      (effects (font (size 0.7 0.7) (thickness 0.15)) (justify left bottom mirror))
    )
    (fp_text value "R_10k_0402" (at 0 -1.4 180) (layer "B.Fab")
      (effects (font (size 0.7 0.7) (thickness 0.15)) (justify left bottom mirror))
    )
    (fp_text user "Author: Antmicro" (at -0.95 -4.169 180) (layer "B.Fab") hide
      (effects (font (size 0.7 0.7) (thickness 0.15)) (justify left bottom mirror))
    )
    (fp_text user "${REFERENCE}" (at -0.95 -3.168 180) (layer "B.Fab") hide
      (effects (font (size 0.7 0.7) (thickness 0.15)) (justify left bottom mirror))
    )
    (fp_text user "License: Apache-2.0" (at -0.95 -5.169 180) (layer "B.Fab") hide
      (effects (font (size 0.7 0.7) (thickness 0.15)) (justify left bottom mirror))
    )
    (fp_rect (start -0.93 0.47) (end 0.93 -0.47) (layer "B.CrtYd") (width 0.05) (fill none))
    (fp_rect (start -0.5 0.25) (end 0.5 -0.25) (layer "B.Fab") (width 0.15) (fill none))
    (pad "1" smd roundrect (at -0.485 0) (size 0.59 0.64) (layers "B.Cu" "B.Paste" "B.Mask") (roundrect_rratio 0.25)
      (net 131 "3V3_SYS") (pintype "passive"))
    (pad "2" smd roundrect (at 0.485 0) (size 0.59 0.64) (layers "B.Cu" "B.Paste" "B.Mask") (roundrect_rratio 0.25)
      (net 121 "M2_ALERT") (pintype "passive"))
  )

  (footprint "sa800u-baseboard-hw-footprints:R_0402_1005Metric" (layer "B.Cu")
    (tedit 5FD9C158)
    (at 140.7 94 -90)
    (descr "Resistor SMD 0402")
    (tags "resistor SMD 0402")
    (property "Author" "Antmicro")
    (property "License" "Apache-2.0")
    (property "MPN" "CR0402-FX-1002GLF")
    (property "Manufacturer" "Bourns")
    (property "Sheetfile" "m2.kicad_sch")
    (property "Sheetname" "M2")
    (property "Tolerance" "1%")
    (property "Val" "10k")
    (attr smd)
    (fp_text reference "R90" (at 0.9 -0.4 90) (layer "B.SilkS")
      (effects (font (size 0.7 0.7) (thickness 0.15)) (justify left bottom mirror))
    )
    (fp_text value "R_10k_0402" (at 0 -1.4 90) (layer "B.Fab")
      (effects (font (size 0.7 0.7) (thickness 0.15)) (justify left bottom mirror))
    )
    (fp_text user "${REFERENCE}" (at -0.95 -3.168 90) (layer "B.Fab") hide
      (effects (font (size 0.7 0.7) (thickness 0.15)) (justify left bottom mirror))
    )
    (fp_text user "Author: Antmicro" (at -0.95 -4.169 90) (layer "B.Fab") hide
      (effects (font (size 0.7 0.7) (thickness 0.15)) (justify left bottom mirror))
    )
    (fp_text user "License: Apache-2.0" (at -0.95 -5.169 90) (layer "B.Fab") hide
      (effects (font (size 0.7 0.7) (thickness 0.15)) (justify left bottom mirror))
    )
    (fp_rect (start -0.93 0.47) (end 0.93 -0.47) (layer "B.CrtYd") (width 0.05) (fill none))
    (fp_rect (start -0.5 0.25) (end 0.5 -0.25) (layer "B.Fab") (width 0.15) (fill none))
    (pad "1" smd roundrect (at -0.485 0 270) (size 0.59 0.64) (layers "B.Cu" "B.Paste" "B.Mask") (roundrect_rratio 0.25)
      (net 131 "3V3_SYS") (pintype "passive"))
    (pad "2" smd roundrect (at 0.485 0 270) (size 0.59 0.64) (layers "B.Cu" "B.Paste" "B.Mask") (roundrect_rratio 0.25)
      (net 120 "PCIE0_CLKREQ_N") (pintype "passive"))
  )

  (footprint "sa800u-baseboard-hw-footprints:R_0402_1005Metric" (layer "B.Cu")
    (tedit 5FD9C158)
    (at 139.74 94 -90)
    (descr "Resistor SMD 0402")
    (tags "resistor SMD 0402")
    (property "Author" "Antmicro")
    (property "License" "Apache-2.0")
    (property "MPN" "CR0402-FX-1002GLF")
    (property "Manufacturer" "Bourns")
    (property "Sheetfile" "m2.kicad_sch")
    (property "Sheetname" "M2")
    (property "Tolerance" "1%")
    (property "Val" "10k")
    (attr smd)
    (fp_text reference "R91" (at 0.9 -0.4 90) (layer "B.SilkS")
      (effects (font (size 0.7 0.7) (thickness 0.15)) (justify left bottom mirror))
    )
    (fp_text value "R_10k_0402" (at 0 -1.4 90) (layer "B.Fab")
      (effects (font (size 0.7 0.7) (thickness 0.15)) (justify left bottom mirror))
    )
    (fp_text user "Author: Antmicro" (at -0.95 -4.169 90) (layer "B.Fab") hide
      (effects (font (size 0.7 0.7) (thickness 0.15)) (justify left bottom mirror))
    )
    (fp_text user "License: Apache-2.0" (at -0.95 -5.169 90) (layer "B.Fab") hide
      (effects (font (size 0.7 0.7) (thickness 0.15)) (justify left bottom mirror))
    )
    (fp_text user "${REFERENCE}" (at -0.95 -3.168 90) (layer "B.Fab") hide
      (effects (font (size 0.7 0.7) (thickness 0.15)) (justify left bottom mirror))
    )
    (fp_rect (start -0.93 0.47) (end 0.93 -0.47) (layer "B.CrtYd") (width 0.05) (fill none))
    (fp_rect (start -0.5 0.25) (end 0.5 -0.25) (layer "B.Fab") (width 0.15) (fill none))
    (pad "1" smd roundrect (at -0.485 0 270) (size 0.59 0.64) (layers "B.Cu" "B.Paste" "B.Mask") (roundrect_rratio 0.25)
      (net 131 "3V3_SYS") (pintype "passive"))
    (pad "2" smd roundrect (at 0.485 0 270) (size 0.59 0.64) (layers "B.Cu" "B.Paste" "B.Mask") (roundrect_rratio 0.25)
      (net 124 "PCIE0_RST_N") (pintype "passive"))
  )

  (footprint "sa800u-baseboard-hw-footprints:C_0402_1005Metric" (layer "B.Cu")
    (tedit 616D63CF)
    (at 137.75 134.95 90)
    (descr "Capacitor SMD 0402")
    (tags "capacitor SMD 0402")
    (property "Author" "Antmicro")
    (property "DNP" "DNP")
    (property "Dielectric" "C0G")
    (property "License" "Apache-2.0")
    (property "MPN" "GCM1555C1H100GA16D")
    (property "Manufacturer" "Murata")
    (property "Sheetfile" "hdmi-converter.kicad_sch")
    (property "Sheetname" "HDMI converter")
    (property "Val" "10p")
    (property "Voltage" "50V")
    (attr exclude_from_pos_files)
    (fp_text reference "C56" (at -0.85 0.37 270) (layer "B.SilkS")
      (effects (font (size 0.7 0.7) (thickness 0.15)) (justify left bottom mirror))
    )
    (fp_text value "C_10p_0402" (at 0 -1.4 270) (layer "B.Fab")
      (effects (font (size 0.7 0.7) (thickness 0.15)) (justify left bottom mirror))
    )
    (fp_text user "License: Apache-2.0" (at -0.932 -5.17 270) (layer "B.Fab") hide
      (effects (font (size 0.7 0.7) (thickness 0.15)) (justify left bottom mirror))
    )
    (fp_text user "Author: Antmicro" (at -0.932 -4.17 270) (layer "B.Fab") hide
      (effects (font (size 0.7 0.7) (thickness 0.15)) (justify left bottom mirror))
    )
    (fp_text user "${REFERENCE}" (at -0.932 -3.168 270) (layer "B.Fab") hide
      (effects (font (size 0.7 0.7) (thickness 0.15)) (justify left bottom mirror))
    )
    (fp_rect (start -0.94 0.47) (end 0.94 -0.47) (layer "B.CrtYd") (width 0.05) (fill none))
    (fp_rect (start -0.499 0.249) (end 0.499 -0.249) (layer "B.Fab") (width 0.15) (fill none))
    (pad "1" smd roundrect (at -0.484 0 90) (size 0.59 0.64) (layers "B.Cu" "B.Paste" "B.Mask") (roundrect_rratio 0.25)
      (net 206 "/HDMI converter/HDMI_CLK_P") (pintype "passive"))
    (pad "2" smd roundrect (at 0.484 0 90) (size 0.59 0.64) (layers "B.Cu" "B.Paste" "B.Mask") (roundrect_rratio 0.25)
      (net 1 "GND") (pintype "passive"))
  )

  (footprint "sa800u-baseboard-hw-footprints:R_0402_1005Metric" (layer "B.Cu")
    (tedit 5FD9C158)
    (at 121.8 115.9 -90)
    (descr "Resistor SMD 0402")
    (tags "resistor SMD 0402")
    (property "Author" "Antmicro")
    (property "License" "Apache-2.0")
    (property "MPN" "CR0402-FX-1002GLF")
    (property "Manufacturer" "Bourns")
    (property "Sheetfile" "hdmi-converter.kicad_sch")
    (property "Sheetname" "HDMI converter")
    (property "Tolerance" "1%")
    (property "Val" "10k")
    (attr smd)
    (fp_text reference "R17" (at -1.22 -2.38 90) (layer "B.SilkS")
      (effects (font (size 0.7 0.7) (thickness 0.15)) (justify left bottom mirror))
    )
    (fp_text value "R_10k_0402" (at 0 -1.4 90) (layer "B.Fab")
      (effects (font (size 0.7 0.7) (thickness 0.15)) (justify left bottom mirror))
    )
    (fp_text user "License: Apache-2.0" (at -0.95 -5.169 90) (layer "B.Fab") hide
      (effects (font (size 0.7 0.7) (thickness 0.15)) (justify left bottom mirror))
    )
    (fp_text user "Author: Antmicro" (at -0.95 -4.169 90) (layer "B.Fab") hide
      (effects (font (size 0.7 0.7) (thickness 0.15)) (justify left bottom mirror))
    )
    (fp_text user "${REFERENCE}" (at -0.95 -3.168 90) (layer "B.Fab") hide
      (effects (font (size 0.7 0.7) (thickness 0.15)) (justify left bottom mirror))
    )
    (fp_rect (start -0.93 0.47) (end 0.93 -0.47) (layer "B.CrtYd") (width 0.05) (fill none))
    (fp_rect (start -0.5 0.25) (end 0.5 -0.25) (layer "B.Fab") (width 0.15) (fill none))
    (pad "1" smd roundrect (at -0.485 0 270) (size 0.59 0.64) (layers "B.Cu" "B.Paste" "B.Mask") (roundrect_rratio 0.25)
      (net 131 "3V3_SYS") (pintype "passive"))
    (pad "2" smd roundrect (at 0.485 0 270) (size 0.59 0.64) (layers "B.Cu" "B.Paste" "B.Mask") (roundrect_rratio 0.25)
      (net 186 "/HDMI converter/LT9611_RST_N") (pintype "passive"))
  )

  (footprint "sa800u-baseboard-hw-footprints:R_0603_1608Metric" (layer "B.Cu")
    (tedit 5D5D3E92)
    (at 68.6 121.875 90)
    (descr "Resistor SMD 0603")
    (tags "resistor SMD 0603")
    (property "Author" "Antmicro")
    (property "License" "Apache-2.0")
    (property "MPN" "CR0603-FX-2002ELF")
    (property "Manufacturer" "Bourns")
    (property "Sheetfile" "poe.kicad_sch")
    (property "Sheetname" "PoE")
    (property "Tolerance" "1%")
    (property "Val" "20k")
    (attr smd)
    (fp_text reference "R149" (at 1.395 -0.52 270) (layer "B.SilkS")
      (effects (font (size 0.7 0.7) (thickness 0.15)) (justify left bottom mirror))
    )
    (fp_text value "R_20k_0603" (at 0 -1.6 270) (layer "B.Fab")
      (effects (font (size 0.7 0.7) (thickness 0.15)) (justify left bottom mirror))
    )
    (fp_text user "${REFERENCE}" (at -1.25 -3.898 270) (layer "B.Fab") hide
      (effects (font (size 0.7 0.7) (thickness 0.15)) (justify left bottom mirror))
    )
    (fp_text user "Author: Antmicro" (at -1.25 -4.9 270) (layer "B.Fab") hide
      (effects (font (size 0.7 0.7) (thickness 0.15)) (justify left bottom mirror))
    )
    (fp_text user "License: Apache-2.0" (at -1.25 -5.9 270) (layer "B.Fab") hide
      (effects (font (size 0.7 0.7) (thickness 0.15)) (justify left bottom mirror))
    )
    (fp_line (start -0.3 -0.3) (end 0.3 -0.3) (layer "B.SilkS") (width 0.15))
    (fp_line (start -0.3 0.3) (end 0.3 0.3) (layer "B.SilkS") (width 0.15))
    (fp_rect (start -1.25 0.7) (end 1.25 -0.7) (layer "B.CrtYd") (width 0.05) (fill none))
    (fp_rect (start -0.8 0.4) (end 0.8 -0.4) (layer "B.Fab") (width 0.15) (fill none))
    (pad "1" smd roundrect (at -0.7 0 90) (size 0.6 0.8) (layers "B.Cu" "B.Paste" "B.Mask") (roundrect_rratio 0.2)
      (net 73 "/PoE/VDD_POE") (pintype "passive"))
    (pad "2" smd roundrect (at 0.7 0 90) (size 0.6 0.8) (layers "B.Cu" "B.Paste" "B.Mask") (roundrect_rratio 0.2)
      (net 380 "Net-(D32-Pad1)") (pintype "passive"))
  )

  (footprint "sa800u-baseboard-hw-footprints:R_0402_1005Metric" (layer "B.Cu")
    (tedit 5FD9C158)
    (at 121.85 121.9)
    (descr "Resistor SMD 0402")
    (tags "resistor SMD 0402")
    (property "Author" "Antmicro")
    (property "License" "Apache-2.0")
    (property "MPN" "CR0402-FX-1002GLF")
    (property "Manufacturer" "Bourns")
    (property "Sheetfile" "psu.kicad_sch")
    (property "Sheetname" "PSU")
    (property "Tolerance" "1%")
    (property "Val" "10k")
    (attr smd)
    (fp_text reference "R128" (at -0.84 0.37 180) (layer "B.SilkS")
      (effects (font (size 0.7 0.7) (thickness 0.15)) (justify left bottom mirror))
    )
    (fp_text value "R_10k_0402" (at 0 -1.4 180) (layer "B.Fab")
      (effects (font (size 0.7 0.7) (thickness 0.15)) (justify left bottom mirror))
    )
    (fp_text user "License: Apache-2.0" (at -0.95 -5.169 180) (layer "B.Fab") hide
      (effects (font (size 0.7 0.7) (thickness 0.15)) (justify left bottom mirror))
    )
    (fp_text user "Author: Antmicro" (at -0.95 -4.169 180) (layer "B.Fab") hide
      (effects (font (size 0.7 0.7) (thickness 0.15)) (justify left bottom mirror))
    )
    (fp_text user "${REFERENCE}" (at -0.95 -3.168 180) (layer "B.Fab") hide
      (effects (font (size 0.7 0.7) (thickness 0.15)) (justify left bottom mirror))
    )
    (fp_rect (start -0.93 0.47) (end 0.93 -0.47) (layer "B.CrtYd") (width 0.05) (fill none))
    (fp_rect (start -0.5 0.25) (end 0.5 -0.25) (layer "B.Fab") (width 0.15) (fill none))
    (pad "1" smd roundrect (at -0.485 0) (size 0.59 0.64) (layers "B.Cu" "B.Paste" "B.Mask") (roundrect_rratio 0.25)
      (net 320 "1V2_SYS_EN") (pintype "passive"))
    (pad "2" smd roundrect (at 0.485 0) (size 0.59 0.64) (layers "B.Cu" "B.Paste" "B.Mask") (roundrect_rratio 0.25)
      (net 408 "Net-(R128-Pad2)") (pintype "passive"))
  )

  (footprint "sa800u-baseboard-hw-footprints:R_0402_1005Metric" (layer "B.Cu")
    (tedit 5FD9C158)
    (at 123.8 124.35 180)
    (descr "Resistor SMD 0402")
    (tags "resistor SMD 0402")
    (property "Author" "Antmicro")
    (property "DNP" "DNP")
    (property "License" "Apache-2.0")
    (property "MPN" "CR0402-FX-1002GLF")
    (property "Manufacturer" "Bourns")
    (property "Sheetfile" "psu.kicad_sch")
    (property "Sheetname" "PSU")
    (property "Tolerance" "1%")
    (property "Val" "10k")
    (attr exclude_from_pos_files)
    (fp_text reference "R133" (at -1.14 -1.28) (layer "B.SilkS")
      (effects (font (size 0.7 0.7) (thickness 0.15)) (justify left bottom mirror))
    )
    (fp_text value "R_10k_0402" (at 0 -1.4) (layer "B.Fab")
      (effects (font (size 0.7 0.7) (thickness 0.15)) (justify left bottom mirror))
    )
    (fp_text user "License: Apache-2.0" (at -0.95 -5.169) (layer "B.Fab") hide
      (effects (font (size 0.7 0.7) (thickness 0.15)) (justify left bottom mirror))
    )
    (fp_text user "${REFERENCE}" (at -0.95 -3.168) (layer "B.Fab") hide
      (effects (font (size 0.7 0.7) (thickness 0.15)) (justify left bottom mirror))
    )
    (fp_text user "Author: Antmicro" (at -0.95 -4.169) (layer "B.Fab") hide
      (effects (font (size 0.7 0.7) (thickness 0.15)) (justify left bottom mirror))
    )
    (fp_rect (start -0.93 0.47) (end 0.93 -0.47) (layer "B.CrtYd") (width 0.05) (fill none))
    (fp_rect (start -0.5 0.25) (end 0.5 -0.25) (layer "B.Fab") (width 0.15) (fill none))
    (pad "1" smd roundrect (at -0.485 0 180) (size 0.59 0.64) (layers "B.Cu" "B.Paste" "B.Mask") (roundrect_rratio 0.25)
      (net 133 "5V_SYS") (pintype "passive"))
    (pad "2" smd roundrect (at 0.485 0 180) (size 0.59 0.64) (layers "B.Cu" "B.Paste" "B.Mask") (roundrect_rratio 0.25)
      (net 408 "Net-(R128-Pad2)") (pintype "passive"))
  )

  (footprint "sa800u-baseboard-hw-footprints:L_Coilcraft_XEL4030" (layer "B.Cu")
    (tedit 6215D867)
    (at 129.026 121.88)
    (property "Author" "Antmicro")
    (property "IMax" "")
    (property "ISat" "")
    (property "License" "Apache-2.0")
    (property "MPN" "XEL4030-222MEC")
    (property "Manufacturer" "Coilcraft")
    (property "MaxCur" "6.1A")
    (property "Sheetfile" "psu.kicad_sch")
    (property "Sheetname" "PSU")
    (property "Size" "4x4")
    (property "Val" "2u2/6.1A")
    (attr smd)
    (fp_text reference "L28" (at 0.935 -2.52 180) (layer "B.SilkS")
      (effects (font (size 0.7 0.7) (thickness 0.15)) (justify left bottom mirror))
    )
    (fp_text value "L_2u2_6.1A_XEL4030" (at 0 -3.35 180) (layer "B.Fab")
      (effects (font (size 0.7 0.7) (thickness 0.15)) (justify left bottom mirror))
    )
    (fp_text user "Author: Antmicro" (at -2.15 -5.996 180) (layer "B.Fab") hide
      (effects (font (size 0.7 0.7) (thickness 0.15)) (justify left bottom mirror))
    )
    (fp_text user "License: Apache-2.0" (at -2.15 -6.996 180) (layer "B.Fab") hide
      (effects (font (size 0.7 0.7) (thickness 0.15)) (justify left bottom mirror))
    )
    (fp_text user "${REFERENCE}" (at -2.15 -4.996 180) (layer "B.Fab") hide
      (effects (font (size 0.7 0.7) (thickness 0.15)) (justify left bottom mirror))
    )
    (fp_line (start -1.8 -2.2) (end 1.85 -2.199) (layer "B.SilkS") (width 0.15))
    (fp_line (start -1.8 2.2) (end 1.85 2.201) (layer "B.SilkS") (width 0.15))
    (fp_rect (start -2.45 2.45) (end 2.45 -2.45) (layer "B.CrtYd") (width 0.05) (fill none))
    (fp_line (start 1.999 2) (end 1.999 -1.999) (layer "B.Fab") (width 0.15))
    (fp_line (start -2 -1.999) (end -2 2) (layer "B.Fab") (width 0.15))
    (fp_line (start -2 2) (end 1.999 2) (layer "B.Fab") (width 0.15))
    (fp_line (start 1.999 -1.999) (end -2 -1.999) (layer "B.Fab") (width 0.15))
    (pad "1" smd rect (at -1.186 0) (size 0.98 3.4) (layers "B.Cu" "B.Paste" "B.Mask")
      (net 360 "Net-(C134-Pad2)") (pintype "passive"))
    (pad "2" smd rect (at 1.185 0) (size 0.98 3.4) (layers "B.Cu" "B.Paste" "B.Mask")
      (net 138 "1V2_SYS") (pintype "passive"))
  )

  (footprint "sa800u-baseboard-hw-footprints:AP62301WU-7-TSOT23-6" (layer "B.Cu")
    (tedit 6215EA50)
    (at 124.85 121.95 -90)
    (property "Author" "Antmicro")
    (property "License" "Apache-2.0")
    (property "MPN" "AP62301WU-7")
    (property "Manufacturer" "Diodes Incorporated")
    (property "Sheetfile" "psu.kicad_sch")
    (property "Sheetname" "PSU")
    (attr smd)
    (fp_text reference "U21" (at -1.79 -1.1 180) (layer "B.SilkS")
      (effects (font (size 0.7 0.7) (thickness 0.15)) (justify left bottom mirror))
    )
    (fp_text value "AP62301WU-7" (at -0.005 -2.6 90) (layer "B.Fab")
      (effects (font (size 0.7 0.7) (thickness 0.15)) (justify left bottom mirror))
    )
    (fp_text user "License: Apache-2.0" (at -1.893 -4.967 90) (layer "B.Fab") hide
      (effects (font (size 0.7 0.7) (thickness 0.15)) (justify left bottom mirror))
    )
    (fp_text user "Author: Antmicro" (at -1.893 -7.368 90) (layer "B.Fab") hide
      (effects (font (size 0.7 0.7) (thickness 0.15)) (justify left bottom mirror))
    )
    (fp_text user "${REFERENCE}" (at -1.893 -6.168 90) (layer "B.Fab") hide
      (effects (font (size 0.7 0.7) (thickness 0.15)) (justify left bottom mirror))
    )
    (fp_line (start -1.4805 -0.725) (end -1.4795 0.725) (layer "B.SilkS") (width 0.15))
    (fp_line (start -1.4805 -0.725) (end -1.3905 -0.725) (layer "B.SilkS") (width 0.15))
    (fp_line (start 1.48 0.72) (end 1.479 -0.73) (layer "B.SilkS") (width 0.15))
    (fp_line (start -1.4795 0.725) (end -1.3905 0.725) (layer "B.SilkS") (width 0.15))
    (fp_line (start 1.48 0.72) (end 1.38 0.72) (layer "B.SilkS") (width 0.15))
    (fp_line (start 1.479 -0.73) (end 1.38 -0.73) (layer "B.SilkS") (width 0.15))
    (fp_circle (center -1.499 -1.236) (end -1.45 -1.236) (layer "B.SilkS") (width 0.15) (fill solid))
    (fp_rect (start -1.65 1.61) (end 1.65 -1.61) (layer "B.CrtYd") (width 0.05) (fill none))
    (fp_line (start 1.523 0.833) (end 1.523 -0.916) (layer "B.Fab") (width 0.15))
    (fp_line (start -1.527 -0.491) (end -1.527 0.833) (layer "B.Fab") (width 0.15))
    (fp_line (start -1.527 -0.491) (end -1.102 -0.916) (layer "B.Fab") (width 0.15))
    (fp_line (start -1.102 -0.916) (end 1.523 -0.916) (layer "B.Fab") (width 0.15))
    (fp_line (start -1.527 0.833) (end 1.523 0.833) (layer "B.Fab") (width 0.15))
    (pad "1" smd rect (at -0.952 -1.18 270) (size 0.7 0.8) (layers "B.Cu" "B.Paste" "B.Mask")
      (net 1 "GND") (pinfunction "GND") (pintype "power_in"))
    (pad "2" smd rect (at -0.001 -1.18 270) (size 0.7 0.8) (layers "B.Cu" "B.Paste" "B.Mask")
      (net 360 "Net-(C134-Pad2)") (pinfunction "SW") (pintype "power_out"))
    (pad "3" smd rect (at 0.947 -1.18 270) (size 0.7 0.8) (layers "B.Cu" "B.Paste" "B.Mask")
      (net 133 "5V_SYS") (pinfunction "VIN") (pintype "power_in"))
    (pad "4" smd rect (at 0.947 1.18 270) (size 0.7 0.8) (layers "B.Cu" "B.Paste" "B.Mask")
      (net 172 "Net-(R139-Pad2)") (pinfunction "FB") (pintype "input"))
    (pad "5" smd rect (at -0.001 1.18 270) (size 0.7 0.8) (layers "B.Cu" "B.Paste" "B.Mask")
      (net 408 "Net-(R128-Pad2)") (pinfunction "EN") (pintype "input"))
    (pad "6" smd rect (at -0.952 1.18 270) (size 0.7 0.8) (layers "B.Cu" "B.Paste" "B.Mask")
      (net 361 "Net-(C134-Pad1)") (pinfunction "BST") (pintype "output"))
  )

  (footprint "sa800u-baseboard-hw-footprints:C_0402_1005Metric" (layer "B.Cu")
    (tedit 616D63CF)
    (at 121.85 120.9 180)
    (descr "Capacitor SMD 0402")
    (tags "capacitor SMD 0402")
    (property "Author" "Antmicro")
    (property "Dielectric" "X5R")
    (property "License" "Apache-2.0")
    (property "MPN" "GRM155R61H104KE14D")
    (property "Manufacturer" "Murata")
    (property "Sheetfile" "psu.kicad_sch")
    (property "Sheetname" "PSU")
    (property "Val" "100n")
    (property "Voltage" "50V")
    (attr smd)
    (fp_text reference "C134" (at 0.83 -0.32) (layer "B.SilkS")
      (effects (font (size 0.7 0.7) (thickness 0.15)) (justify left bottom mirror))
    )
    (fp_text value "C_100n_0402" (at 0 -1.4) (layer "B.Fab")
      (effects (font (size 0.7 0.7) (thickness 0.15)) (justify left bottom mirror))
    )
    (fp_text user "Author: Antmicro" (at -0.932 -4.17) (layer "B.Fab") hide
      (effects (font (size 0.7 0.7) (thickness 0.15)) (justify left bottom mirror))
    )
    (fp_text user "License: Apache-2.0" (at -0.932 -5.17) (layer "B.Fab") hide
      (effects (font (size 0.7 0.7) (thickness 0.15)) (justify left bottom mirror))
    )
    (fp_text user "${REFERENCE}" (at -0.932 -3.168) (layer "B.Fab") hide
      (effects (font (size 0.7 0.7) (thickness 0.15)) (justify left bottom mirror))
    )
    (fp_rect (start -0.94 0.47) (end 0.94 -0.47) (layer "B.CrtYd") (width 0.05) (fill none))
    (fp_rect (start -0.499 0.249) (end 0.499 -0.249) (layer "B.Fab") (width 0.15) (fill none))
    (pad "1" smd roundrect (at -0.484 0 180) (size 0.59 0.64) (layers "B.Cu" "B.Paste" "B.Mask") (roundrect_rratio 0.25)
      (net 361 "Net-(C134-Pad1)") (pintype "passive"))
    (pad "2" smd roundrect (at 0.484 0 180) (size 0.59 0.64) (layers "B.Cu" "B.Paste" "B.Mask") (roundrect_rratio 0.25)
      (net 360 "Net-(C134-Pad2)") (pintype "passive"))
  )

  (footprint "sa800u-baseboard-hw-footprints:R_0402_1005Metric" (layer "B.Cu")
    (tedit 5FD9C158)
    (at 121.85 124.05)
    (descr "Resistor SMD 0402")
    (tags "resistor SMD 0402")
    (property "Author" "Antmicro")
    (property "License" "Apache-2.0")
    (property "MPN" "CR0402-FX-1002GLF")
    (property "Manufacturer" "Bourns")
    (property "Sheetfile" "psu.kicad_sch")
    (property "Sheetname" "PSU")
    (property "Tolerance" "1%")
    (property "Val" "10k")
    (attr smd)
    (fp_text reference "R139" (at -0.84 0.37 180) (layer "B.SilkS")
      (effects (font (size 0.7 0.7) (thickness 0.15)) (justify left bottom mirror))
    )
    (fp_text value "R_10k_0402" (at 0 -1.4 180) (layer "B.Fab")
      (effects (font (size 0.7 0.7) (thickness 0.15)) (justify left bottom mirror))
    )
    (fp_text user "License: Apache-2.0" (at -0.95 -5.169 180) (layer "B.Fab") hide
      (effects (font (size 0.7 0.7) (thickness 0.15)) (justify left bottom mirror))
    )
    (fp_text user "${REFERENCE}" (at -0.95 -3.168 180) (layer "B.Fab") hide
      (effects (font (size 0.7 0.7) (thickness 0.15)) (justify left bottom mirror))
    )
    (fp_text user "Author: Antmicro" (at -0.95 -4.169 180) (layer "B.Fab") hide
      (effects (font (size 0.7 0.7) (thickness 0.15)) (justify left bottom mirror))
    )
    (fp_rect (start -0.93 0.47) (end 0.93 -0.47) (layer "B.CrtYd") (width 0.05) (fill none))
    (fp_rect (start -0.5 0.25) (end 0.5 -0.25) (layer "B.Fab") (width 0.15) (fill none))
    (pad "1" smd roundrect (at -0.485 0) (size 0.59 0.64) (layers "B.Cu" "B.Paste" "B.Mask") (roundrect_rratio 0.25)
      (net 138 "1V2_SYS") (pintype "passive"))
    (pad "2" smd roundrect (at 0.485 0) (size 0.59 0.64) (layers "B.Cu" "B.Paste" "B.Mask") (roundrect_rratio 0.25)
      (net 172 "Net-(R139-Pad2)") (pintype "passive"))
  )

  (footprint "sa800u-baseboard-hw-footprints:C_0603_1608Metric" (layer "B.Cu")
    (tedit 5D5E94D2)
    (at 126.85 125.04)
    (descr "Capacitor SMD 0603")
    (tags "capacitor 0603")
    (property "Author" "Antmicro")
    (property "Dielectric" "")
    (property "License" "Apache-2.0")
    (property "MPN" "GRM188R60J226MEA0D")
    (property "Manufacturer" "Murata")
    (property "Sheetfile" "psu.kicad_sch")
    (property "Sheetname" "PSU")
    (property "Val" "22u")
    (property "Voltage" "")
    (attr smd)
    (fp_text reference "C130" (at 1.33 1.61 180) (layer "B.SilkS")
      (effects (font (size 0.7 0.7) (thickness 0.15)) (justify left bottom mirror))
    )
    (fp_text value "C_22u_0603" (at 0 -1.6 180) (layer "B.Fab")
      (effects (font (size 0.7 0.7) (thickness 0.15)) (justify left bottom mirror))
    )
    (fp_text user "${REFERENCE}" (at -1.682 -3.895 180) (layer "B.Fab") hide
      (effects (font (size 0.7 0.7) (thickness 0.15)) (justify left bottom mirror))
    )
    (fp_text user "License: Apache-2.0" (at -1.682 -5.895 180) (layer "B.Fab") hide
      (effects (font (size 0.7 0.7) (thickness 0.15)) (justify left bottom mirror))
    )
    (fp_text user "Author: Antmicro" (at -1.682 -4.894 180) (layer "B.Fab") hide
      (effects (font (size 0.7 0.7) (thickness 0.15)) (justify left bottom mirror))
    )
    (fp_line (start -0.3 0.3) (end 0.3 0.3) (layer "B.SilkS") (width 0.15))
    (fp_line (start -0.3 -0.3) (end 0.3 -0.3) (layer "B.SilkS") (width 0.15))
    (fp_rect (start -1.24 0.7) (end 1.24 -0.7) (layer "B.CrtYd") (width 0.05) (fill none))
    (fp_rect (start -0.8 0.4) (end 0.8 -0.4) (layer "B.Fab") (width 0.15) (fill none))
    (pad "1" smd roundrect (at -0.7 0) (size 0.6 0.8) (layers "B.Cu" "B.Paste" "B.Mask") (roundrect_rratio 0.2)
      (net 133 "5V_SYS") (pintype "passive"))
    (pad "2" smd roundrect (at 0.7 0) (size 0.6 0.8) (layers "B.Cu" "B.Paste" "B.Mask") (roundrect_rratio 0.2)
      (net 1 "GND") (pintype "passive"))
  )

  (footprint "sa800u-baseboard-hw-footprints:C_0603_1608Metric" (layer "B.Cu")
    (tedit 5D5E94D2)
    (at 129.55 125.04 180)
    (descr "Capacitor SMD 0603")
    (tags "capacitor 0603")
    (property "Author" "Antmicro")
    (property "Dielectric" "")
    (property "License" "Apache-2.0")
    (property "MPN" "GRM188R60J226MEA0D")
    (property "Manufacturer" "Murata")
    (property "Sheetfile" "psu.kicad_sch")
    (property "Sheetname" "PSU")
    (property "Val" "22u")
    (property "Voltage" "")
    (attr smd)
    (fp_text reference "C140" (at -1.48 -2.88) (layer "B.SilkS")
      (effects (font (size 0.7 0.7) (thickness 0.15)) (justify left bottom mirror))
    )
    (fp_text value "C_22u_0603" (at 0 -1.6) (layer "B.Fab")
      (effects (font (size 0.7 0.7) (thickness 0.15)) (justify left bottom mirror))
    )
    (fp_text user "Author: Antmicro" (at -1.682 -4.894) (layer "B.Fab") hide
      (effects (font (size 0.7 0.7) (thickness 0.15)) (justify left bottom mirror))
    )
    (fp_text user "${REFERENCE}" (at -1.682 -3.895) (layer "B.Fab") hide
      (effects (font (size 0.7 0.7) (thickness 0.15)) (justify left bottom mirror))
    )
    (fp_text user "License: Apache-2.0" (at -1.682 -5.895) (layer "B.Fab") hide
      (effects (font (size 0.7 0.7) (thickness 0.15)) (justify left bottom mirror))
    )
    (fp_line (start -0.3 -0.3) (end 0.3 -0.3) (layer "B.SilkS") (width 0.15))
    (fp_line (start -0.3 0.3) (end 0.3 0.3) (layer "B.SilkS") (width 0.15))
    (fp_rect (start -1.24 0.7) (end 1.24 -0.7) (layer "B.CrtYd") (width 0.05) (fill none))
    (fp_rect (start -0.8 0.4) (end 0.8 -0.4) (layer "B.Fab") (width 0.15) (fill none))
    (pad "1" smd roundrect (at -0.7 0 180) (size 0.6 0.8) (layers "B.Cu" "B.Paste" "B.Mask") (roundrect_rratio 0.2)
      (net 138 "1V2_SYS") (pintype "passive"))
    (pad "2" smd roundrect (at 0.7 0 180) (size 0.6 0.8) (layers "B.Cu" "B.Paste" "B.Mask") (roundrect_rratio 0.2)
      (net 1 "GND") (pintype "passive"))
  )

  (footprint "sa800u-baseboard-hw-footprints:R_0402_1005Metric" (layer "B.Cu")
    (tedit 5FD9C158)
    (at 121.85 123.05)
    (descr "Resistor SMD 0402")
    (tags "resistor SMD 0402")
    (property "Author" "Antmicro")
    (property "License" "Apache-2.0")
    (property "MPN" "CR0402-FX-2002GLF")
    (property "Manufacturer" "Bourns")
    (property "Sheetfile" "psu.kicad_sch")
    (property "Sheetname" "PSU")
    (property "Tolerance" "1%")
    (property "Val" "20k")
    (attr smd)
    (fp_text reference "R140" (at -0.84 0.37 180) (layer "B.SilkS")
      (effects (font (size 0.7 0.7) (thickness 0.15)) (justify left bottom mirror))
    )
    (fp_text value "R_20k_0402" (at 0 -1.4 180) (layer "B.Fab")
      (effects (font (size 0.7 0.7) (thickness 0.15)) (justify left bottom mirror))
    )
    (fp_text user "${REFERENCE}" (at -0.95 -3.168 180) (layer "B.Fab") hide
      (effects (font (size 0.7 0.7) (thickness 0.15)) (justify left bottom mirror))
    )
    (fp_text user "Author: Antmicro" (at -0.95 -4.169 180) (layer "B.Fab") hide
      (effects (font (size 0.7 0.7) (thickness 0.15)) (justify left bottom mirror))
    )
    (fp_text user "License: Apache-2.0" (at -0.95 -5.169 180) (layer "B.Fab") hide
      (effects (font (size 0.7 0.7) (thickness 0.15)) (justify left bottom mirror))
    )
    (fp_rect (start -0.93 0.47) (end 0.93 -0.47) (layer "B.CrtYd") (width 0.05) (fill none))
    (fp_rect (start -0.5 0.25) (end 0.5 -0.25) (layer "B.Fab") (width 0.15) (fill none))
    (pad "1" smd roundrect (at -0.485 0) (size 0.59 0.64) (layers "B.Cu" "B.Paste" "B.Mask") (roundrect_rratio 0.25)
      (net 1 "GND") (pintype "passive"))
    (pad "2" smd roundrect (at 0.485 0) (size 0.59 0.64) (layers "B.Cu" "B.Paste" "B.Mask") (roundrect_rratio 0.25)
      (net 172 "Net-(R139-Pad2)") (pintype "passive"))
  )

  (footprint "sa800u-baseboard-hw-footprints:C_0402_1005Metric" (layer "B.Cu")
    (tedit 616D63CF)
    (at 136.75 134.95 90)
    (descr "Capacitor SMD 0402")
    (tags "capacitor SMD 0402")
    (property "Author" "Antmicro")
    (property "DNP" "DNP")
    (property "Dielectric" "C0G")
    (property "License" "Apache-2.0")
    (property "MPN" "GCM1555C1H100GA16D")
    (property "Manufacturer" "Murata")
    (property "Sheetfile" "hdmi-converter.kicad_sch")
    (property "Sheetname" "HDMI converter")
    (property "Val" "10p")
    (property "Voltage" "50V")
    (attr exclude_from_pos_files)
    (fp_text reference "C57" (at -0.85 0.37 270) (layer "B.SilkS")
      (effects (font (size 0.7 0.7) (thickness 0.15)) (justify left bottom mirror))
    )
    (fp_text value "C_10p_0402" (at 0 -1.4 270) (layer "B.Fab")
      (effects (font (size 0.7 0.7) (thickness 0.15)) (justify left bottom mirror))
    )
    (fp_text user "License: Apache-2.0" (at -0.932 -5.17 270) (layer "B.Fab") hide
      (effects (font (size 0.7 0.7) (thickness 0.15)) (justify left bottom mirror))
    )
    (fp_text user "Author: Antmicro" (at -0.932 -4.17 270) (layer "B.Fab") hide
      (effects (font (size 0.7 0.7) (thickness 0.15)) (justify left bottom mirror))
    )
    (fp_text user "${REFERENCE}" (at -0.932 -3.168 270) (layer "B.Fab") hide
      (effects (font (size 0.7 0.7) (thickness 0.15)) (justify left bottom mirror))
    )
    (fp_rect (start -0.94 0.47) (end 0.94 -0.47) (layer "B.CrtYd") (width 0.05) (fill none))
    (fp_rect (start -0.499 0.249) (end 0.499 -0.249) (layer "B.Fab") (width 0.15) (fill none))
    (pad "1" smd roundrect (at -0.484 0 90) (size 0.59 0.64) (layers "B.Cu" "B.Paste" "B.Mask") (roundrect_rratio 0.25)
      (net 208 "/HDMI converter/HDMI_CLK_N") (pintype "passive"))
    (pad "2" smd roundrect (at 0.484 0 90) (size 0.59 0.64) (layers "B.Cu" "B.Paste" "B.Mask") (roundrect_rratio 0.25)
      (net 1 "GND") (pintype "passive"))
  )

  (footprint "sa800u-baseboard-hw-footprints:R_0402_1005Metric" (layer "B.Cu")
    (tedit 5FD9C158)
    (at 139.388164 128.712953 90)
    (descr "Resistor SMD 0402")
    (tags "resistor SMD 0402")
    (property "Author" "Antmicro")
    (property "License" "Apache-2.0")
    (property "MPN" "CR0402-FX-2002GLF")
    (property "Manufacturer" "Bourns")
    (property "Sheetfile" "hdmi-converter.kicad_sch")
    (property "Sheetname" "HDMI converter")
    (property "Tolerance" "1%")
    (property "Val" "20k")
    (attr smd)
    (fp_text reference "R27" (at -0.291 -2.64 270) (layer "B.SilkS")
      (effects (font (size 0.7 0.7) (thickness 0.15)) (justify left bottom mirror))
    )
    (fp_text value "R_20k_0402" (at 0 -1.4 270) (layer "B.Fab")
      (effects (font (size 0.7 0.7) (thickness 0.15)) (justify left bottom mirror))
    )
    (fp_text user "${REFERENCE}" (at -0.95 -3.168 270) (layer "B.Fab") hide
      (effects (font (size 0.7 0.7) (thickness 0.15)) (justify left bottom mirror))
    )
    (fp_text user "License: Apache-2.0" (at -0.95 -5.169 270) (layer "B.Fab") hide
      (effects (font (size 0.7 0.7) (thickness 0.15)) (justify left bottom mirror))
    )
    (fp_text user "Author: Antmicro" (at -0.95 -4.169 270) (layer "B.Fab") hide
      (effects (font (size 0.7 0.7) (thickness 0.15)) (justify left bottom mirror))
    )
    (fp_rect (start -0.93 0.47) (end 0.93 -0.47) (layer "B.CrtYd") (width 0.05) (fill none))
    (fp_rect (start -0.5 0.25) (end 0.5 -0.25) (layer "B.Fab") (width 0.15) (fill none))
    (pad "1" smd roundrect (at -0.485 0 90) (size 0.59 0.64) (layers "B.Cu" "B.Paste" "B.Mask") (roundrect_rratio 0.25)
      (net 395 "Net-(R27-Pad1)") (pintype "passive"))
    (pad "2" smd roundrect (at 0.485 0 90) (size 0.59 0.64) (layers "B.Cu" "B.Paste" "B.Mask") (roundrect_rratio 0.25)
      (net 1 "GND") (pintype "passive"))
  )

  (footprint "sa800u-baseboard-hw-footprints:C_0402_1005Metric" (layer "B.Cu")
    (tedit 616D63CF)
    (at 137.39 128.71 90)
    (descr "Capacitor SMD 0402")
    (tags "capacitor SMD 0402")
    (property "Author" "Antmicro")
    (property "DNP" "DNP")
    (property "Dielectric" "")
    (property "License" "Apache-2.0")
    (property "MPN" "CC0402MRX5R5BB106")
    (property "Manufacturer" "Yaego")
    (property "Sheetfile" "hdmi-converter.kicad_sch")
    (property "Sheetname" "HDMI converter")
    (property "Val" "10u")
    (property "Voltage" "")
    (attr exclude_from_pos_files)
    (fp_text reference "C23" (at -0.29 -2.64 270) (layer "B.SilkS")
      (effects (font (size 0.7 0.7) (thickness 0.15)) (justify left bottom mirror))
    )
    (fp_text value "C_10u_0402" (at 0 -1.4 270) (layer "B.Fab")
      (effects (font (size 0.7 0.7) (thickness 0.15)) (justify left bottom mirror))
    )
    (fp_text user "License: Apache-2.0" (at -0.932 -5.17 270) (layer "B.Fab") hide
      (effects (font (size 0.7 0.7) (thickness 0.15)) (justify left bottom mirror))
    )
    (fp_text user "Author: Antmicro" (at -0.932 -4.17 270) (layer "B.Fab") hide
      (effects (font (size 0.7 0.7) (thickness 0.15)) (justify left bottom mirror))
    )
    (fp_text user "${REFERENCE}" (at -0.932 -3.168 270) (layer "B.Fab") hide
      (effects (font (size 0.7 0.7) (thickness 0.15)) (justify left bottom mirror))
    )
    (fp_rect (start -0.94 0.47) (end 0.94 -0.47) (layer "B.CrtYd") (width 0.05) (fill none))
    (fp_rect (start -0.499 0.249) (end 0.499 -0.249) (layer "B.Fab") (width 0.15) (fill none))
    (pad "1" smd roundrect (at -0.484 0 90) (size 0.59 0.64) (layers "B.Cu" "B.Paste" "B.Mask") (roundrect_rratio 0.25)
      (net 184 "/HDMI converter/LT9611_VCC33_IO") (pintype "passive"))
    (pad "2" smd roundrect (at 0.484 0 90) (size 0.59 0.64) (layers "B.Cu" "B.Paste" "B.Mask") (roundrect_rratio 0.25)
      (net 1 "GND") (pintype "passive"))
  )

  (footprint "sa800u-baseboard-hw-footprints:C_0402_1005Metric" (layer "B.Cu")
    (tedit 616D63CF)
    (at 137.773164 126.212952)
    (descr "Capacitor SMD 0402")
    (tags "capacitor SMD 0402")
    (property "Author" "Antmicro")
    (property "Dielectric" "X5R")
    (property "License" "Apache-2.0")
    (property "MPN" "GRM155R61H104KE14D")
    (property "Manufacturer" "Murata")
    (property "Sheetfile" "hdmi-converter.kicad_sch")
    (property "Sheetname" "HDMI converter")
    (property "Val" "100n")
    (property "Voltage" "50V")
    (attr smd)
    (fp_text reference "C29" (at 0.666836 1.327048 180) (layer "B.SilkS")
      (effects (font (size 0.7 0.7) (thickness 0.15)) (justify left bottom mirror))
    )
    (fp_text value "C_100n_0402" (at 0 -1.4 180) (layer "B.Fab")
      (effects (font (size 0.7 0.7) (thickness 0.15)) (justify left bottom mirror))
    )
    (fp_text user "Author: Antmicro" (at -0.932 -4.17 180) (layer "B.Fab") hide
      (effects (font (size 0.7 0.7) (thickness 0.15)) (justify left bottom mirror))
    )
    (fp_text user "${REFERENCE}" (at -0.932 -3.168 180) (layer "B.Fab") hide
      (effects (font (size 0.7 0.7) (thickness 0.15)) (justify left bottom mirror))
    )
    (fp_text user "License: Apache-2.0" (at -0.932 -5.17 180) (layer "B.Fab") hide
      (effects (font (size 0.7 0.7) (thickness 0.15)) (justify left bottom mirror))
    )
    (fp_rect (start -0.94 0.47) (end 0.94 -0.47) (layer "B.CrtYd") (width 0.05) (fill none))
    (fp_rect (start -0.499 0.249) (end 0.499 -0.249) (layer "B.Fab") (width 0.15) (fill none))
    (pad "1" smd roundrect (at -0.484 0) (size 0.59 0.64) (layers "B.Cu" "B.Paste" "B.Mask") (roundrect_rratio 0.25)
      (net 184 "/HDMI converter/LT9611_VCC33_IO") (pintype "passive"))
    (pad "2" smd roundrect (at 0.484 0) (size 0.59 0.64) (layers "B.Cu" "B.Paste" "B.Mask") (roundrect_rratio 0.25)
      (net 1 "GND") (pintype "passive"))
  )

  (footprint "sa800u-baseboard-hw-footprints:C_0402_1005Metric" (layer "B.Cu")
    (tedit 616D63CF)
    (at 138.388164 128.712953 90)
    (descr "Capacitor SMD 0402")
    (tags "capacitor SMD 0402")
    (property "Author" "Antmicro")
    (property "Dielectric" "X5R")
    (property "License" "Apache-2.0")
    (property "MPN" "GRM155R61H104KE14D")
    (property "Manufacturer" "Murata")
    (property "Sheetfile" "hdmi-converter.kicad_sch")
    (property "Sheetname" "HDMI converter")
    (property "Val" "100n")
    (property "Voltage" "50V")
    (attr smd)
    (fp_text reference "C32" (at -0.29 -2.64 270) (layer "B.SilkS")
      (effects (font (size 0.7 0.7) (thickness 0.15)) (justify left bottom mirror))
    )
    (fp_text value "C_100n_0402" (at 0 -1.4 270) (layer "B.Fab")
      (effects (font (size 0.7 0.7) (thickness 0.15)) (justify left bottom mirror))
    )
    (fp_text user "License: Apache-2.0" (at -0.932 -5.17 270) (layer "B.Fab") hide
      (effects (font (size 0.7 0.7) (thickness 0.15)) (justify left bottom mirror))
    )
    (fp_text user "Author: Antmicro" (at -0.932 -4.17 270) (layer "B.Fab") hide
      (effects (font (size 0.7 0.7) (thickness 0.15)) (justify left bottom mirror))
    )
    (fp_text user "${REFERENCE}" (at -0.932 -3.168 270) (layer "B.Fab") hide
      (effects (font (size 0.7 0.7) (thickness 0.15)) (justify left bottom mirror))
    )
    (fp_rect (start -0.94 0.47) (end 0.94 -0.47) (layer "B.CrtYd") (width 0.05) (fill none))
    (fp_rect (start -0.499 0.249) (end 0.499 -0.249) (layer "B.Fab") (width 0.15) (fill none))
    (pad "1" smd roundrect (at -0.484 0 90) (size 0.59 0.64) (layers "B.Cu" "B.Paste" "B.Mask") (roundrect_rratio 0.25)
      (net 184 "/HDMI converter/LT9611_VCC33_IO") (pintype "passive"))
    (pad "2" smd roundrect (at 0.484 0 90) (size 0.59 0.64) (layers "B.Cu" "B.Paste" "B.Mask") (roundrect_rratio 0.25)
      (net 1 "GND") (pintype "passive"))
  )

  (footprint "sa800u-baseboard-hw-footprints:C_0402_1005Metric" (layer "B.Cu")
    (tedit 616D63CF)
    (at 144.6 122.9 180)
    (descr "Capacitor SMD 0402")
    (tags "capacitor SMD 0402")
    (property "Author" "Antmicro")
    (property "DNP" "DNP")
    (property "Dielectric" "")
    (property "License" "Apache-2.0")
    (property "MPN" "CC0402MRX5R5BB106")
    (property "Manufacturer" "Yaego")
    (property "Sheetfile" "hdmi-converter.kicad_sch")
    (property "Sheetname" "HDMI converter")
    (property "Val" "10u")
    (property "Voltage" "")
    (attr exclude_from_pos_files)
    (fp_text reference "C38" (at -1 -1.18) (layer "B.SilkS")
      (effects (font (size 0.7 0.7) (thickness 0.15)) (justify left bottom mirror))
    )
    (fp_text value "C_10u_0402" (at 0 -1.4) (layer "B.Fab")
      (effects (font (size 0.7 0.7) (thickness 0.15)) (justify left bottom mirror))
    )
    (fp_text user "License: Apache-2.0" (at -0.932 -5.17) (layer "B.Fab") hide
      (effects (font (size 0.7 0.7) (thickness 0.15)) (justify left bottom mirror))
    )
    (fp_text user "${REFERENCE}" (at -0.932 -3.168) (layer "B.Fab") hide
      (effects (font (size 0.7 0.7) (thickness 0.15)) (justify left bottom mirror))
    )
    (fp_text user "Author: Antmicro" (at -0.932 -4.17) (layer "B.Fab") hide
      (effects (font (size 0.7 0.7) (thickness 0.15)) (justify left bottom mirror))
    )
    (fp_rect (start -0.94 0.47) (end 0.94 -0.47) (layer "B.CrtYd") (width 0.05) (fill none))
    (fp_rect (start -0.499 0.249) (end 0.499 -0.249) (layer "B.Fab") (width 0.15) (fill none))
    (pad "1" smd roundrect (at -0.484 0 180) (size 0.59 0.64) (layers "B.Cu" "B.Paste" "B.Mask") (roundrect_rratio 0.25)
      (net 185 "/HDMI converter/LT9611_VCC33_RX") (pintype "passive"))
    (pad "2" smd roundrect (at 0.484 0 180) (size 0.59 0.64) (layers "B.Cu" "B.Paste" "B.Mask") (roundrect_rratio 0.25)
      (net 1 "GND") (pintype "passive"))
  )

  (footprint "sa800u-baseboard-hw-footprints:C_0402_1005Metric" (layer "B.Cu")
    (tedit 616D63CF)
    (at 144.1 129.15 180)
    (descr "Capacitor SMD 0402")
    (tags "capacitor SMD 0402")
    (property "Author" "Antmicro")
    (property "Dielectric" "X5R")
    (property "License" "Apache-2.0")
    (property "MPN" "GRM155R61H104KE14D")
    (property "Manufacturer" "Murata")
    (property "Sheetfile" "hdmi-converter.kicad_sch")
    (property "Sheetname" "HDMI converter")
    (property "Val" "100n")
    (property "Voltage" "50V")
    (attr smd)
    (fp_text reference "C42" (at -3.119 -0.3) (layer "B.SilkS")
      (effects (font (size 0.7 0.7) (thickness 0.15)) (justify left bottom mirror))
    )
    (fp_text value "C_100n_0402" (at 0 -1.4) (layer "B.Fab")
      (effects (font (size 0.7 0.7) (thickness 0.15)) (justify left bottom mirror))
    )
    (fp_text user "License: Apache-2.0" (at -0.932 -5.17) (layer "B.Fab") hide
      (effects (font (size 0.7 0.7) (thickness 0.15)) (justify left bottom mirror))
    )
    (fp_text user "${REFERENCE}" (at -0.932 -3.168) (layer "B.Fab") hide
      (effects (font (size 0.7 0.7) (thickness 0.15)) (justify left bottom mirror))
    )
    (fp_text user "Author: Antmicro" (at -0.932 -4.17) (layer "B.Fab") hide
      (effects (font (size 0.7 0.7) (thickness 0.15)) (justify left bottom mirror))
    )
    (fp_rect (start -0.94 0.47) (end 0.94 -0.47) (layer "B.CrtYd") (width 0.05) (fill none))
    (fp_rect (start -0.499 0.249) (end 0.499 -0.249) (layer "B.Fab") (width 0.15) (fill none))
    (pad "1" smd roundrect (at -0.484 0 180) (size 0.59 0.64) (layers "B.Cu" "B.Paste" "B.Mask") (roundrect_rratio 0.25)
      (net 185 "/HDMI converter/LT9611_VCC33_RX") (pintype "passive"))
    (pad "2" smd roundrect (at 0.484 0 180) (size 0.59 0.64) (layers "B.Cu" "B.Paste" "B.Mask") (roundrect_rratio 0.25)
      (net 1 "GND") (pintype "passive"))
  )

  (footprint "sa800u-baseboard-hw-footprints:C_0402_1005Metric" (layer "B.Cu")
    (tedit 616D63CF)
    (at 140.85 131.95 180)
    (descr "Capacitor SMD 0402")
    (tags "capacitor SMD 0402")
    (property "Author" "Antmicro")
    (property "DNP" "DNP")
    (property "Dielectric" "")
    (property "License" "Apache-2.0")
    (property "MPN" "CC0402MRX5R5BB106")
    (property "Manufacturer" "Yaego")
    (property "Sheetfile" "hdmi-converter.kicad_sch")
    (property "Sheetname" "HDMI converter")
    (property "Val" "10u")
    (property "Voltage" "")
    (attr exclude_from_pos_files)
    (fp_text reference "C43" (at 0.89 -0.41) (layer "B.SilkS")
      (effects (font (size 0.7 0.7) (thickness 0.15)) (justify left bottom mirror))
    )
    (fp_text value "C_10u_0402" (at 0 -1.4) (layer "B.Fab")
      (effects (font (size 0.7 0.7) (thickness 0.15)) (justify left bottom mirror))
    )
    (fp_text user "Author: Antmicro" (at -0.932 -4.17) (layer "B.Fab") hide
      (effects (font (size 0.7 0.7) (thickness 0.15)) (justify left bottom mirror))
    )
    (fp_text user "${REFERENCE}" (at -0.932 -3.168) (layer "B.Fab") hide
      (effects (font (size 0.7 0.7) (thickness 0.15)) (justify left bottom mirror))
    )
    (fp_text user "License: Apache-2.0" (at -0.932 -5.17) (layer "B.Fab") hide
      (effects (font (size 0.7 0.7) (thickness 0.15)) (justify left bottom mirror))
    )
    (fp_rect (start -0.94 0.47) (end 0.94 -0.47) (layer "B.CrtYd") (width 0.05) (fill none))
    (fp_rect (start -0.499 0.249) (end 0.499 -0.249) (layer "B.Fab") (width 0.15) (fill none))
    (pad "1" smd roundrect (at -0.484 0 180) (size 0.59 0.64) (layers "B.Cu" "B.Paste" "B.Mask") (roundrect_rratio 0.25)
      (net 187 "/HDMI converter/LT9611_VCC33_TX") (pintype "passive"))
    (pad "2" smd roundrect (at 0.484 0 180) (size 0.59 0.64) (layers "B.Cu" "B.Paste" "B.Mask") (roundrect_rratio 0.25)
      (net 1 "GND") (pintype "passive"))
  )

  (footprint "sa800u-baseboard-hw-footprints:C_0402_1005Metric" (layer "B.Cu")
    (tedit 616D63CF)
    (at 141.65 128.7 90)
    (descr "Capacitor SMD 0402")
    (tags "capacitor SMD 0402")
    (property "Author" "Antmicro")
    (property "Dielectric" "X5R")
    (property "License" "Apache-2.0")
    (property "MPN" "GRM155R61H104KE14D")
    (property "Manufacturer" "Murata")
    (property "Sheetfile" "hdmi-converter.kicad_sch")
    (property "Sheetname" "HDMI converter")
    (property "Val" "100n")
    (property "Voltage" "50V")
    (attr smd)
    (fp_text reference "C45" (at 1.12 -0.65 270) (layer "B.SilkS")
      (effects (font (size 0.7 0.7) (thickness 0.15)) (justify left bottom mirror))
    )
    (fp_text value "C_100n_0402" (at 0 -1.4 270) (layer "B.Fab")
      (effects (font (size 0.7 0.7) (thickness 0.15)) (justify left bottom mirror))
    )
    (fp_text user "Author: Antmicro" (at -0.932 -4.17 270) (layer "B.Fab") hide
      (effects (font (size 0.7 0.7) (thickness 0.15)) (justify left bottom mirror))
    )
    (fp_text user "License: Apache-2.0" (at -0.932 -5.17 270) (layer "B.Fab") hide
      (effects (font (size 0.7 0.7) (thickness 0.15)) (justify left bottom mirror))
    )
    (fp_text user "${REFERENCE}" (at -0.932 -3.168 270) (layer "B.Fab") hide
      (effects (font (size 0.7 0.7) (thickness 0.15)) (justify left bottom mirror))
    )
    (fp_rect (start -0.94 0.47) (end 0.94 -0.47) (layer "B.CrtYd") (width 0.05) (fill none))
    (fp_rect (start -0.499 0.249) (end 0.499 -0.249) (layer "B.Fab") (width 0.15) (fill none))
    (pad "1" smd roundrect (at -0.484 0 90) (size 0.59 0.64) (layers "B.Cu" "B.Paste" "B.Mask") (roundrect_rratio 0.25)
      (net 187 "/HDMI converter/LT9611_VCC33_TX") (pintype "passive"))
    (pad "2" smd roundrect (at 0.484 0 90) (size 0.59 0.64) (layers "B.Cu" "B.Paste" "B.Mask") (roundrect_rratio 0.25)
      (net 1 "GND") (pintype "passive"))
  )

  (footprint "sa800u-baseboard-hw-footprints:C_0402_1005Metric" (layer "B.Cu")
    (tedit 616D63CF)
    (at 138.4 121.7 -90)
    (descr "Capacitor SMD 0402")
    (tags "capacitor SMD 0402")
    (property "Author" "Antmicro")
    (property "Dielectric" "X5R")
    (property "License" "Apache-2.0")
    (property "MPN" "GRM155R61H104KE14D")
    (property "Manufacturer" "Murata")
    (property "Sheetfile" "hdmi-converter.kicad_sch")
    (property "Sheetname" "HDMI converter")
    (property "Val" "100n")
    (property "Voltage" "50V")
    (attr smd)
    (fp_text reference "C28" (at -3.02 -0.36 90) (layer "B.SilkS")
      (effects (font (size 0.7 0.7) (thickness 0.15)) (justify left bottom mirror))
    )
    (fp_text value "C_100n_0402" (at 0 -1.4 90) (layer "B.Fab")
      (effects (font (size 0.7 0.7) (thickness 0.15)) (justify left bottom mirror))
    )
    (fp_text user "Author: Antmicro" (at -0.932 -4.17 90) (layer "B.Fab") hide
      (effects (font (size 0.7 0.7) (thickness 0.15)) (justify left bottom mirror))
    )
    (fp_text user "License: Apache-2.0" (at -0.932 -5.17 90) (layer "B.Fab") hide
      (effects (font (size 0.7 0.7) (thickness 0.15)) (justify left bottom mirror))
    )
    (fp_text user "${REFERENCE}" (at -0.932 -3.168 90) (layer "B.Fab") hide
      (effects (font (size 0.7 0.7) (thickness 0.15)) (justify left bottom mirror))
    )
    (fp_rect (start -0.94 0.47) (end 0.94 -0.47) (layer "B.CrtYd") (width 0.05) (fill none))
    (fp_rect (start -0.499 0.249) (end 0.499 -0.249) (layer "B.Fab") (width 0.15) (fill none))
    (pad "1" smd roundrect (at -0.484 0 270) (size 0.59 0.64) (layers "B.Cu" "B.Paste" "B.Mask") (roundrect_rratio 0.25)
      (net 188 "/HDMI converter/LT9611_VDD12") (pintype "passive"))
    (pad "2" smd roundrect (at 0.484 0 270) (size 0.59 0.64) (layers "B.Cu" "B.Paste" "B.Mask") (roundrect_rratio 0.25)
      (net 1 "GND") (pintype "passive"))
  )

  (footprint "sa800u-baseboard-hw-footprints:C_0402_1005Metric" (layer "B.Cu")
    (tedit 616D63CF)
    (at 139.4 121.7 -90)
    (descr "Capacitor SMD 0402")
    (tags "capacitor SMD 0402")
    (property "Author" "Antmicro")
    (property "Dielectric" "X5R")
    (property "License" "Apache-2.0")
    (property "MPN" "GRM155R61H104KE14D")
    (property "Manufacturer" "Murata")
    (property "Sheetfile" "hdmi-converter.kicad_sch")
    (property "Sheetname" "HDMI converter")
    (property "Val" "100n")
    (property "Voltage" "50V")
    (attr smd)
    (fp_text reference "C31" (at -3.02 -0.36 90) (layer "B.SilkS")
      (effects (font (size 0.7 0.7) (thickness 0.15)) (justify left bottom mirror))
    )
    (fp_text value "C_100n_0402" (at 0 -1.4 90) (layer "B.Fab")
      (effects (font (size 0.7 0.7) (thickness 0.15)) (justify left bottom mirror))
    )
    (fp_text user "License: Apache-2.0" (at -0.932 -5.17 90) (layer "B.Fab") hide
      (effects (font (size 0.7 0.7) (thickness 0.15)) (justify left bottom mirror))
    )
    (fp_text user "${REFERENCE}" (at -0.932 -3.168 90) (layer "B.Fab") hide
      (effects (font (size 0.7 0.7) (thickness 0.15)) (justify left bottom mirror))
    )
    (fp_text user "Author: Antmicro" (at -0.932 -4.17 90) (layer "B.Fab") hide
      (effects (font (size 0.7 0.7) (thickness 0.15)) (justify left bottom mirror))
    )
    (fp_rect (start -0.94 0.47) (end 0.94 -0.47) (layer "B.CrtYd") (width 0.05) (fill none))
    (fp_rect (start -0.499 0.249) (end 0.499 -0.249) (layer "B.Fab") (width 0.15) (fill none))
    (pad "1" smd roundrect (at -0.484 0 270) (size 0.59 0.64) (layers "B.Cu" "B.Paste" "B.Mask") (roundrect_rratio 0.25)
      (net 188 "/HDMI converter/LT9611_VDD12") (pintype "passive"))
    (pad "2" smd roundrect (at 0.484 0 270) (size 0.59 0.64) (layers "B.Cu" "B.Paste" "B.Mask") (roundrect_rratio 0.25)
      (net 1 "GND") (pintype "passive"))
  )

  (footprint "sa800u-baseboard-hw-footprints:C_0402_1005Metric" (layer "B.Cu")
    (tedit 616D63CF)
    (at 143.2 131.95)
    (descr "Capacitor SMD 0402")
    (tags "capacitor SMD 0402")
    (property "Author" "Antmicro")
    (property "DNP" "DNP")
    (property "Dielectric" "")
    (property "License" "Apache-2.0")
    (property "MPN" "CC0402MRX5R5BB106")
    (property "Manufacturer" "Yaego")
    (property "Sheetfile" "hdmi-converter.kicad_sch")
    (property "Sheetname" "HDMI converter")
    (property "Val" "10u")
    (property "Voltage" "")
    (attr exclude_from_pos_files)
    (fp_text reference "C36" (at 3.02 0.4 180) (layer "B.SilkS")
      (effects (font (size 0.7 0.7) (thickness 0.15)) (justify left bottom mirror))
    )
    (fp_text value "C_10u_0402" (at 0 -1.4 180) (layer "B.Fab")
      (effects (font (size 0.7 0.7) (thickness 0.15)) (justify left bottom mirror))
    )
    (fp_text user "Author: Antmicro" (at -0.932 -4.17 180) (layer "B.Fab") hide
      (effects (font (size 0.7 0.7) (thickness 0.15)) (justify left bottom mirror))
    )
    (fp_text user "License: Apache-2.0" (at -0.932 -5.17 180) (layer "B.Fab") hide
      (effects (font (size 0.7 0.7) (thickness 0.15)) (justify left bottom mirror))
    )
    (fp_text user "${REFERENCE}" (at -0.932 -3.168 180) (layer "B.Fab") hide
      (effects (font (size 0.7 0.7) (thickness 0.15)) (justify left bottom mirror))
    )
    (fp_rect (start -0.94 0.47) (end 0.94 -0.47) (layer "B.CrtYd") (width 0.05) (fill none))
    (fp_rect (start -0.499 0.249) (end 0.499 -0.249) (layer "B.Fab") (width 0.15) (fill none))
    (pad "1" smd roundrect (at -0.484 0) (size 0.59 0.64) (layers "B.Cu" "B.Paste" "B.Mask") (roundrect_rratio 0.25)
      (net 191 "/HDMI converter/LT9611_VCC12_TX") (pintype "passive"))
    (pad "2" smd roundrect (at 0.484 0) (size 0.59 0.64) (layers "B.Cu" "B.Paste" "B.Mask") (roundrect_rratio 0.25)
      (net 1 "GND") (pintype "passive"))
  )

  (footprint "sa800u-baseboard-hw-footprints:C_0402_1005Metric" (layer "B.Cu")
    (tedit 616D63CF)
    (at 142.65 128.7 90)
    (descr "Capacitor SMD 0402")
    (tags "capacitor SMD 0402")
    (property "Author" "Antmicro")
    (property "Dielectric" "X5R")
    (property "License" "Apache-2.0")
    (property "MPN" "GRM155R61H104KE14D")
    (property "Manufacturer" "Murata")
    (property "Sheetfile" "hdmi-converter.kicad_sch")
    (property "Sheetname" "HDMI converter")
    (property "Val" "100n")
    (property "Voltage" "50V")
    (attr smd)
    (fp_text reference "C39" (at 0.93 1.04) (layer "B.SilkS")
      (effects (font (size 0.7 0.7) (thickness 0.15)) (justify left bottom mirror))
    )
    (fp_text value "C_100n_0402" (at 0 -1.4 270) (layer "B.Fab")
      (effects (font (size 0.7 0.7) (thickness 0.15)) (justify left bottom mirror))
    )
    (fp_text user "License: Apache-2.0" (at -0.932 -5.17 270) (layer "B.Fab") hide
      (effects (font (size 0.7 0.7) (thickness 0.15)) (justify left bottom mirror))
    )
    (fp_text user "${REFERENCE}" (at -0.932 -3.168 270) (layer "B.Fab") hide
      (effects (font (size 0.7 0.7) (thickness 0.15)) (justify left bottom mirror))
    )
    (fp_text user "Author: Antmicro" (at -0.932 -4.17 270) (layer "B.Fab") hide
      (effects (font (size 0.7 0.7) (thickness 0.15)) (justify left bottom mirror))
    )
    (fp_rect (start -0.94 0.47) (end 0.94 -0.47) (layer "B.CrtYd") (width 0.05) (fill none))
    (fp_rect (start -0.499 0.249) (end 0.499 -0.249) (layer "B.Fab") (width 0.15) (fill none))
    (pad "1" smd roundrect (at -0.484 0 90) (size 0.59 0.64) (layers "B.Cu" "B.Paste" "B.Mask") (roundrect_rratio 0.25)
      (net 191 "/HDMI converter/LT9611_VCC12_TX") (pintype "passive"))
    (pad "2" smd roundrect (at 0.484 0 90) (size 0.59 0.64) (layers "B.Cu" "B.Paste" "B.Mask") (roundrect_rratio 0.25)
      (net 1 "GND") (pintype "passive"))
  )

  (footprint "sa800u-baseboard-hw-footprints:L_0603_1608Metric" (layer "B.Cu")
    (tedit 5D5D3F54)
    (at 140.25 130.65)
    (property "Author" "Antmicro")
    (property "IMax" "")
    (property "ISat" "")
    (property "License" "Apache-2.0")
    (property "MPN" "BRC1608TR35M")
    (property "Manufacturer" "Taiyo Yuden")
    (property "Sheetfile" "hdmi-converter.kicad_sch")
    (property "Sheetname" "HDMI converter")
    (property "Size" "")
    (property "Val" "350n/1.4A")
    (attr smd)
    (fp_text reference "L3" (at -1.1 0.45 180) (layer "B.SilkS")
      (effects (font (size 0.7 0.7) (thickness 0.15)) (justify left bottom mirror))
    )
    (fp_text value "L_350n_1.4A_0603" (at 0 -2 180) (layer "B.Fab")
      (effects (font (size 0.7 0.7) (thickness 0.15)) (justify left bottom mirror))
    )
    (fp_text user "${REFERENCE}" (at -1.9 -3.1 180) (layer "B.Fab") hide
      (effects (font (size 0.7 0.7) (thickness 0.15)) (justify left bottom mirror))
    )
    (fp_text user "License: Apache-2.0" (at -1.9 -5.75 180) (layer "B.Fab") hide
      (effects (font (size 0.7 0.7) (thickness 0.15)) (justify left bottom mirror))
    )
    (fp_text user "Author: Antmicro" (at -1.9 -4.4 180) (layer "B.Fab") hide
      (effects (font (size 0.7 0.7) (thickness 0.15)) (justify left bottom mirror))
    )
    (fp_line (start -0.25 0.45) (end 0.25 0.45) (layer "B.SilkS") (width 0.1))
    (fp_line (start -0.25 -0.45) (end 0.25 -0.45) (layer "B.SilkS") (width 0.1))
    (fp_rect (start -1.15 0.75) (end 1.15 -0.75) (layer "B.CrtYd") (width 0.05) (fill none))
    (fp_rect (start -0.8 0.4) (end 0.8 -0.4) (layer "B.Fab") (width 0.1) (fill none))
    (pad "1" smd roundrect (at -0.625 0) (size 0.55 1) (layers "B.Cu" "B.Paste" "B.Mask") (roundrect_rratio 0.15)
      (net 131 "3V3_SYS") (pintype "passive"))
    (pad "2" smd roundrect (at 0.625 0) (size 0.55 1) (layers "B.Cu" "B.Paste" "B.Mask") (roundrect_rratio 0.15)
      (net 187 "/HDMI converter/LT9611_VCC33_TX") (pintype "passive"))
  )

  (footprint "sa800u-baseboard-hw-footprints:L_0603_1608Metric" (layer "B.Cu")
    (tedit 5D5D3F54)
    (at 143.8 130.65 180)
    (property "Author" "Antmicro")
    (property "IMax" "")
    (property "ISat" "")
    (property "License" "Apache-2.0")
    (property "MPN" "BRC1608TR35M")
    (property "Manufacturer" "Taiyo Yuden")
    (property "Sheetfile" "hdmi-converter.kicad_sch")
    (property "Sheetname" "HDMI converter")
    (property "Size" "")
    (property "Val" "350n/1.4A")
    (attr smd)
    (fp_text reference "L6" (at -2.53 -0.52) (layer "B.SilkS")
      (effects (font (size 0.7 0.7) (thickness 0.15)) (justify left bottom mirror))
    )
    (fp_text value "L_350n_1.4A_0603" (at 0 -2) (layer "B.Fab")
      (effects (font (size 0.7 0.7) (thickness 0.15)) (justify left bottom mirror))
    )
    (fp_text user "${REFERENCE}" (at -1.9 -3.1) (layer "B.Fab") hide
      (effects (font (size 0.7 0.7) (thickness 0.15)) (justify left bottom mirror))
    )
    (fp_text user "License: Apache-2.0" (at -1.9 -5.75) (layer "B.Fab") hide
      (effects (font (size 0.7 0.7) (thickness 0.15)) (justify left bottom mirror))
    )
    (fp_text user "Author: Antmicro" (at -1.9 -4.4) (layer "B.Fab") hide
      (effects (font (size 0.7 0.7) (thickness 0.15)) (justify left bottom mirror))
    )
    (fp_line (start -0.25 -0.45) (end 0.25 -0.45) (layer "B.SilkS") (width 0.1))
    (fp_line (start -0.25 0.45) (end 0.25 0.45) (layer "B.SilkS") (width 0.1))
    (fp_rect (start -1.15 0.75) (end 1.15 -0.75) (layer "B.CrtYd") (width 0.05) (fill none))
    (fp_rect (start -0.8 0.4) (end 0.8 -0.4) (layer "B.Fab") (width 0.1) (fill none))
    (pad "1" smd roundrect (at -0.625 0 180) (size 0.55 1) (layers "B.Cu" "B.Paste" "B.Mask") (roundrect_rratio 0.15)
      (net 138 "1V2_SYS") (pintype "passive"))
    (pad "2" smd roundrect (at 0.625 0 180) (size 0.55 1) (layers "B.Cu" "B.Paste" "B.Mask") (roundrect_rratio 0.15)
      (net 191 "/HDMI converter/LT9611_VCC12_TX") (pintype "passive"))
  )

  (footprint "sa800u-baseboard-hw-footprints:R_0402_1005Metric" (layer "B.Cu")
    (tedit 5FD9C158)
    (at 144.1 128.15 180)
    (descr "Resistor SMD 0402")
    (tags "resistor SMD 0402")
    (property "Author" "Antmicro")
    (property "License" "Apache-2.0")
    (property "MPN" "CR0402-FX-7681GLF")
    (property "Manufacturer" "Bourns")
    (property "Sheetfile" "hdmi-converter.kicad_sch")
    (property "Sheetname" "HDMI converter")
    (property "Tolerance" "1%")
    (property "Val" "7k68")
    (attr smd)
    (fp_text reference "R22" (at -3.12 -0.3) (layer "B.SilkS")
      (effects (font (size 0.7 0.7) (thickness 0.15)) (justify left bottom mirror))
    )
    (fp_text value "R_7k68_0402" (at 0 -1.4) (layer "B.Fab")
      (effects (font (size 0.7 0.7) (thickness 0.15)) (justify left bottom mirror))
    )
    (fp_text user "License: Apache-2.0" (at -0.95 -5.169) (layer "B.Fab") hide
      (effects (font (size 0.7 0.7) (thickness 0.15)) (justify left bottom mirror))
    )
    (fp_text user "Author: Antmicro" (at -0.95 -4.169) (layer "B.Fab") hide
      (effects (font (size 0.7 0.7) (thickness 0.15)) (justify left bottom mirror))
    )
    (fp_text user "${REFERENCE}" (at -0.95 -3.168) (layer "B.Fab") hide
      (effects (font (size 0.7 0.7) (thickness 0.15)) (justify left bottom mirror))
    )
    (fp_rect (start -0.93 0.47) (end 0.93 -0.47) (layer "B.CrtYd") (width 0.05) (fill none))
    (fp_rect (start -0.5 0.25) (end 0.5 -0.25) (layer "B.Fab") (width 0.15) (fill none))
    (pad "1" smd roundrect (at -0.485 0 180) (size 0.59 0.64) (layers "B.Cu" "B.Paste" "B.Mask") (roundrect_rratio 0.25)
      (net 394 "Net-(R22-Pad1)") (pintype "passive"))
    (pad "2" smd roundrect (at 0.485 0 180) (size 0.59 0.64) (layers "B.Cu" "B.Paste" "B.Mask") (roundrect_rratio 0.25)
      (net 1 "GND") (pintype "passive"))
  )

  (footprint "sa800u-baseboard-hw-footprints:R_0402_1005Metric" (layer "B.Cu")
    (tedit 5FD9C158)
    (at 154 144.75 -90)
    (descr "Resistor SMD 0402")
    (tags "resistor SMD 0402")
    (property "Author" "Antmicro")
    (property "Current" "1A")
    (property "DNP" "DNP")
    (property "License" "Apache-2.0")
    (property "MPN" "ERJ2GE0R00X")
    (property "Manufacturer" "Panasonic")
    (property "Sheetfile" "sa800u-baseboard-hw.kicad_sch")
    (property "Sheetname" "")
    (property "Tolerance" "")
    (property "Val" "0R")
    (attr exclude_from_pos_files)
    (fp_text reference "R2" (at -0.78 0.64 90) (layer "B.SilkS")
      (effects (font (size 0.7 0.7) (thickness 0.15)) (justify left bottom mirror))
    )
    (fp_text value "R_0R_0402" (at 0 -1.4 90) (layer "B.Fab")
      (effects (font (size 0.7 0.7) (thickness 0.15)) (justify left bottom mirror))
    )
    (fp_text user "${REFERENCE}" (at -0.95 -3.168 90) (layer "B.Fab") hide
      (effects (font (size 0.7 0.7) (thickness 0.15)) (justify left bottom mirror))
    )
    (fp_text user "License: Apache-2.0" (at -0.95 -5.169 90) (layer "B.Fab") hide
      (effects (font (size 0.7 0.7) (thickness 0.15)) (justify left bottom mirror))
    )
    (fp_text user "Author: Antmicro" (at -0.95 -4.169 90) (layer "B.Fab") hide
      (effects (font (size 0.7 0.7) (thickness 0.15)) (justify left bottom mirror))
    )
    (fp_rect (start -0.93 0.47) (end 0.93 -0.47) (layer "B.CrtYd") (width 0.05) (fill none))
    (fp_rect (start -0.5 0.25) (end 0.5 -0.25) (layer "B.Fab") (width 0.15) (fill none))
    (pad "1" smd roundrect (at -0.485 0 270) (size 0.59 0.64) (layers "B.Cu" "B.Paste" "B.Mask") (roundrect_rratio 0.25)
      (net 1 "GND") (pintype "passive"))
    (pad "2" smd roundrect (at 0.485 0 270) (size 0.59 0.64) (layers "B.Cu" "B.Paste" "B.Mask") (roundrect_rratio 0.25)
      (net 37 "Net-(R2-Pad2)") (pintype "passive"))
  )

  (footprint "sa800u-baseboard-hw-footprints:PowerPak-1212" (layer "B.Cu")
    (tedit 625E61BE)
    (at 81.9 136.75 180)
    (property "Author" "Antmicro")
    (property "License" "Apache-2.0")
    (property "MPN" "SI7223DN-T1-GE3")
    (property "Manufacturer" "Vishay")
    (property "Sheetfile" "psu.kicad_sch")
    (property "Sheetname" "PSU")
    (attr smd)
    (fp_text reference "Q11" (at 0 2.5) (layer "B.SilkS")
      (effects (font (size 0.65 0.65) (thickness 0.15)) (justify mirror))
    )
    (fp_text value "Si7223DN" (at 0 -3) (layer "B.Fab") hide
      (effects (font (size 0.65 0.65) (thickness 0.15)) (justify mirror))
    )
    (fp_text user "Author: Antmicro" (at -2.667 -7.4) (layer "B.Fab") hide
      (effects (font (size 0.7 0.7) (thickness 0.15)) (justify left bottom mirror))
    )
    (fp_text user "${REFERENCE}" (at 0 0) (layer "B.Fab") hide
      (effects (font (size 0.65 0.65) (thickness 0.15)) (justify mirror))
    )
    (fp_text user "License: Apache-2.0" (at -2.667 -8.599) (layer "B.Fab") hide
      (effects (font (size 0.7 0.7) (thickness 0.15)) (justify left bottom mirror))
    )
    (fp_poly (pts
        (xy 1.699 -1.178)
        (xy 1.699 -0.771)
        (xy 1.14 -0.771)
        (xy 1.14 -0.528)
        (xy 1.699 -0.528)
        (xy 1.699 -0.121)
        (xy 1.14 -0.121)
        (xy 1.14 -0.174)
        (xy -0.387 -0.174)
        (xy -0.387 -1.119)
        (xy -0.386607 -1.698508)
        (xy -0.047 -1.699)
        (xy -0.047 -1.119)
        (xy 1.14 -1.119)
        (xy 1.14 -1.178)
      ) (layer "B.Paste") (width 0.1) (fill solid))
    (fp_poly (pts
        (xy 1.699 0.122)
        (xy 1.699 0.529)
        (xy 1.14 0.529)
        (xy 1.14 0.772)
        (xy 1.699 0.772)
        (xy 1.699 1.179)
        (xy 1.14 1.179)
        (xy 1.14 1.12)
        (xy -0.047 1.12)
        (xy -0.047 1.7)
        (xy -0.387 1.7)
        (xy -0.387 1.12)
        (xy -0.386607 0.174507)
        (xy 1.14 0.175)
        (xy 1.14 0.122)
      ) (layer "B.Paste") (width 0.1) (fill solid))
    (fp_line (start 1.701 1.702) (end 1.701 1.511) (layer "B.SilkS") (width 0.15))
    (fp_line (start 1.701 -1.701) (end 0.2 -1.7) (layer "B.SilkS") (width 0.15))
    (fp_line (start -0.6 -1.7) (end -1.702 -1.701) (layer "B.SilkS") (width 0.15))
    (fp_line (start 0.2 1.702) (end 1.701 1.702) (layer "B.SilkS") (width 0.15))
    (fp_line (start -1.702 -1.701) (end -1.702 -1.51) (layer "B.SilkS") (width 0.15))
    (fp_line (start 1.701 -1.51) (end 1.701 -1.701) (layer "B.SilkS") (width 0.15))
    (fp_line (start -1.702 1.702) (end -0.6 1.7) (layer "B.SilkS") (width 0.15))
    (fp_line (start -1.702 1.511) (end -1.702 1.702) (layer "B.SilkS") (width 0.15))
    (fp_circle (center -1.85 1.3) (end -1.8 1.3) (layer "B.SilkS") (width 0.15) (fill solid))
    (fp_poly (pts
        (xy 1.699 1.179)
        (xy 1.14 1.179)
        (xy 1.14 1.12)
        (xy -0.047 1.12)
        (xy -0.047 1.7)
        (xy -0.387 1.7)
        (xy -0.387 0.175)
        (xy 1.14 0.175)
        (xy 1.14 0.122)
        (xy 1.699 0.122)
        (xy 1.699 0.529)
        (xy 1.14 0.529)
        (xy 1.14 0.772)
        (xy 1.699 0.772)
      ) (layer "B.Mask") (width 0.1) (fill solid))
    (fp_poly (pts
        (xy -0.387 -0.174)
        (xy -0.387 -1.699)
        (xy -0.047 -1.699)
        (xy -0.047 -1.119)
        (xy 1.14 -1.119)
        (xy 1.14 -1.178)
        (xy 1.699 -1.178)
        (xy 1.699 -0.771)
        (xy 1.14 -0.771)
        (xy 1.14 -0.528)
        (xy 1.699 -0.528)
        (xy 1.699 -0.121)
        (xy 1.14 -0.121)
        (xy 1.14 -0.174)
      ) (layer "B.Mask") (width 0.1) (fill solid))
    (fp_line (start 1.95 -1.95) (end -1.96 -1.95) (layer "B.CrtYd") (width 0.05))
    (fp_line (start 1.95 1.96) (end 1.95 -1.95) (layer "B.CrtYd") (width 0.05))
    (fp_line (start -1.96 1.96) (end 1.95 1.96) (layer "B.CrtYd") (width 0.05))
    (fp_line (start -1.96 -1.95) (end -1.96 1.96) (layer "B.CrtYd") (width 0.05))
    (fp_line (start -1.575 -1.574) (end -1.575 1.575) (layer "B.Fab") (width 0.15))
    (fp_line (start -1.575 1.575) (end 1.574 1.575) (layer "B.Fab") (width 0.15))
    (fp_line (start 1.574 1.575) (end 1.574 -1.574) (layer "B.Fab") (width 0.15))
    (fp_line (start 1.574 -1.574) (end -1.575 -1.574) (layer "B.Fab") (width 0.15))
    (fp_circle (center 0.99 0.975) (end 0.914 0.975) (layer "B.Fab") (width 0.15) (fill none))
    (pad "1" smd rect (at -1.446 0.975 180) (size 0.508 0.4064) (layers "B.Cu" "B.Paste" "B.Mask")
      (net 158 "/PSU/VS2") (pinfunction "S1") (pintype "passive"))
    (pad "2" smd rect (at -1.446 0.325 180) (size 0.508 0.4064) (layers "B.Cu" "B.Paste" "B.Mask")
      (net 355 "/PSU/G2") (pinfunction "G1") (pintype "passive"))
    (pad "3" smd rect (at -1.446 -0.324 180) (size 0.508 0.4064) (layers "B.Cu" "B.Paste" "B.Mask")
      (net 158 "/PSU/VS2") (pinfunction "S2") (pintype "passive"))
    (pad "4" smd rect (at -1.446 -0.974 180) (size 0.508 0.4064) (layers "B.Cu" "B.Paste" "B.Mask")
      (net 355 "/PSU/G2") (pinfunction "G2") (pintype "passive"))
    (pad "5" smd rect (at 1.42 -0.974 180) (size 0.5588 0.4064) (layers "B.Cu" "B.Paste" "B.Mask")
      (net 142 "PD_VDD") (pinfunction "D2") (pintype "passive"))
    (pad "6" smd custom (at 1.42 -0.324 180) (size 0.5588 0.4064) (layers "B.Cu" "B.Paste" "B.Mask")
      (net 142 "PD_VDD") (pinfunction "D2") (pintype "passive") (zone_connect 2)
      (options (clearance outline) (anchor rect))
      (primitives
        (gr_poly (pts
            (xy 0.2794 -0.853186)
            (xy 0.2794 -0.446786)
            (xy -0.2794 -0.446786)
            (xy -0.2794 -0.2032)
            (xy 0.2794 -0.2032)
            (xy 0.2794 0.2032)
            (xy -0.2794 0.2032)
            (xy -0.279407 0.150493)
            (xy -1.806607 0.150493)
            (xy -1.806607 -1.374508)
            (xy -1.466602 -1.374508)
            (xy -1.466602 -0.794499)
            (xy -0.279407 -0.794507)
            (xy -0.2794 -0.853186)
          ) (width 0.1) (fill yes))
      ))
    (pad "7" smd custom (at 1.42 0.325 180) (size 0.5588 0.4064) (layers "B.Cu" "B.Paste" "B.Mask")
      (net 74 "VDD") (pinfunction "D1") (pintype "passive") (zone_connect 2)
      (options (clearance outline) (anchor rect))
      (primitives
        (gr_poly (pts
            (xy 0.2794 0.446786)
            (xy 0.2794 0.853186)
            (xy -0.2794 0.853186)
            (xy -0.279407 0.794507)
            (xy -1.466602 0.794499)
            (xy -1.466602 1.374508)
            (xy -1.806607 1.374508)
            (xy -1.806607 -0.150493)
            (xy -0.279407 -0.150493)
            (xy -0.2794 -0.2032)
            (xy 0.2794 -0.2032)
            (xy 0.2794 0.2032)
            (xy -0.2794 0.2032)
            (xy -0.2794 0.446786)
          ) (width 0.1) (fill yes))
      ))
    (pad "8" smd rect (at 1.42 0.975 180) (size 0.5588 0.4064) (layers "B.Cu" "B.Paste" "B.Mask")
      (net 74 "VDD") (pinfunction "D1") (pintype "passive"))
  )

  (footprint "sa800u-baseboard-hw-footprints:QFN-32-1EP_4x4mm_P0.4mm" (layer "B.Cu")
    (tedit 619D0372)
    (at 97.171211 103.09844)
    (property "Author" "Antmicro")
    (property "License" "Apache-2.0")
    (property "MPN" "RTL8111H")
    (property "Manufacturer" "Realtek")
    (property "Sheetfile" "ethernet-controller.kicad_sch")
    (property "Sheetname" "Ethernet Controller")
    (attr smd)
    (fp_text reference "U1" (at 3.248789 -2.36844 180) (layer "B.SilkS")
      (effects (font (size 0.7 0.7) (thickness 0.15)) (justify left bottom mirror))
    )
    (fp_text value "RTL8111H" (at 0 -3.5 180) (layer "B.Fab")
      (effects (font (size 0.7 0.7) (thickness 0.15)) (justify left bottom mirror))
    )
    (fp_text user "Author: Antmicro" (at -2.851 -7.888 180) (layer "B.Fab") hide
      (effects (font (size 0.7 0.7) (thickness 0.15)) (justify left bottom mirror))
    )
    (fp_text user "${REFERENCE}" (at -2.851 -6.688 180) (layer "B.Fab") hide
      (effects (font (size 0.7 0.7) (thickness 0.15)) (justify left bottom mirror))
    )
    (fp_text user "License: Apache-2.0" (at -2.851 -9.088 180) (layer "B.Fab") hide
      (effects (font (size 0.7 0.7) (thickness 0.15)) (justify left bottom mirror))
    )
    (fp_poly (pts
        (xy -0.919 0.918)
        (xy 0.917 0.918)
        (xy 0.917 -0.918)
        (xy -0.919 -0.918)
      ) (layer "B.Paste") (width 0.01) (fill solid))
    (fp_line (start -1.69 2) (end -2 2) (layer "B.SilkS") (width 0.15))
    (fp_line (start 1.999 2) (end 1.689 2) (layer "B.SilkS") (width 0.15))
    (fp_line (start -2 2) (end -2 1.69) (layer "B.SilkS") (width 0.15))
    (fp_line (start -2 -1.689) (end -2 -1.999) (layer "B.SilkS") (width 0.15))
    (fp_line (start 1.999 -1.999) (end 1.999 -1.689) (layer "B.SilkS") (width 0.15))
    (fp_line (start 1.999 1.69) (end 1.999 2) (layer "B.SilkS") (width 0.15))
    (fp_line (start 1.689 -1.999) (end 1.999 -1.999) (layer "B.SilkS") (width 0.15))
    (fp_line (start -2 -1.999) (end -1.69 -1.999) (layer "B.SilkS") (width 0.15))
    (fp_circle (center -2.3 1.7) (end -2.25 1.7) (layer "B.SilkS") (width 0.15) (fill solid))
    (fp_line (start 2.24 -1.75) (end 2.24 -2.24) (layer "B.CrtYd") (width 0.05))
    (fp_line (start -1.76 -2.24) (end -2.25 -2.24) (layer "B.CrtYd") (width 0.05))
    (fp_line (start -2.25 -2.24) (end -2.25 -1.75) (layer "B.CrtYd") (width 0.05))
    (fp_line (start 1.75 2.61) (end 1.75 2.25) (layer "B.CrtYd") (width 0.05))
    (fp_line (start 1.75 -2.24) (end 1.75 -2.6) (layer "B.CrtYd") (width 0.05))
    (fp_line (start -1.76 2.61) (end 1.75 2.61) (layer "B.CrtYd") (width 0.05))
    (fp_line (start -2.25 2.25) (end -1.76 2.25) (layer "B.CrtYd") (width 0.05))
    (fp_line (start 2.24 -2.24) (end 1.75 -2.24) (layer "B.CrtYd") (width 0.05))
    (fp_line (start 1.75 -2.6) (end -1.76 -2.6) (layer "B.CrtYd") (width 0.05))
    (fp_line (start 1.75 2.25) (end 2.24 2.25) (layer "B.CrtYd") (width 0.05))
    (fp_line (start -1.76 2.25) (end -1.76 2.61) (layer "B.CrtYd") (width 0.05))
    (fp_line (start 2.24 2.25) (end 2.24 1.76) (layer "B.CrtYd") (width 0.05))
    (fp_line (start -2.61 1.76) (end -2.25 1.76) (layer "B.CrtYd") (width 0.05))
    (fp_line (start 2.24 1.76) (end 2.6 1.76) (layer "B.CrtYd") (width 0.05))
    (fp_line (start 2.6 -1.75) (end 2.24 -1.75) (layer "B.CrtYd") (width 0.05))
    (fp_line (start 2.6 1.76) (end 2.6 -1.75) (layer "B.CrtYd") (width 0.05))
    (fp_line (start -1.76 -2.6) (end -1.76 -2.24) (layer "B.CrtYd") (width 0.05))
    (fp_line (start -2.25 -1.75) (end -2.61 -1.75) (layer "B.CrtYd") (width 0.05))
    (fp_line (start -2.61 -1.75) (end -2.61 1.76) (layer "B.CrtYd") (width 0.05))
    (fp_line (start -2.25 1.76) (end -2.25 2.25) (layer "B.CrtYd") (width 0.05))
    (fp_line (start 1.999 -1.999) (end -2 -1.999) (layer "B.Fab") (width 0.15))
    (fp_line (start -2 2) (end 1.999 2) (layer "B.Fab") (width 0.15))
    (fp_line (start -2 -1.999) (end -2 2) (layer "B.Fab") (width 0.15))
    (fp_line (start 1.999 2) (end 1.999 -1.999) (layer "B.Fab") (width 0.15))
    (fp_circle (center -1.45 1.371) (end -1.351 1.371) (layer "B.Fab") (width 0.15) (fill none))
    (pad "1" smd roundrect (at -2.005 1.4) (size 0.71 0.22) (layers "B.Cu" "B.Paste" "B.Mask") (roundrect_rratio 0.03)
      (net 255 "/Ethernet Controller/LAN0_MDI0_P") (pinfunction "MDIP0") (pintype "bidirectional"))
    (pad "2" smd roundrect (at -2.005 1) (size 0.71 0.22) (layers "B.Cu" "B.Paste" "B.Mask") (roundrect_rratio 0.03)
      (net 254 "/Ethernet Controller/LAN0_MDI0_N") (pinfunction "MDIN0") (pintype "bidirectional"))
    (pad "3" smd roundrect (at -2.005 0.6) (size 0.71 0.22) (layers "B.Cu" "B.Paste" "B.Mask") (roundrect_rratio 0.03)
      (net 181 "/Ethernet Controller/ETH_1V0") (pinfunction "AVDD10") (pintype "power_in"))
    (pad "4" smd roundrect (at -2.005 0.201) (size 0.71 0.22) (layers "B.Cu" "B.Paste" "B.Mask") (roundrect_rratio 0.03)
      (net 257 "/Ethernet Controller/LAN0_MDI1_P") (pinfunction "MDIP1") (pintype "bidirectional"))
    (pad "5" smd roundrect (at -2.005 -0.2) (size 0.71 0.22) (layers "B.Cu" "B.Paste" "B.Mask") (roundrect_rratio 0.03)
      (net 256 "/Ethernet Controller/LAN0_MDI1_N") (pinfunction "MDIN1") (pintype "bidirectional"))
    (pad "6" smd roundrect (at -2.005 -0.599) (size 0.71 0.22) (layers "B.Cu" "B.Paste" "B.Mask") (roundrect_rratio 0.03)
      (net 259 "/Ethernet Controller/LAN0_MDI2_P") (pinfunction "MDIP2") (pintype "bidirectional"))
    (pad "7" smd roundrect (at -2.005 -0.999) (size 0.71 0.22) (layers "B.Cu" "B.Paste" "B.Mask") (roundrect_rratio 0.03)
      (net 258 "/Ethernet Controller/LAN0_MDI2_N") (pinfunction "MDIN2") (pintype "bidirectional"))
    (pad "8" smd roundrect (at -2.005 -1.399) (size 0.71 0.22) (layers "B.Cu" "B.Paste" "B.Mask") (roundrect_rratio 0.03)
      (net 181 "/Ethernet Controller/ETH_1V0") (pinfunction "AVDD10_1") (pintype "power_in"))
    (pad "9" smd roundrect (at -1.4 -2.004) (size 0.22 0.71) (layers "B.Cu" "B.Paste" "B.Mask") (roundrect_rratio 0.03)
      (net 261 "/Ethernet Controller/LAN0_MDI3_P") (pinfunction "MDIP3") (pintype "bidirectional"))
    (pad "10" smd roundrect (at -1 -2.004) (size 0.22 0.71) (layers "B.Cu" "B.Paste" "B.Mask") (roundrect_rratio 0.03)
      (net 260 "/Ethernet Controller/LAN0_MDI3_N") (pinfunction "MDIN3") (pintype "bidirectional"))
    (pad "11" smd roundrect (at -0.6 -2.004) (size 0.22 0.71) (layers "B.Cu" "B.Paste" "B.Mask") (roundrect_rratio 0.03)
      (net 177 "/Ethernet Controller/ETH_3V3") (pinfunction "AVDD33_1") (pintype "power_in"))
    (pad "12" smd roundrect (at -0.201 -2.004) (size 0.22 0.71) (layers "B.Cu" "B.Paste" "B.Mask") (roundrect_rratio 0.03)
      (net 162 "PCIE1_CLKREQ_N") (pinfunction "CLKREQB") (pintype "open_collector"))
    (pad "13" smd roundrect (at 0.2 -2.004) (size 0.22 0.71) (layers "B.Cu" "B.Paste" "B.Mask") (roundrect_rratio 0.03)
      (net 49 "PCIE1_TX_P") (pinfunction "HSIP") (pintype "input"))
    (pad "14" smd roundrect (at 0.599 -2.004) (size 0.22 0.71) (layers "B.Cu" "B.Paste" "B.Mask") (roundrect_rratio 0.03)
      (net 48 "PCIE1_TX_N") (pinfunction "HSIN") (pintype "input"))
    (pad "15" smd roundrect (at 0.999 -2.004) (size 0.22 0.71) (layers "B.Cu" "B.Paste" "B.Mask") (roundrect_rratio 0.03)
      (net 47 "PCIE1_REFCLK_P") (pinfunction "REFCLK_P") (pintype "input"))
    (pad "16" smd roundrect (at 1.399 -2.004) (size 0.22 0.71) (layers "B.Cu" "B.Paste" "B.Mask") (roundrect_rratio 0.03)
      (net 46 "PCIE1_REFCLK_N") (pinfunction "REFCLK_N") (pintype "input"))
    (pad "17" smd roundrect (at 2.004 -1.399) (size 0.71 0.22) (layers "B.Cu" "B.Paste" "B.Mask") (roundrect_rratio 0.03)
      (net 179 "/Ethernet Controller/PCIE1_RX_C_P") (pinfunction "HSOP") (pintype "output"))
    (pad "18" smd roundrect (at 2.004 -0.999) (size 0.71 0.22) (layers "B.Cu" "B.Paste" "B.Mask") (roundrect_rratio 0.03)
      (net 180 "/Ethernet Controller/PCIE1_RX_C_N") (pinfunction "HSON") (pintype "output"))
    (pad "19" smd roundrect (at 2.004 -0.599) (size 0.71 0.22) (layers "B.Cu" "B.Paste" "B.Mask") (roundrect_rratio 0.03)
      (net 163 "PCIE1_RST_N") (pinfunction "PERSTB") (pintype "input"))
    (pad "20" smd roundrect (at 2.004 -0.2) (size 0.71 0.22) (layers "B.Cu" "B.Paste" "B.Mask") (roundrect_rratio 0.03)
      (net 286 "/Ethernet Controller/ETH_ISOLATEB") (pinfunction "ISOLATEB") (pintype "open_collector"))
    (pad "21" smd roundrect (at 2.004 0.201) (size 0.71 0.22) (layers "B.Cu" "B.Paste" "B.Mask") (roundrect_rratio 0.03)
      (net 161 "PCIE1_WAKE_N") (pinfunction "LANWAKEB") (pintype "output"))
    (pad "22" smd roundrect (at 2.004 0.6) (size 0.71 0.22) (layers "B.Cu" "B.Paste" "B.Mask") (roundrect_rratio 0.03)
      (net 181 "/Ethernet Controller/ETH_1V0") (pinfunction "DVDD10") (pintype "power_in"))
    (pad "23" smd roundrect (at 2.004 1) (size 0.71 0.22) (layers "B.Cu" "B.Paste" "B.Mask") (roundrect_rratio 0.03)
      (net 177 "/Ethernet Controller/ETH_3V3") (pinfunction "VDDREG") (pintype "power_in"))
    (pad "24" smd roundrect (at 2.004 1.4) (size 0.71 0.22) (layers "B.Cu" "B.Paste" "B.Mask") (roundrect_rratio 0.03)
      (net 178 "/Ethernet Controller/REG_1V0") (pinfunction "REGOUT") (pintype "output"))
    (pad "25" smd roundrect (at 1.399 2.005) (size 0.22 0.71) (layers "B.Cu" "B.Paste" "B.Mask") (roundrect_rratio 0.03)
      (net 263 "/Ethernet Controller/ETH_LED2") (pinfunction "LED2") (pintype "output"))
    (pad "26" smd roundrect (at 0.999 2.005) (size 0.22 0.71) (layers "B.Cu" "B.Paste" "B.Mask") (roundrect_rratio 0.03)
      (net 469 "unconnected-(U1-Pad26)") (pinfunction "LED1/GPO") (pintype "output+no_connect"))
    (pad "27" smd roundrect (at 0.599 2.005) (size 0.22 0.71) (layers "B.Cu" "B.Paste" "B.Mask") (roundrect_rratio 0.03)
      (net 262 "/Ethernet Controller/ETH_LED0") (pinfunction "LED0") (pintype "output"))
    (pad "28" smd roundrect (at 0.2 2.005) (size 0.22 0.71) (layers "B.Cu" "B.Paste" "B.Mask") (roundrect_rratio 0.03)
      (net 182 "/Ethernet Controller/XTAL1") (pinfunction "CKXTAL1") (pintype "input"))
    (pad "29" smd roundrect (at -0.201 2.005) (size 0.22 0.71) (layers "B.Cu" "B.Paste" "B.Mask") (roundrect_rratio 0.03)
      (net 183 "/Ethernet Controller/XTAL2") (pinfunction "CKXTAL2") (pintype "input"))
    (pad "30" smd roundrect (at -0.6 2.005) (size 0.22 0.71) (layers "B.Cu" "B.Paste" "B.Mask") (roundrect_rratio 0.03)
      (net 181 "/Ethernet Controller/ETH_1V0") (pinfunction "AVD10_2") (pintype "power_in"))
    (pad "31" smd roundrect (at -1 2.005) (size 0.22 0.71) (layers "B.Cu" "B.Paste" "B.Mask") (roundrect_rratio 0.03)
      (net 393 "Net-(R11-Pad1)") (pinfunction "RSET") (pintype "input"))
    (pad "32" smd roundrect (at -1.4 2.005) (size 0.22 0.71) (layers "B.Cu" "B.Paste" "B.Mask") (roundrect_rratio 0.03)
      (net 177 "/Ethernet Controller/ETH_3V3") (pinfunction "AVDD33_2") (pintype "input"))
    (pad "33" smd rect (at 0 0) (size 2.8 2.8) (layers "B.Cu" "B.Mask")
      (net 1 "GND") (pinfunction "GND") (pintype "power_in"))
  )

  (footprint "sa800u-baseboard-hw-footprints:R_0402_1005Metric" (layer "B.Cu")
    (tedit 5FD9C158)
    (at 101.549173 102.257734 180)
    (descr "Resistor SMD 0402")
    (tags "resistor SMD 0402")
    (property "Author" "Antmicro")
    (property "License" "Apache-2.0")
    (property "MPN" "CR0402-FX-1001GLF")
    (property "Manufacturer" "Bourns")
    (property "Sheetfile" "ethernet-controller.kicad_sch")
    (property "Sheetname" "Ethernet Controller")
    (property "Tolerance" "1%")
    (property "Val" "1k")
    (attr smd)
    (fp_text reference "R9" (at -2.420827 -0.272266) (layer "B.SilkS")
      (effects (font (size 0.7 0.7) (thickness 0.15)) (justify left bottom mirror))
    )
    (fp_text value "R_1k_0402" (at 0 -1.4) (layer "B.Fab")
      (effects (font (size 0.7 0.7) (thickness 0.15)) (justify left bottom mirror))
    )
    (fp_text user "License: Apache-2.0" (at -0.95 -5.169) (layer "B.Fab") hide
      (effects (font (size 0.7 0.7) (thickness 0.15)) (justify left bottom mirror))
    )
    (fp_text user "Author: Antmicro" (at -0.95 -4.169) (layer "B.Fab") hide
      (effects (font (size 0.7 0.7) (thickness 0.15)) (justify left bottom mirror))
    )
    (fp_text user "${REFERENCE}" (at -0.95 -3.168) (layer "B.Fab") hide
      (effects (font (size 0.7 0.7) (thickness 0.15)) (justify left bottom mirror))
    )
    (fp_rect (start -0.93 0.47) (end 0.93 -0.47) (layer "B.CrtYd") (width 0.05) (fill none))
    (fp_rect (start -0.5 0.25) (end 0.5 -0.25) (layer "B.Fab") (width 0.15) (fill none))
    (pad "1" smd roundrect (at -0.485 0 180) (size 0.59 0.64) (layers "B.Cu" "B.Paste" "B.Mask") (roundrect_rratio 0.25)
      (net 131 "3V3_SYS") (pintype "passive"))
    (pad "2" smd roundrect (at 0.485 0 180) (size 0.59 0.64) (layers "B.Cu" "B.Paste" "B.Mask") (roundrect_rratio 0.25)
      (net 286 "/Ethernet Controller/ETH_ISOLATEB") (pintype "passive"))
  )

  (footprint "sa800u-baseboard-hw-footprints:R_0402_1005Metric" (layer "B.Cu")
    (tedit 5FD9C158)
    (at 101.549173 101.257734 180)
    (descr "Resistor SMD 0402")
    (tags "resistor SMD 0402")
    (property "Author" "Antmicro")
    (property "License" "Apache-2.0")
    (property "MPN" "CR0402-FX-1002GLF")
    (property "Manufacturer" "Bourns")
    (property "Sheetfile" "ethernet-controller.kicad_sch")
    (property "Sheetname" "Ethernet Controller")
    (property "Tolerance" "1%")
    (property "Val" "10k")
    (attr smd)
    (fp_text reference "R8" (at -2.350827 -0.332266) (layer "B.SilkS")
      (effects (font (size 0.7 0.7) (thickness 0.15)) (justify left bottom mirror))
    )
    (fp_text value "R_10k_0402" (at 0 -1.4) (layer "B.Fab")
      (effects (font (size 0.7 0.7) (thickness 0.15)) (justify left bottom mirror))
    )
    (fp_text user "Author: Antmicro" (at -0.95 -4.169) (layer "B.Fab") hide
      (effects (font (size 0.7 0.7) (thickness 0.15)) (justify left bottom mirror))
    )
    (fp_text user "License: Apache-2.0" (at -0.95 -5.169) (layer "B.Fab") hide
      (effects (font (size 0.7 0.7) (thickness 0.15)) (justify left bottom mirror))
    )
    (fp_text user "${REFERENCE}" (at -0.95 -3.168) (layer "B.Fab") hide
      (effects (font (size 0.7 0.7) (thickness 0.15)) (justify left bottom mirror))
    )
    (fp_rect (start -0.93 0.47) (end 0.93 -0.47) (layer "B.CrtYd") (width 0.05) (fill none))
    (fp_rect (start -0.5 0.25) (end 0.5 -0.25) (layer "B.Fab") (width 0.15) (fill none))
    (pad "1" smd roundrect (at -0.485 0 180) (size 0.59 0.64) (layers "B.Cu" "B.Paste" "B.Mask") (roundrect_rratio 0.25)
      (net 132 "VREG_S4A_1V8") (pintype "passive"))
    (pad "2" smd roundrect (at 0.485 0 180) (size 0.59 0.64) (layers "B.Cu" "B.Paste" "B.Mask") (roundrect_rratio 0.25)
      (net 163 "PCIE1_RST_N") (pintype "passive"))
  )

  (footprint "sa800u-baseboard-hw-footprints:R_0402_1005Metric" (layer "B.Cu")
    (tedit 5FD9C158)
    (at 96.8 98 -90)
    (descr "Resistor SMD 0402")
    (tags "resistor SMD 0402")
    (property "Author" "Antmicro")
    (property "License" "Apache-2.0")
    (property "MPN" "CR0402-FX-1002GLF")
    (property "Manufacturer" "Bourns")
    (property "Sheetfile" "ethernet-controller.kicad_sch")
    (property "Sheetname" "Ethernet Controller")
    (property "Tolerance" "1%")
    (property "Val" "10k")
    (attr smd)
    (fp_text reference "R6" (at -0.78 -1.36 90) (layer "B.SilkS")
      (effects (font (size 0.7 0.7) (thickness 0.15)) (justify left bottom mirror))
    )
    (fp_text value "R_10k_0402" (at 0 -1.4 90) (layer "B.Fab")
      (effects (font (size 0.7 0.7) (thickness 0.15)) (justify left bottom mirror))
    )
    (fp_text user "Author: Antmicro" (at -0.95 -4.169 90) (layer "B.Fab") hide
      (effects (font (size 0.7 0.7) (thickness 0.15)) (justify left bottom mirror))
    )
    (fp_text user "License: Apache-2.0" (at -0.95 -5.169 90) (layer "B.Fab") hide
      (effects (font (size 0.7 0.7) (thickness 0.15)) (justify left bottom mirror))
    )
    (fp_text user "${REFERENCE}" (at -0.95 -3.168 90) (layer "B.Fab") hide
      (effects (font (size 0.7 0.7) (thickness 0.15)) (justify left bottom mirror))
    )
    (fp_rect (start -0.93 0.47) (end 0.93 -0.47) (layer "B.CrtYd") (width 0.05) (fill none))
    (fp_rect (start -0.5 0.25) (end 0.5 -0.25) (layer "B.Fab") (width 0.15) (fill none))
    (pad "1" smd roundrect (at -0.485 0 270) (size 0.59 0.64) (layers "B.Cu" "B.Paste" "B.Mask") (roundrect_rratio 0.25)
      (net 132 "VREG_S4A_1V8") (pintype "passive"))
    (pad "2" smd roundrect (at 0.485 0 270) (size 0.59 0.64) (layers "B.Cu" "B.Paste" "B.Mask") (roundrect_rratio 0.25)
      (net 162 "PCIE1_CLKREQ_N") (pintype "passive"))
  )

  (footprint "sa800u-baseboard-hw-footprints:R_0402_1005Metric" (layer "B.Cu")
    (tedit 5FD9C158)
    (at 93.749174 106.957733 -90)
    (descr "Resistor SMD 0402")
    (tags "resistor SMD 0402")
    (property "Author" "Antmicro")
    (property "License" "Apache-2.0")
    (property "MPN" "CR0402-FX-2491GLF")
    (property "Manufacturer" "Bourns")
    (property "Sheetfile" "ethernet-controller.kicad_sch")
    (property "Sheetname" "Ethernet Controller")
    (property "Tolerance" "1%")
    (property "Val" "2k49")
    (attr smd)
    (fp_text reference "R11" (at 0 0.7 90) (layer "B.SilkS")
      (effects (font (size 0.7 0.7) (thickness 0.15)) (justify left bottom mirror))
    )
    (fp_text value "R_2k49_0402" (at 0 -1.4 90) (layer "B.Fab")
      (effects (font (size 0.7 0.7) (thickness 0.15)) (justify left bottom mirror))
    )
    (fp_text user "License: Apache-2.0" (at -0.95 -5.169 90) (layer "B.Fab") hide
      (effects (font (size 0.7 0.7) (thickness 0.15)) (justify left bottom mirror))
    )
    (fp_text user "${REFERENCE}" (at -0.95 -3.168 90) (layer "B.Fab") hide
      (effects (font (size 0.7 0.7) (thickness 0.15)) (justify left bottom mirror))
    )
    (fp_text user "Author: Antmicro" (at -0.95 -4.169 90) (layer "B.Fab") hide
      (effects (font (size 0.7 0.7) (thickness 0.15)) (justify left bottom mirror))
    )
    (fp_rect (start -0.93 0.47) (end 0.93 -0.47) (layer "B.CrtYd") (width 0.05) (fill none))
    (fp_rect (start -0.5 0.25) (end 0.5 -0.25) (layer "B.Fab") (width 0.15) (fill none))
    (pad "1" smd roundrect (at -0.485 0 270) (size 0.59 0.64) (layers "B.Cu" "B.Paste" "B.Mask") (roundrect_rratio 0.25)
      (net 393 "Net-(R11-Pad1)") (pintype "passive"))
    (pad "2" smd roundrect (at 0.485 0 270) (size 0.59 0.64) (layers "B.Cu" "B.Paste" "B.Mask") (roundrect_rratio 0.25)
      (net 1 "GND") (pintype "passive"))
  )

  (footprint "sa800u-baseboard-hw-footprints:R_0402_1005Metric" (layer "B.Cu")
    (tedit 5FD9C158)
    (at 101.549174 103.257734 180)
    (descr "Resistor SMD 0402")
    (tags "resistor SMD 0402")
    (property "Author" "Antmicro")
    (property "License" "Apache-2.0")
    (property "MPN" "CR0402-FX-1001GLF")
    (property "Manufacturer" "Bourns")
    (property "Sheetfile" "ethernet-controller.kicad_sch")
    (property "Sheetname" "Ethernet Controller")
    (property "Tolerance" "1%")
    (property "Val" "1k")
    (attr smd)
    (fp_text reference "R7" (at -2.420827 -0.272266) (layer "B.SilkS")
      (effects (font (size 0.7 0.7) (thickness 0.15)) (justify left bottom mirror))
    )
    (fp_text value "R_1k_0402" (at 0 -1.4) (layer "B.Fab")
      (effects (font (size 0.7 0.7) (thickness 0.15)) (justify left bottom mirror))
    )
    (fp_text user "License: Apache-2.0" (at -0.95 -5.169) (layer "B.Fab") hide
      (effects (font (size 0.7 0.7) (thickness 0.15)) (justify left bottom mirror))
    )
    (fp_text user "${REFERENCE}" (at -0.95 -3.168) (layer "B.Fab") hide
      (effects (font (size 0.7 0.7) (thickness 0.15)) (justify left bottom mirror))
    )
    (fp_text user "Author: Antmicro" (at -0.95 -4.169) (layer "B.Fab") hide
      (effects (font (size 0.7 0.7) (thickness 0.15)) (justify left bottom mirror))
    )
    (fp_rect (start -0.93 0.47) (end 0.93 -0.47) (layer "B.CrtYd") (width 0.05) (fill none))
    (fp_rect (start -0.5 0.25) (end 0.5 -0.25) (layer "B.Fab") (width 0.15) (fill none))
    (pad "1" smd roundrect (at -0.485 0 180) (size 0.59 0.64) (layers "B.Cu" "B.Paste" "B.Mask") (roundrect_rratio 0.25)
      (net 132 "VREG_S4A_1V8") (pintype "passive"))
    (pad "2" smd roundrect (at 0.485 0 180) (size 0.59 0.64) (layers "B.Cu" "B.Paste" "B.Mask") (roundrect_rratio 0.25)
      (net 161 "PCIE1_WAKE_N") (pintype "passive"))
  )

  (footprint "sa800u-baseboard-hw-footprints:C_0402_1005Metric" (layer "B.Cu")
    (tedit 616D63CF)
    (at 99.549174 106.357734 -90)
    (descr "Capacitor SMD 0402")
    (tags "capacitor SMD 0402")
    (property "Author" "Antmicro")
    (property "Dielectric" "X5R")
    (property "License" "Apache-2.0")
    (property "MPN" "GRM155R61H104KE14D")
    (property "Manufacturer" "Murata")
    (property "Sheetfile" "ethernet-controller.kicad_sch")
    (property "Sheetname" "Ethernet Controller")
    (property "Val" "100n")
    (property "Voltage" "50V")
    (attr smd)
    (fp_text reference "C11" (at -1.097734 -3.290826 90) (layer "B.SilkS")
      (effects (font (size 0.7 0.7) (thickness 0.15)) (justify left bottom mirror))
    )
    (fp_text value "C_100n_0402" (at 0 -1.4 90) (layer "B.Fab")
      (effects (font (size 0.7 0.7) (thickness 0.15)) (justify left bottom mirror))
    )
    (fp_text user "Author: Antmicro" (at -0.932 -4.17 90) (layer "B.Fab") hide
      (effects (font (size 0.7 0.7) (thickness 0.15)) (justify left bottom mirror))
    )
    (fp_text user "License: Apache-2.0" (at -0.932 -5.17 90) (layer "B.Fab") hide
      (effects (font (size 0.7 0.7) (thickness 0.15)) (justify left bottom mirror))
    )
    (fp_text user "${REFERENCE}" (at -0.932 -3.168 90) (layer "B.Fab") hide
      (effects (font (size 0.7 0.7) (thickness 0.15)) (justify left bottom mirror))
    )
    (fp_rect (start -0.94 0.47) (end 0.94 -0.47) (layer "B.CrtYd") (width 0.05) (fill none))
    (fp_rect (start -0.499 0.249) (end 0.499 -0.249) (layer "B.Fab") (width 0.15) (fill none))
    (pad "1" smd roundrect (at -0.484 0 270) (size 0.59 0.64) (layers "B.Cu" "B.Paste" "B.Mask") (roundrect_rratio 0.25)
      (net 178 "/Ethernet Controller/REG_1V0") (pintype "passive"))
    (pad "2" smd roundrect (at 0.484 0 270) (size 0.59 0.64) (layers "B.Cu" "B.Paste" "B.Mask") (roundrect_rratio 0.25)
      (net 1 "GND") (pintype "passive"))
  )

  (footprint "sa800u-baseboard-hw-footprints:C_0402_1005Metric" (layer "B.Cu")
    (tedit 616D63CF)
    (at 95.249174 106.957733 180)
    (descr "Capacitor SMD 0402")
    (tags "capacitor SMD 0402")
    (property "Author" "Antmicro")
    (property "Dielectric" "X5R")
    (property "License" "Apache-2.0")
    (property "MPN" "GRM155R61H104KE14D")
    (property "Manufacturer" "Murata")
    (property "Sheetfile" "ethernet-controller.kicad_sch")
    (property "Sheetname" "Ethernet Controller")
    (property "Val" "100n")
    (property "Voltage" "50V")
    (attr smd)
    (fp_text reference "C14" (at -1.230826 0.417733) (layer "B.SilkS")
      (effects (font (size 0.7 0.7) (thickness 0.15)) (justify left bottom mirror))
    )
    (fp_text value "C_100n_0402" (at 0 -1.4) (layer "B.Fab")
      (effects (font (size 0.7 0.7) (thickness 0.15)) (justify left bottom mirror))
    )
    (fp_text user "Author: Antmicro" (at -0.932 -4.17) (layer "B.Fab") hide
      (effects (font (size 0.7 0.7) (thickness 0.15)) (justify left bottom mirror))
    )
    (fp_text user "License: Apache-2.0" (at -0.932 -5.17) (layer "B.Fab") hide
      (effects (font (size 0.7 0.7) (thickness 0.15)) (justify left bottom mirror))
    )
    (fp_text user "${REFERENCE}" (at -0.932 -3.168) (layer "B.Fab") hide
      (effects (font (size 0.7 0.7) (thickness 0.15)) (justify left bottom mirror))
    )
    (fp_rect (start -0.94 0.47) (end 0.94 -0.47) (layer "B.CrtYd") (width 0.05) (fill none))
    (fp_rect (start -0.499 0.249) (end 0.499 -0.249) (layer "B.Fab") (width 0.15) (fill none))
    (pad "1" smd roundrect (at -0.484 0 180) (size 0.59 0.64) (layers "B.Cu" "B.Paste" "B.Mask") (roundrect_rratio 0.25)
      (net 181 "/Ethernet Controller/ETH_1V0") (pintype "passive"))
    (pad "2" smd roundrect (at 0.484 0 180) (size 0.59 0.64) (layers "B.Cu" "B.Paste" "B.Mask") (roundrect_rratio 0.25)
      (net 1 "GND") (pintype "passive"))
  )

  (footprint "sa800u-baseboard-hw-footprints:C_0402_1005Metric" (layer "B.Cu")
    (tedit 616D63CF)
    (at 101.549174 106.357734 -90)
    (descr "Capacitor SMD 0402")
    (tags "capacitor SMD 0402")
    (property "Author" "Antmicro")
    (property "DNP" "DNP")
    (property "Dielectric" "")
    (property "License" "Apache-2.0")
    (property "MPN" "C1005X6S1A105K050BC")
    (property "Manufacturer" "TDK")
    (property "Sheetfile" "ethernet-controller.kicad_sch")
    (property "Sheetname" "Ethernet Controller")
    (property "Val" "1u")
    (property "Voltage" "")
    (attr exclude_from_pos_files)
    (fp_text reference "C17" (at -1.117734 -3.160826 90) (layer "B.SilkS")
      (effects (font (size 0.7 0.7) (thickness 0.15)) (justify left bottom mirror))
    )
    (fp_text value "C_1u_0402" (at 0 -1.4 90) (layer "B.Fab")
      (effects (font (size 0.7 0.7) (thickness 0.15)) (justify left bottom mirror))
    )
    (fp_text user "Author: Antmicro" (at -0.932 -4.17 90) (layer "B.Fab") hide
      (effects (font (size 0.7 0.7) (thickness 0.15)) (justify left bottom mirror))
    )
    (fp_text user "${REFERENCE}" (at -0.932 -3.168 90) (layer "B.Fab") hide
      (effects (font (size 0.7 0.7) (thickness 0.15)) (justify left bottom mirror))
    )
    (fp_text user "License: Apache-2.0" (at -0.932 -5.17 90) (layer "B.Fab") hide
      (effects (font (size 0.7 0.7) (thickness 0.15)) (justify left bottom mirror))
    )
    (fp_rect (start -0.94 0.47) (end 0.94 -0.47) (layer "B.CrtYd") (width 0.05) (fill none))
    (fp_rect (start -0.499 0.249) (end 0.499 -0.249) (layer "B.Fab") (width 0.15) (fill none))
    (pad "1" smd roundrect (at -0.484 0 270) (size 0.59 0.64) (layers "B.Cu" "B.Paste" "B.Mask") (roundrect_rratio 0.25)
      (net 181 "/Ethernet Controller/ETH_1V0") (pintype "passive"))
    (pad "2" smd roundrect (at 0.484 0 270) (size 0.59 0.64) (layers "B.Cu" "B.Paste" "B.Mask") (roundrect_rratio 0.25)
      (net 1 "GND") (pintype "passive"))
  )

  (footprint "sa800u-baseboard-hw-footprints:C_0402_1005Metric" (layer "B.Cu")
    (tedit 616D63CF)
    (at 99.691694 109.145244 90)
    (descr "Capacitor SMD 0402")
    (tags "capacitor SMD 0402")
    (property "Author" "Antmicro")
    (property "Dielectric" "C0G")
    (property "License" "Apache-2.0")
    (property "MPN" "GCM1555C1H100GA16D")
    (property "Manufacturer" "Murata")
    (property "Sheetfile" "ethernet-controller.kicad_sch")
    (property "Sheetname" "Ethernet Controller")
    (property "Val" "10p")
    (property "Voltage" "50V")
    (attr smd)
    (fp_text reference "C1" (at 0.675244 1.368306 270) (layer "B.SilkS")
      (effects (font (size 0.7 0.7) (thickness 0.15)) (justify left bottom mirror))
    )
    (fp_text value "C_10p_0402" (at 0 -1.4 270) (layer "B.Fab")
      (effects (font (size 0.7 0.7) (thickness 0.15)) (justify left bottom mirror))
    )
    (fp_text user "${REFERENCE}" (at -0.932 -3.168 270) (layer "B.Fab") hide
      (effects (font (size 0.7 0.7) (thickness 0.15)) (justify left bottom mirror))
    )
    (fp_text user "Author: Antmicro" (at -0.932 -4.17 270) (layer "B.Fab") hide
      (effects (font (size 0.7 0.7) (thickness 0.15)) (justify left bottom mirror))
    )
    (fp_text user "License: Apache-2.0" (at -0.932 -5.17 270) (layer "B.Fab") hide
      (effects (font (size 0.7 0.7) (thickness 0.15)) (justify left bottom mirror))
    )
    (fp_rect (start -0.94 0.47) (end 0.94 -0.47) (layer "B.CrtYd") (width 0.05) (fill none))
    (fp_rect (start -0.499 0.249) (end 0.499 -0.249) (layer "B.Fab") (width 0.15) (fill none))
    (pad "1" smd roundrect (at -0.484 0 90) (size 0.59 0.64) (layers "B.Cu" "B.Paste" "B.Mask") (roundrect_rratio 0.25)
      (net 182 "/Ethernet Controller/XTAL1") (pintype "passive"))
    (pad "2" smd roundrect (at 0.484 0 90) (size 0.59 0.64) (layers "B.Cu" "B.Paste" "B.Mask") (roundrect_rratio 0.25)
      (net 1 "GND") (pintype "passive"))
  )

  (footprint "sa800u-baseboard-hw-footprints:C_0402_1005Metric" (layer "B.Cu")
    (tedit 616D63CF)
    (at 94.459104 109.145243 -90)
    (descr "Capacitor SMD 0402")
    (tags "capacitor SMD 0402")
    (property "Author" "Antmicro")
    (property "Dielectric" "C0G")
    (property "License" "Apache-2.0")
    (property "MPN" "GCM1555C1H100GA16D")
    (property "Manufacturer" "Murata")
    (property "Sheetfile" "ethernet-controller.kicad_sch")
    (property "Sheetname" "Ethernet Controller")
    (property "Val" "10p")
    (property "Voltage" "50V")
    (attr smd)
    (fp_text reference "C2" (at 0.914757 -0.320896 90) (layer "B.SilkS")
      (effects (font (size 0.7 0.7) (thickness 0.15)) (justify left bottom mirror))
    )
    (fp_text value "C_10p_0402" (at 0 -1.4 90) (layer "B.Fab")
      (effects (font (size 0.7 0.7) (thickness 0.15)) (justify left bottom mirror))
    )
    (fp_text user "License: Apache-2.0" (at -0.932 -5.17 90) (layer "B.Fab") hide
      (effects (font (size 0.7 0.7) (thickness 0.15)) (justify left bottom mirror))
    )
    (fp_text user "${REFERENCE}" (at -0.932 -3.168 90) (layer "B.Fab") hide
      (effects (font (size 0.7 0.7) (thickness 0.15)) (justify left bottom mirror))
    )
    (fp_text user "Author: Antmicro" (at -0.932 -4.17 90) (layer "B.Fab") hide
      (effects (font (size 0.7 0.7) (thickness 0.15)) (justify left bottom mirror))
    )
    (fp_rect (start -0.94 0.47) (end 0.94 -0.47) (layer "B.CrtYd") (width 0.05) (fill none))
    (fp_rect (start -0.499 0.249) (end 0.499 -0.249) (layer "B.Fab") (width 0.15) (fill none))
    (pad "1" smd roundrect (at -0.484 0 270) (size 0.59 0.64) (layers "B.Cu" "B.Paste" "B.Mask") (roundrect_rratio 0.25)
      (net 183 "/Ethernet Controller/XTAL2") (pintype "passive"))
    (pad "2" smd roundrect (at 0.484 0 270) (size 0.59 0.64) (layers "B.Cu" "B.Paste" "B.Mask") (roundrect_rratio 0.25)
      (net 1 "GND") (pintype "passive"))
  )

  (footprint "sa800u-baseboard-hw-footprints:R_0402_1005Metric" (layer "B.Cu")
    (tedit 5FD9C158)
    (at 100.549174 106.357734 90)
    (descr "Resistor SMD 0402")
    (tags "resistor SMD 0402")
    (property "Author" "Antmicro")
    (property "Current" "1A")
    (property "License" "Apache-2.0")
    (property "MPN" "ERJ2GE0R00X")
    (property "Manufacturer" "Panasonic")
    (property "Sheetfile" "ethernet-controller.kicad_sch")
    (property "Sheetname" "Ethernet Controller")
    (property "Tolerance" "")
    (property "Val" "0R")
    (attr smd)
    (fp_text reference "R12" (at 1.107734 3.220826 270) (layer "B.SilkS")
      (effects (font (size 0.7 0.7) (thickness 0.15)) (justify left bottom mirror))
    )
    (fp_text value "R_0R_0402" (at 0 -1.4 270) (layer "B.Fab")
      (effects (font (size 0.7 0.7) (thickness 0.15)) (justify left bottom mirror))
    )
    (fp_text user "${REFERENCE}" (at -0.95 -3.168 270) (layer "B.Fab") hide
      (effects (font (size 0.7 0.7) (thickness 0.15)) (justify left bottom mirror))
    )
    (fp_text user "License: Apache-2.0" (at -0.95 -5.169 270) (layer "B.Fab") hide
      (effects (font (size 0.7 0.7) (thickness 0.15)) (justify left bottom mirror))
    )
    (fp_text user "Author: Antmicro" (at -0.95 -4.169 270) (layer "B.Fab") hide
      (effects (font (size 0.7 0.7) (thickness 0.15)) (justify left bottom mirror))
    )
    (fp_rect (start -0.93 0.47) (end 0.93 -0.47) (layer "B.CrtYd") (width 0.05) (fill none))
    (fp_rect (start -0.5 0.25) (end 0.5 -0.25) (layer "B.Fab") (width 0.15) (fill none))
    (pad "1" smd roundrect (at -0.485 0 90) (size 0.59 0.64) (layers "B.Cu" "B.Paste" "B.Mask") (roundrect_rratio 0.25)
      (net 178 "/Ethernet Controller/REG_1V0") (pintype "passive"))
    (pad "2" smd roundrect (at 0.485 0 90) (size 0.59 0.64) (layers "B.Cu" "B.Paste" "B.Mask") (roundrect_rratio 0.25)
      (net 181 "/Ethernet Controller/ETH_1V0") (pintype "passive"))
  )

  (footprint "sa800u-baseboard-hw-footprints:R_0402_1005Metric" (layer "B.Cu")
    (tedit 5FD9C158)
    (at 97.149174 106.957733)
    (descr "Resistor SMD 0402")
    (tags "resistor SMD 0402")
    (property "Author" "Antmicro")
    (property "DNP" "DNP")
    (property "License" "Apache-2.0")
    (property "MPN" "CR0402-FX-1004GLF")
    (property "Manufacturer" "Bourns")
    (property "Sheetfile" "ethernet-controller.kicad_sch")
    (property "Sheetname" "Ethernet Controller")
    (property "Tolerance" "1%")
    (property "Val" "1M")
    (attr exclude_from_pos_files)
    (fp_text reference "R5" (at 0.670826 -0.447733 180) (layer "B.SilkS")
      (effects (font (size 0.7 0.7) (thickness 0.15)) (justify left bottom mirror))
    )
    (fp_text value "R_1M_0402" (at 0 -1.4 180) (layer "B.Fab")
      (effects (font (size 0.7 0.7) (thickness 0.15)) (justify left bottom mirror))
    )
    (fp_text user "Author: Antmicro" (at -0.95 -4.169 180) (layer "B.Fab") hide
      (effects (font (size 0.7 0.7) (thickness 0.15)) (justify left bottom mirror))
    )
    (fp_text user "${REFERENCE}" (at -0.95 -3.168 180) (layer "B.Fab") hide
      (effects (font (size 0.7 0.7) (thickness 0.15)) (justify left bottom mirror))
    )
    (fp_text user "License: Apache-2.0" (at -0.95 -5.169 180) (layer "B.Fab") hide
      (effects (font (size 0.7 0.7) (thickness 0.15)) (justify left bottom mirror))
    )
    (fp_rect (start -0.93 0.47) (end 0.93 -0.47) (layer "B.CrtYd") (width 0.05) (fill none))
    (fp_rect (start -0.5 0.25) (end 0.5 -0.25) (layer "B.Fab") (width 0.15) (fill none))
    (pad "1" smd roundrect (at -0.485 0) (size 0.59 0.64) (layers "B.Cu" "B.Paste" "B.Mask") (roundrect_rratio 0.25)
      (net 183 "/Ethernet Controller/XTAL2") (pintype "passive"))
    (pad "2" smd roundrect (at 0.485 0) (size 0.59 0.64) (layers "B.Cu" "B.Paste" "B.Mask") (roundrect_rratio 0.25)
      (net 182 "/Ethernet Controller/XTAL1") (pintype "passive"))
  )

  (footprint "sa800u-baseboard-hw-footprints:Oscillator_SMD_Geyer_KX-7-4Pin_3.2x2.5mm" (layer "B.Cu")
    (tedit 5D7218CB)
    (at 97.14611 109.145244 180)
    (property "Author" "Antmicro")
    (property "License" "Apache-2.0")
    (property "MPN" "ABM8G-25.000MHZ-18-D2Y-T")
    (property "Manufacturer" "Abracon")
    (property "Sheetfile" "ethernet-controller.kicad_sch")
    (property "Sheetname" "Ethernet Controller")
    (property "Val" "25MHz")
    (attr smd)
    (fp_text reference "Y1" (at 0.84611 -2.524756) (layer "B.SilkS")
      (effects (font (size 0.7 0.7) (thickness 0.15)) (justify right bottom mirror))
    )
    (fp_text value "Oscillator_SMD_25MHz_KX-7" (at -1.75 -2.548) (layer "B.Fab")
      (effects (font (size 0.7 0.7) (thickness 0.15)) (justify left bottom mirror))
    )
    (fp_text user "License: Apache-2.0" (at -1.75 -6.5) (layer "B.Fab") hide
      (effects (font (size 0.7 0.7) (thickness 0.15)) (justify left bottom mirror))
    )
    (fp_text user "Author: Antmicro" (at -1.75 -5) (layer "B.Fab") hide
      (effects (font (size 0.7 0.7) (thickness 0.15)) (justify left bottom mirror))
    )
    (fp_text user "${REFERENCE}" (at -1.75 -3.75) (layer "B.Fab") hide
      (effects (font (size 0.7 0.7) (thickness 0.15)) (justify left bottom mirror))
    )
    (fp_line (start 1.6 -0.3) (end 1.6 0.2) (layer "B.SilkS") (width 0.15))
    (fp_line (start -0.35 1.25) (end 0.45 1.25) (layer "B.SilkS") (width 0.15))
    (fp_line (start -1.6 -0.3) (end -1.6 0.2) (layer "B.SilkS") (width 0.15))
    (fp_line (start -0.35 -1.25) (end 0.45 -1.25) (layer "B.SilkS") (width 0.15))
    (fp_circle (center -1.75 -1.5) (end -1.7 -1.5) (layer "B.SilkS") (width 0.15) (fill none))
    (fp_rect (start -1.907 1.55) (end 2.006 -1.649) (layer "B.CrtYd") (width 0.05) (fill none))
    (pad "1" smd roundrect (at -1.101 -0.949 180) (size 1.3 1.1) (layers "B.Cu" "B.Paste" "B.Mask") (roundrect_rratio 0)
      (chamfer_ratio 0.2) (chamfer top_left)
      (net 182 "/Ethernet Controller/XTAL1") (pintype "passive"))
    (pad "2" smd rect (at 1.199 -0.949 180) (size 1.3 1.1) (layers "B.Cu" "B.Paste" "B.Mask")
      (net 1 "GND") (pinfunction "SH") (pintype "passive"))
    (pad "3" smd rect (at 1.199 0.85 180) (size 1.3 1.1) (layers "B.Cu" "B.Paste" "B.Mask")
      (net 183 "/Ethernet Controller/XTAL2") (pintype "passive"))
    (pad "4" smd rect (at -1.101 0.85 180) (size 1.3 1.1) (layers "B.Cu" "B.Paste" "B.Mask")
      (net 1 "GND") (pinfunction "SH") (pintype "passive"))
  )

  (footprint "sa800u-baseboard-hw-footprints:C_0402_1005Metric" (layer "B.Cu")
    (tedit 616D63CF)
    (at 101.549174 104.257734)
    (descr "Capacitor SMD 0402")
    (tags "capacitor SMD 0402")
    (property "Author" "Antmicro")
    (property "Dielectric" "X5R")
    (property "License" "Apache-2.0")
    (property "MPN" "GRM155R61H104KE14D")
    (property "Manufacturer" "Murata")
    (property "Sheetfile" "ethernet-controller.kicad_sch")
    (property "Sheetname" "Ethernet Controller")
    (property "Val" "100n")
    (property "Voltage" "50V")
    (attr smd)
    (fp_text reference "C4" (at 2.410826 0.282266 180) (layer "B.SilkS")
      (effects (font (size 0.7 0.7) (thickness 0.15)) (justify left bottom mirror))
    )
    (fp_text value "C_100n_0402" (at 0 -1.4 180) (layer "B.Fab")
      (effects (font (size 0.7 0.7) (thickness 0.15)) (justify left bottom mirror))
    )
    (fp_text user "${REFERENCE}" (at -0.932 -3.168 180) (layer "B.Fab") hide
      (effects (font (size 0.7 0.7) (thickness 0.15)) (justify left bottom mirror))
    )
    (fp_text user "Author: Antmicro" (at -0.932 -4.17 180) (layer "B.Fab") hide
      (effects (font (size 0.7 0.7) (thickness 0.15)) (justify left bottom mirror))
    )
    (fp_text user "License: Apache-2.0" (at -0.932 -5.17 180) (layer "B.Fab") hide
      (effects (font (size 0.7 0.7) (thickness 0.15)) (justify left bottom mirror))
    )
    (fp_rect (start -0.94 0.47) (end 0.94 -0.47) (layer "B.CrtYd") (width 0.05) (fill none))
    (fp_rect (start -0.499 0.249) (end 0.499 -0.249) (layer "B.Fab") (width 0.15) (fill none))
    (pad "1" smd roundrect (at -0.484 0) (size 0.59 0.64) (layers "B.Cu" "B.Paste" "B.Mask") (roundrect_rratio 0.25)
      (net 177 "/Ethernet Controller/ETH_3V3") (pintype "passive"))
    (pad "2" smd roundrect (at 0.484 0) (size 0.59 0.64) (layers "B.Cu" "B.Paste" "B.Mask") (roundrect_rratio 0.25)
      (net 1 "GND") (pintype "passive"))
  )

  (footprint "sa800u-baseboard-hw-footprints:C_0402_1005Metric" (layer "B.Cu")
    (tedit 616D63CF)
    (at 93.928774 105.432933 180)
    (descr "Capacitor SMD 0402")
    (tags "capacitor SMD 0402")
    (property "Author" "Antmicro")
    (property "Dielectric" "X5R")
    (property "License" "Apache-2.0")
    (property "MPN" "GRM155R61H104KE14D")
    (property "Manufacturer" "Murata")
    (property "Sheetfile" "ethernet-controller.kicad_sch")
    (property "Sheetname" "Ethernet Controller")
    (property "Val" "100n")
    (property "Voltage" "50V")
    (attr smd)
    (fp_text reference "C5" (at -0.451226 0.612933) (layer "B.SilkS")
      (effects (font (size 0.7 0.7) (thickness 0.15)) (justify left bottom mirror))
    )
    (fp_text value "C_100n_0402" (at 0 -1.4) (layer "B.Fab")
      (effects (font (size 0.7 0.7) (thickness 0.15)) (justify left bottom mirror))
    )
    (fp_text user "${REFERENCE}" (at -0.932 -3.168) (layer "B.Fab") hide
      (effects (font (size 0.7 0.7) (thickness 0.15)) (justify left bottom mirror))
    )
    (fp_text user "License: Apache-2.0" (at -0.932 -5.17) (layer "B.Fab") hide
      (effects (font (size 0.7 0.7) (thickness 0.15)) (justify left bottom mirror))
    )
    (fp_text user "Author: Antmicro" (at -0.932 -4.17) (layer "B.Fab") hide
      (effects (font (size 0.7 0.7) (thickness 0.15)) (justify left bottom mirror))
    )
    (fp_rect (start -0.94 0.47) (end 0.94 -0.47) (layer "B.CrtYd") (width 0.05) (fill none))
    (fp_rect (start -0.499 0.249) (end 0.499 -0.249) (layer "B.Fab") (width 0.15) (fill none))
    (pad "1" smd roundrect (at -0.484 0 180) (size 0.59 0.64) (layers "B.Cu" "B.Paste" "B.Mask") (roundrect_rratio 0.25)
      (net 177 "/Ethernet Controller/ETH_3V3") (pintype "passive"))
    (pad "2" smd roundrect (at 0.484 0 180) (size 0.59 0.64) (layers "B.Cu" "B.Paste" "B.Mask") (roundrect_rratio 0.25)
      (net 1 "GND") (pintype "passive"))
  )

  (footprint "sa800u-baseboard-hw-footprints:C_0402_1005Metric" (layer "B.Cu")
    (tedit 616D63CF)
    (at 93.6 101.5 180)
    (descr "Capacitor SMD 0402")
    (tags "capacitor SMD 0402")
    (property "Author" "Antmicro")
    (property "Dielectric" "X5R")
    (property "License" "Apache-2.0")
    (property "MPN" "GRM155R61H104KE14D")
    (property "Manufacturer" "Murata")
    (property "Sheetfile" "ethernet-controller.kicad_sch")
    (property "Sheetname" "Ethernet Controller")
    (property "Val" "100n")
    (property "Voltage" "50V")
    (attr smd)
    (fp_text reference "C13" (at -0.82 -1.23) (layer "B.SilkS")
      (effects (font (size 0.7 0.7) (thickness 0.15)) (justify left bottom mirror))
    )
    (fp_text value "C_100n_0402" (at 0 -1.4) (layer "B.Fab")
      (effects (font (size 0.7 0.7) (thickness 0.15)) (justify left bottom mirror))
    )
    (fp_text user "License: Apache-2.0" (at -0.932 -5.17) (layer "B.Fab") hide
      (effects (font (size 0.7 0.7) (thickness 0.15)) (justify left bottom mirror))
    )
    (fp_text user "${REFERENCE}" (at -0.932 -3.168) (layer "B.Fab") hide
      (effects (font (size 0.7 0.7) (thickness 0.15)) (justify left bottom mirror))
    )
    (fp_text user "Author: Antmicro" (at -0.932 -4.17) (layer "B.Fab") hide
      (effects (font (size 0.7 0.7) (thickness 0.15)) (justify left bottom mirror))
    )
    (fp_rect (start -0.94 0.47) (end 0.94 -0.47) (layer "B.CrtYd") (width 0.05) (fill none))
    (fp_rect (start -0.499 0.249) (end 0.499 -0.249) (layer "B.Fab") (width 0.15) (fill none))
    (pad "1" smd roundrect (at -0.484 0 180) (size 0.59 0.64) (layers "B.Cu" "B.Paste" "B.Mask") (roundrect_rratio 0.25)
      (net 181 "/Ethernet Controller/ETH_1V0") (pintype "passive"))
    (pad "2" smd roundrect (at 0.484 0 180) (size 0.59 0.64) (layers "B.Cu" "B.Paste" "B.Mask") (roundrect_rratio 0.25)
      (net 1 "GND") (pintype "passive"))
  )

  (footprint "sa800u-baseboard-hw-footprints:C_0603_1608Metric" (layer "B.Cu")
    (tedit 5D5E94D2)
    (at 113.5 149.25 -90)
    (descr "Capacitor SMD 0603")
    (tags "capacitor 0603")
    (property "Author" "Antmicro")
    (property "Dielectric" "")
    (property "License" "Apache-2.0")
    (property "MPN" "GRM188R60J476ME15D")
    (property "Manufacturer" "Murata")
    (property "Sheetfile" "usb-c-interface.kicad_sch")
    (property "Sheetname" "USB-C Interface ")
    (property "Val" "47u")
    (property "Voltage" "")
    (attr smd)
    (fp_text reference "C78" (at -1.05 0.69 90) (layer "B.SilkS")
      (effects (font (size 0.7 0.7) (thickness 0.15)) (justify left bottom mirror))
    )
    (fp_text value "C_47u_0603" (at 0 -1.6 90) (layer "B.Fab")
      (effects (font (size 0.7 0.7) (thickness 0.15)) (justify left bottom mirror))
    )
    (fp_text user "${REFERENCE}" (at -1.682 -3.895 90) (layer "B.Fab") hide
      (effects (font (size 0.7 0.7) (thickness 0.15)) (justify left bottom mirror))
    )
    (fp_text user "Author: Antmicro" (at -1.682 -4.894 90) (layer "B.Fab") hide
      (effects (font (size 0.7 0.7) (thickness 0.15)) (justify left bottom mirror))
    )
    (fp_text user "License: Apache-2.0" (at -1.682 -5.895 90) (layer "B.Fab") hide
      (effects (font (size 0.7 0.7) (thickness 0.15)) (justify left bottom mirror))
    )
    (fp_line (start -0.3 0.3) (end 0.3 0.3) (layer "B.SilkS") (width 0.15))
    (fp_line (start -0.3 -0.3) (end 0.3 -0.3) (layer "B.SilkS") (width 0.15))
    (fp_rect (start -1.24 0.7) (end 1.24 -0.7) (layer "B.CrtYd") (width 0.05) (fill none))
    (fp_rect (start -0.8 0.4) (end 0.8 -0.4) (layer "B.Fab") (width 0.15) (fill none))
    (pad "1" smd roundrect (at -0.7 0 270) (size 0.6 0.8) (layers "B.Cu" "B.Paste" "B.Mask") (roundrect_rratio 0.2)
      (net 210 "/USB-C Interface /USB2_5V") (pintype "passive"))
    (pad "2" smd roundrect (at 0.7 0 270) (size 0.6 0.8) (layers "B.Cu" "B.Paste" "B.Mask") (roundrect_rratio 0.2)
      (net 1 "GND") (pintype "passive"))
  )

  (footprint "sa800u-baseboard-hw-footprints:Nexperia_DFN-10_2.5x1mm_P0.5mm" (layer "B.Cu")
    (tedit 6215DC23)
    (at 99 140.6)
    (property "Author" "Antmicro")
    (property "License" "Apache-2.0")
    (property "MPN" "PUSB3F96X")
    (property "Manufacturer" "Nexperia")
    (property "Sheetfile" "usb-c-interface.kicad_sch")
    (property "Sheetname" "USB-C Interface ")
    (attr smd)
    (fp_text reference "D9" (at 0.94 1.57 180) (layer "B.SilkS")
      (effects (font (size 0.7 0.7) (thickness 0.15)) (justify left bottom mirror))
    )
    (fp_text value "PUSB3F96X_PASS" (at -0.016 -1.705 180) (layer "B.Fab")
      (effects (font (size 0.7 0.7) (thickness 0.15)) (justify left bottom mirror))
    )
    (fp_text user "Author: Antmicro" (at -1.367 -4.905 180) (layer "B.Fab") hide
      (effects (font (size 0.7 0.7) (thickness 0.15)) (justify left bottom mirror))
    )
    (fp_text user "${REFERENCE}" (at -1.367 -3.704 180) (layer "B.Fab") hide
      (effects (font (size 0.7 0.7) (thickness 0.15)) (justify left bottom mirror))
    )
    (fp_text user "License: Apache-2.0" (at -1.367 -6.105 180) (layer "B.Fab") hide
      (effects (font (size 0.7 0.7) (thickness 0.15)) (justify left bottom mirror))
    )
    (fp_line (start 1.233 -0.405) (end 1.233 0.396) (layer "B.SilkS") (width 0.15))
    (fp_line (start -1.266 0.396) (end -1.266 -0.405) (layer "B.SilkS") (width 0.15))
    (fp_circle (center -1.317 -0.704) (end -1.266 -0.704) (layer "B.SilkS") (width 0.15) (fill solid))
    (fp_rect (start -1.4 0.7) (end 1.4 -0.7) (layer "B.CrtYd") (width 0.05) (fill none))
    (pad "1" smd rect (at -1.016 -0.392) (size 0.2 0.475) (layers "B.Cu" "B.Paste" "B.Mask")
      (net 308 "/USB-C Interface /USB1C_RX0_C_P") (pinfunction "CH1") (pintype "passive"))
    (pad "2" smd rect (at -0.517 -0.392) (size 0.2 0.475) (layers "B.Cu" "B.Paste" "B.Mask")
      (net 323 "/USB-C Interface /USB1C_RX0_C_N") (pinfunction "CH2") (pintype "passive"))
    (pad "3" smd rect (at -0.016 -0.392) (size 0.2 0.475) (layers "B.Cu" "B.Paste" "B.Mask")
      (net 1 "GND") (pinfunction "GND") (pintype "passive"))
    (pad "4" smd rect (at 0.482 -0.392) (size 0.2 0.475) (layers "B.Cu" "B.Paste" "B.Mask")
      (net 302 "/USB-C Interface /USB1C_TX0_C_P") (pinfunction "CH3") (pintype "passive"))
    (pad "5" smd rect (at 0.982 -0.392) (size 0.2 0.475) (layers "B.Cu" "B.Paste" "B.Mask")
      (net 303 "/USB-C Interface /USB1C_TX0_C_N") (pinfunction "CH4") (pintype "passive"))
    (pad "6" smd rect (at 0.982 0.383 180) (size 0.2 0.475) (layers "B.Cu" "B.Paste" "B.Mask")
      (net 303 "/USB-C Interface /USB1C_TX0_C_N") (pinfunction "CH4") (pintype "passive"))
    (pad "7" smd rect (at 0.482 0.383 180) (size 0.2 0.475) (layers "B.Cu" "B.Paste" "B.Mask")
      (net 302 "/USB-C Interface /USB1C_TX0_C_P") (pinfunction "CH3") (pintype "passive"))
    (pad "8" smd rect (at -0.016 0.383 180) (size 0.2 0.475) (layers "B.Cu" "B.Paste" "B.Mask")
      (net 1 "GND") (pinfunction "GND") (pintype "passive"))
    (pad "9" smd rect (at -0.517 0.383 180) (size 0.2 0.475) (layers "B.Cu" "B.Paste" "B.Mask")
      (net 323 "/USB-C Interface /USB1C_RX0_C_N") (pinfunction "CH2") (pintype "passive"))
    (pad "10" smd rect (at -1.016 0.383 180) (size 0.2 0.475) (layers "B.Cu" "B.Paste" "B.Mask")
      (net 308 "/USB-C Interface /USB1C_RX0_C_P") (pinfunction "CH1") (pintype "passive"))
  )

  (footprint "sa800u-baseboard-hw-footprints:C_0402_1005Metric" (layer "B.Cu")
    (tedit 616D63CF)
    (at 111.8 133.5 -90)
    (descr "Capacitor SMD 0402")
    (tags "capacitor SMD 0402")
    (property "Author" "Antmicro")
    (property "Dielectric" "X5R")
    (property "License" "Apache-2.0")
    (property "MPN" "GRM155R61H104KE14D")
    (property "Manufacturer" "Murata")
    (property "Sheetfile" "usb-c-interface.kicad_sch")
    (property "Sheetname" "USB-C Interface ")
    (property "Val" "100n")
    (property "Voltage" "50V")
    (attr smd)
    (fp_text reference "C74" (at -1 0.6 90) (layer "B.SilkS")
      (effects (font (size 0.7 0.7) (thickness 0.15)) (justify left bottom mirror))
    )
    (fp_text value "C_100n_0402" (at 0 -1.4 90) (layer "B.Fab")
      (effects (font (size 0.7 0.7) (thickness 0.15)) (justify left bottom mirror))
    )
    (fp_text user "Author: Antmicro" (at -0.932 -4.17 90) (layer "B.Fab") hide
      (effects (font (size 0.7 0.7) (thickness 0.15)) (justify left bottom mirror))
    )
    (fp_text user "License: Apache-2.0" (at -0.932 -5.17 90) (layer "B.Fab") hide
      (effects (font (size 0.7 0.7) (thickness 0.15)) (justify left bottom mirror))
    )
    (fp_text user "${REFERENCE}" (at -0.932 -3.168 90) (layer "B.Fab") hide
      (effects (font (size 0.7 0.7) (thickness 0.15)) (justify left bottom mirror))
    )
    (fp_rect (start -0.94 0.47) (end 0.94 -0.47) (layer "B.CrtYd") (width 0.05) (fill none))
    (fp_rect (start -0.499 0.249) (end 0.499 -0.249) (layer "B.Fab") (width 0.15) (fill none))
    (pad "1" smd roundrect (at -0.484 0 270) (size 0.59 0.64) (layers "B.Cu" "B.Paste" "B.Mask") (roundrect_rratio 0.25)
      (net 131 "3V3_SYS") (pintype "passive"))
    (pad "2" smd roundrect (at 0.484 0 270) (size 0.59 0.64) (layers "B.Cu" "B.Paste" "B.Mask") (roundrect_rratio 0.25)
      (net 1 "GND") (pintype "passive"))
  )

  (footprint "sa800u-baseboard-hw-footprints:C_0402_1005Metric" (layer "B.Cu")
    (tedit 616D63CF)
    (at 115.25 138.95 -90)
    (descr "Capacitor SMD 0402")
    (tags "capacitor SMD 0402")
    (property "Author" "Antmicro")
    (property "Dielectric" "X5R")
    (property "License" "Apache-2.0")
    (property "MPN" "GRM155R61H104KE14D")
    (property "Manufacturer" "Murata")
    (property "Sheetfile" "usb-c-interface.kicad_sch")
    (property "Sheetname" "USB-C Interface ")
    (property "Val" "100n")
    (property "Voltage" "50V")
    (attr smd)
    (fp_text reference "C81" (at -3.05 -0.34 90) (layer "B.SilkS")
      (effects (font (size 0.7 0.7) (thickness 0.15)) (justify left bottom mirror))
    )
    (fp_text value "C_100n_0402" (at 0 -1.4 90) (layer "B.Fab")
      (effects (font (size 0.7 0.7) (thickness 0.15)) (justify left bottom mirror))
    )
    (fp_text user "${REFERENCE}" (at -0.932 -3.168 90) (layer "B.Fab") hide
      (effects (font (size 0.7 0.7) (thickness 0.15)) (justify left bottom mirror))
    )
    (fp_text user "Author: Antmicro" (at -0.932 -4.17 90) (layer "B.Fab") hide
      (effects (font (size 0.7 0.7) (thickness 0.15)) (justify left bottom mirror))
    )
    (fp_text user "License: Apache-2.0" (at -0.932 -5.17 90) (layer "B.Fab") hide
      (effects (font (size 0.7 0.7) (thickness 0.15)) (justify left bottom mirror))
    )
    (fp_rect (start -0.94 0.47) (end 0.94 -0.47) (layer "B.CrtYd") (width 0.05) (fill none))
    (fp_rect (start -0.499 0.249) (end 0.499 -0.249) (layer "B.Fab") (width 0.15) (fill none))
    (pad "1" smd roundrect (at -0.484 0 270) (size 0.59 0.64) (layers "B.Cu" "B.Paste" "B.Mask") (roundrect_rratio 0.25)
      (net 212 "/USB-C Interface /USB2C_TX1_N") (pintype "passive"))
    (pad "2" smd roundrect (at 0.484 0 270) (size 0.59 0.64) (layers "B.Cu" "B.Paste" "B.Mask") (roundrect_rratio 0.25)
      (net 211 "/USB-C Interface /USB2C_TX1_C_N") (pintype "passive"))
  )

  (footprint "sa800u-baseboard-hw-footprints:C_0402_1005Metric" (layer "B.Cu")
    (tedit 616D63CF)
    (at 116.25 138.95 -90)
    (descr "Capacitor SMD 0402")
    (tags "capacitor SMD 0402")
    (property "Author" "Antmicro")
    (property "Dielectric" "X5R")
    (property "License" "Apache-2.0")
    (property "MPN" "GRM155R61H104KE14D")
    (property "Manufacturer" "Murata")
    (property "Sheetfile" "usb-c-interface.kicad_sch")
    (property "Sheetname" "USB-C Interface ")
    (property "Val" "100n")
    (property "Voltage" "50V")
    (attr smd)
    (fp_text reference "C82" (at -3.05 -0.34 90) (layer "B.SilkS")
      (effects (font (size 0.7 0.7) (thickness 0.15)) (justify left bottom mirror))
    )
    (fp_text value "C_100n_0402" (at 0 -1.4 90) (layer "B.Fab")
      (effects (font (size 0.7 0.7) (thickness 0.15)) (justify left bottom mirror))
    )
    (fp_text user "License: Apache-2.0" (at -0.932 -5.17 90) (layer "B.Fab") hide
      (effects (font (size 0.7 0.7) (thickness 0.15)) (justify left bottom mirror))
    )
    (fp_text user "Author: Antmicro" (at -0.932 -4.17 90) (layer "B.Fab") hide
      (effects (font (size 0.7 0.7) (thickness 0.15)) (justify left bottom mirror))
    )
    (fp_text user "${REFERENCE}" (at -0.932 -3.168 90) (layer "B.Fab") hide
      (effects (font (size 0.7 0.7) (thickness 0.15)) (justify left bottom mirror))
    )
    (fp_rect (start -0.94 0.47) (end 0.94 -0.47) (layer "B.CrtYd") (width 0.05) (fill none))
    (fp_rect (start -0.499 0.249) (end 0.499 -0.249) (layer "B.Fab") (width 0.15) (fill none))
    (pad "1" smd roundrect (at -0.484 0 270) (size 0.59 0.64) (layers "B.Cu" "B.Paste" "B.Mask") (roundrect_rratio 0.25)
      (net 214 "/USB-C Interface /USB2C_RX2_P") (pintype "passive"))
    (pad "2" smd roundrect (at 0.484 0 270) (size 0.59 0.64) (layers "B.Cu" "B.Paste" "B.Mask") (roundrect_rratio 0.25)
      (net 213 "/USB-C Interface /USB2C_RX2_C_P") (pintype "passive"))
  )

  (footprint "sa800u-baseboard-hw-footprints:C_0402_1005Metric" (layer "B.Cu")
    (tedit 616D63CF)
    (at 117.25 138.95 -90)
    (descr "Capacitor SMD 0402")
    (tags "capacitor SMD 0402")
    (property "Author" "Antmicro")
    (property "Dielectric" "X5R")
    (property "License" "Apache-2.0")
    (property "MPN" "GRM155R61H104KE14D")
    (property "Manufacturer" "Murata")
    (property "Sheetfile" "usb-c-interface.kicad_sch")
    (property "Sheetname" "USB-C Interface ")
    (property "Val" "100n")
    (property "Voltage" "50V")
    (attr smd)
    (fp_text reference "C86" (at -3.05 -0.34 90) (layer "B.SilkS")
      (effects (font (size 0.7 0.7) (thickness 0.15)) (justify left bottom mirror))
    )
    (fp_text value "C_100n_0402" (at 0 -1.4 90) (layer "B.Fab")
      (effects (font (size 0.7 0.7) (thickness 0.15)) (justify left bottom mirror))
    )
    (fp_text user "Author: Antmicro" (at -0.932 -4.17 90) (layer "B.Fab") hide
      (effects (font (size 0.7 0.7) (thickness 0.15)) (justify left bottom mirror))
    )
    (fp_text user "License: Apache-2.0" (at -0.932 -5.17 90) (layer "B.Fab") hide
      (effects (font (size 0.7 0.7) (thickness 0.15)) (justify left bottom mirror))
    )
    (fp_text user "${REFERENCE}" (at -0.932 -3.168 90) (layer "B.Fab") hide
      (effects (font (size 0.7 0.7) (thickness 0.15)) (justify left bottom mirror))
    )
    (fp_rect (start -0.94 0.47) (end 0.94 -0.47) (layer "B.CrtYd") (width 0.05) (fill none))
    (fp_rect (start -0.499 0.249) (end 0.499 -0.249) (layer "B.Fab") (width 0.15) (fill none))
    (pad "1" smd roundrect (at -0.484 0 270) (size 0.59 0.64) (layers "B.Cu" "B.Paste" "B.Mask") (roundrect_rratio 0.25)
      (net 218 "/USB-C Interface /USB2C_RX2_N") (pintype "passive"))
    (pad "2" smd roundrect (at 0.484 0 270) (size 0.59 0.64) (layers "B.Cu" "B.Paste" "B.Mask") (roundrect_rratio 0.25)
      (net 217 "/USB-C Interface /USB2C_RX2_C_N") (pintype "passive"))
  )

  (footprint "sa800u-baseboard-hw-footprints:C_0402_1005Metric" (layer "B.Cu")
    (tedit 616D63CF)
    (at 113.25 138.95 -90)
    (descr "Capacitor SMD 0402")
    (tags "capacitor SMD 0402")
    (property "Author" "Antmicro")
    (property "Dielectric" "X5R")
    (property "License" "Apache-2.0")
    (property "MPN" "GRM155R61H104KE14D")
    (property "Manufacturer" "Murata")
    (property "Sheetfile" "usb-c-interface.kicad_sch")
    (property "Sheetname" "USB-C Interface ")
    (property "Val" "100n")
    (property "Voltage" "50V")
    (attr smd)
    (fp_text reference "C90" (at -3.05 -0.34 90) (layer "B.SilkS")
      (effects (font (size 0.7 0.7) (thickness 0.15)) (justify left bottom mirror))
    )
    (fp_text value "C_100n_0402" (at 0 -1.4 90) (layer "B.Fab")
      (effects (font (size 0.7 0.7) (thickness 0.15)) (justify left bottom mirror))
    )
    (fp_text user "Author: Antmicro" (at -0.932 -4.17 90) (layer "B.Fab") hide
      (effects (font (size 0.7 0.7) (thickness 0.15)) (justify left bottom mirror))
    )
    (fp_text user "License: Apache-2.0" (at -0.932 -5.17 90) (layer "B.Fab") hide
      (effects (font (size 0.7 0.7) (thickness 0.15)) (justify left bottom mirror))
    )
    (fp_text user "${REFERENCE}" (at -0.932 -3.168 90) (layer "B.Fab") hide
      (effects (font (size 0.7 0.7) (thickness 0.15)) (justify left bottom mirror))
    )
    (fp_rect (start -0.94 0.47) (end 0.94 -0.47) (layer "B.CrtYd") (width 0.05) (fill none))
    (fp_rect (start -0.499 0.249) (end 0.499 -0.249) (layer "B.Fab") (width 0.15) (fill none))
    (pad "1" smd roundrect (at -0.484 0 270) (size 0.59 0.64) (layers "B.Cu" "B.Paste" "B.Mask") (roundrect_rratio 0.25)
      (net 219 "/USB-C Interface /USB2C_RX1_N") (pintype "passive"))
    (pad "2" smd roundrect (at 0.484 0 270) (size 0.59 0.64) (layers "B.Cu" "B.Paste" "B.Mask") (roundrect_rratio 0.25)
      (net 220 "/USB-C Interface /USB2C_RX1_C_N") (pintype "passive"))
  )

  (footprint "sa800u-baseboard-hw-footprints:C_0402_1005Metric" (layer "B.Cu")
    (tedit 616D63CF)
    (at 118.25 138.95 -90)
    (descr "Capacitor SMD 0402")
    (tags "capacitor SMD 0402")
    (property "Author" "Antmicro")
    (property "Dielectric" "X5R")
    (property "License" "Apache-2.0")
    (property "MPN" "GRM155R61H104KE14D")
    (property "Manufacturer" "Murata")
    (property "Sheetfile" "usb-c-interface.kicad_sch")
    (property "Sheetname" "USB-C Interface ")
    (property "Val" "100n")
    (property "Voltage" "50V")
    (attr smd)
    (fp_text reference "C91" (at -3.05 -0.34 90) (layer "B.SilkS")
      (effects (font (size 0.7 0.7) (thickness 0.15)) (justify left bottom mirror))
    )
    (fp_text value "C_100n_0402" (at 0 -1.4 90) (layer "B.Fab")
      (effects (font (size 0.7 0.7) (thickness 0.15)) (justify left bottom mirror))
    )
    (fp_text user "Author: Antmicro" (at -0.932 -4.17 90) (layer "B.Fab") hide
      (effects (font (size 0.7 0.7) (thickness 0.15)) (justify left bottom mirror))
    )
    (fp_text user "License: Apache-2.0" (at -0.932 -5.17 90) (layer "B.Fab") hide
      (effects (font (size 0.7 0.7) (thickness 0.15)) (justify left bottom mirror))
    )
    (fp_text user "${REFERENCE}" (at -0.932 -3.168 90) (layer "B.Fab") hide
      (effects (font (size 0.7 0.7) (thickness 0.15)) (justify left bottom mirror))
    )
    (fp_rect (start -0.94 0.47) (end 0.94 -0.47) (layer "B.CrtYd") (width 0.05) (fill none))
    (fp_rect (start -0.499 0.249) (end 0.499 -0.249) (layer "B.Fab") (width 0.15) (fill none))
    (pad "1" smd roundrect (at -0.484 0 270) (size 0.59 0.64) (layers "B.Cu" "B.Paste" "B.Mask") (roundrect_rratio 0.25)
      (net 221 "/USB-C Interface /USB2C_TX2_P") (pintype "passive"))
    (pad "2" smd roundrect (at 0.484 0 270) (size 0.59 0.64) (layers "B.Cu" "B.Paste" "B.Mask") (roundrect_rratio 0.25)
      (net 222 "/USB-C Interface /USB2C_TX2_C_P") (pintype "passive"))
  )

  (footprint "sa800u-baseboard-hw-footprints:C_0402_1005Metric" (layer "B.Cu")
    (tedit 616D63CF)
    (at 112.25 138.95 -90)
    (descr "Capacitor SMD 0402")
    (tags "capacitor SMD 0402")
    (property "Author" "Antmicro")
    (property "Dielectric" "X5R")
    (property "License" "Apache-2.0")
    (property "MPN" "GRM155R61H104KE14D")
    (property "Manufacturer" "Murata")
    (property "Sheetfile" "usb-c-interface.kicad_sch")
    (property "Sheetname" "USB-C Interface ")
    (property "Val" "100n")
    (property "Voltage" "50V")
    (attr smd)
    (fp_text reference "C94" (at -3.06 -0.43 90) (layer "B.SilkS")
      (effects (font (size 0.7 0.7) (thickness 0.15)) (justify left bottom mirror))
    )
    (fp_text value "C_100n_0402" (at 0 -1.4 90) (layer "B.Fab")
      (effects (font (size 0.7 0.7) (thickness 0.15)) (justify left bottom mirror))
    )
    (fp_text user "License: Apache-2.0" (at -0.932 -5.17 90) (layer "B.Fab") hide
      (effects (font (size 0.7 0.7) (thickness 0.15)) (justify left bottom mirror))
    )
    (fp_text user "${REFERENCE}" (at -0.932 -3.168 90) (layer "B.Fab") hide
      (effects (font (size 0.7 0.7) (thickness 0.15)) (justify left bottom mirror))
    )
    (fp_text user "Author: Antmicro" (at -0.932 -4.17 90) (layer "B.Fab") hide
      (effects (font (size 0.7 0.7) (thickness 0.15)) (justify left bottom mirror))
    )
    (fp_rect (start -0.94 0.47) (end 0.94 -0.47) (layer "B.CrtYd") (width 0.05) (fill none))
    (fp_rect (start -0.499 0.249) (end 0.499 -0.249) (layer "B.Fab") (width 0.15) (fill none))
    (pad "1" smd roundrect (at -0.484 0 270) (size 0.59 0.64) (layers "B.Cu" "B.Paste" "B.Mask") (roundrect_rratio 0.25)
      (net 223 "/USB-C Interface /USB2C_RX1_P") (pintype "passive"))
    (pad "2" smd roundrect (at 0.484 0 270) (size 0.59 0.64) (layers "B.Cu" "B.Paste" "B.Mask") (roundrect_rratio 0.25)
      (net 224 "/USB-C Interface /USB2C_RX1_C_P") (pintype "passive"))
  )

  (footprint "sa800u-baseboard-hw-footprints:C_0402_1005Metric" (layer "B.Cu")
    (tedit 616D63CF)
    (at 119.25 138.95 -90)
    (descr "Capacitor SMD 0402")
    (tags "capacitor SMD 0402")
    (property "Author" "Antmicro")
    (property "Dielectric" "X5R")
    (property "License" "Apache-2.0")
    (property "MPN" "GRM155R61H104KE14D")
    (property "Manufacturer" "Murata")
    (property "Sheetfile" "usb-c-interface.kicad_sch")
    (property "Sheetname" "USB-C Interface ")
    (property "Val" "100n")
    (property "Voltage" "50V")
    (attr smd)
    (fp_text reference "C95" (at -3.05 -0.34 90) (layer "B.SilkS")
      (effects (font (size 0.7 0.7) (thickness 0.15)) (justify left bottom mirror))
    )
    (fp_text value "C_100n_0402" (at 0 -1.4 90) (layer "B.Fab")
      (effects (font (size 0.7 0.7) (thickness 0.15)) (justify left bottom mirror))
    )
    (fp_text user "${REFERENCE}" (at -0.932 -3.168 90) (layer "B.Fab") hide
      (effects (font (size 0.7 0.7) (thickness 0.15)) (justify left bottom mirror))
    )
    (fp_text user "Author: Antmicro" (at -0.932 -4.17 90) (layer "B.Fab") hide
      (effects (font (size 0.7 0.7) (thickness 0.15)) (justify left bottom mirror))
    )
    (fp_text user "License: Apache-2.0" (at -0.932 -5.17 90) (layer "B.Fab") hide
      (effects (font (size 0.7 0.7) (thickness 0.15)) (justify left bottom mirror))
    )
    (fp_rect (start -0.94 0.47) (end 0.94 -0.47) (layer "B.CrtYd") (width 0.05) (fill none))
    (fp_rect (start -0.499 0.249) (end 0.499 -0.249) (layer "B.Fab") (width 0.15) (fill none))
    (pad "1" smd roundrect (at -0.484 0 270) (size 0.59 0.64) (layers "B.Cu" "B.Paste" "B.Mask") (roundrect_rratio 0.25)
      (net 225 "/USB-C Interface /USB2C_TX2_N") (pintype "passive"))
    (pad "2" smd roundrect (at 0.484 0 270) (size 0.59 0.64) (layers "B.Cu" "B.Paste" "B.Mask") (roundrect_rratio 0.25)
      (net 226 "/USB-C Interface /USB2C_TX2_C_N") (pintype "passive"))
  )

  (footprint "sa800u-baseboard-hw-footprints:C_0402_1005Metric" (layer "B.Cu")
    (tedit 616D63CF)
    (at 115.8 130.4 180)
    (descr "Capacitor SMD 0402")
    (tags "capacitor SMD 0402")
    (property "Author" "Antmicro")
    (property "Dielectric" "X5R")
    (property "License" "Apache-2.0")
    (property "MPN" "GRM155R61H104KE14D")
    (property "Manufacturer" "Murata")
    (property "Sheetfile" "usb-c-interface.kicad_sch")
    (property "Sheetname" "USB-C Interface ")
    (property "Val" "100n")
    (property "Voltage" "50V")
    (attr smd)
    (fp_text reference "C72" (at -1.05 0.68) (layer "B.SilkS")
      (effects (font (size 0.7 0.7) (thickness 0.15)) (justify left bottom mirror))
    )
    (fp_text value "C_100n_0402" (at 0 -1.4) (layer "B.Fab")
      (effects (font (size 0.7 0.7) (thickness 0.15)) (justify left bottom mirror))
    )
    (fp_text user "License: Apache-2.0" (at -0.932 -5.17) (layer "B.Fab") hide
      (effects (font (size 0.7 0.7) (thickness 0.15)) (justify left bottom mirror))
    )
    (fp_text user "${REFERENCE}" (at -0.932 -3.168) (layer "B.Fab") hide
      (effects (font (size 0.7 0.7) (thickness 0.15)) (justify left bottom mirror))
    )
    (fp_text user "Author: Antmicro" (at -0.932 -4.17) (layer "B.Fab") hide
      (effects (font (size 0.7 0.7) (thickness 0.15)) (justify left bottom mirror))
    )
    (fp_rect (start -0.94 0.47) (end 0.94 -0.47) (layer "B.CrtYd") (width 0.05) (fill none))
    (fp_rect (start -0.499 0.249) (end 0.499 -0.249) (layer "B.Fab") (width 0.15) (fill none))
    (pad "1" smd roundrect (at -0.484 0 180) (size 0.59 0.64) (layers "B.Cu" "B.Paste" "B.Mask") (roundrect_rratio 0.25)
      (net 131 "3V3_SYS") (pintype "passive"))
    (pad "2" smd roundrect (at 0.484 0 180) (size 0.59 0.64) (layers "B.Cu" "B.Paste" "B.Mask") (roundrect_rratio 0.25)
      (net 1 "GND") (pintype "passive"))
  )

  (footprint "sa800u-baseboard-hw-footprints:C_0402_1005Metric" (layer "B.Cu")
    (tedit 616D63CF)
    (at 119.6 133.5 -90)
    (descr "Capacitor SMD 0402")
    (tags "capacitor SMD 0402")
    (property "Author" "Antmicro")
    (property "Dielectric" "X5R")
    (property "License" "Apache-2.0")
    (property "MPN" "GRM155R61H104KE14D")
    (property "Manufacturer" "Murata")
    (property "Sheetfile" "usb-c-interface.kicad_sch")
    (property "Sheetname" "USB-C Interface ")
    (property "Val" "100n")
    (property "Voltage" "50V")
    (attr smd)
    (fp_text reference "C73" (at -1.09 -2.34 90) (layer "B.SilkS")
      (effects (font (size 0.7 0.7) (thickness 0.15)) (justify left bottom mirror))
    )
    (fp_text value "C_100n_0402" (at 0 -1.4 90) (layer "B.Fab")
      (effects (font (size 0.7 0.7) (thickness 0.15)) (justify left bottom mirror))
    )
    (fp_text user "Author: Antmicro" (at -0.932 -4.17 90) (layer "B.Fab") hide
      (effects (font (size 0.7 0.7) (thickness 0.15)) (justify left bottom mirror))
    )
    (fp_text user "${REFERENCE}" (at -0.932 -3.168 90) (layer "B.Fab") hide
      (effects (font (size 0.7 0.7) (thickness 0.15)) (justify left bottom mirror))
    )
    (fp_text user "License: Apache-2.0" (at -0.932 -5.17 90) (layer "B.Fab") hide
      (effects (font (size 0.7 0.7) (thickness 0.15)) (justify left bottom mirror))
    )
    (fp_rect (start -0.94 0.47) (end 0.94 -0.47) (layer "B.CrtYd") (width 0.05) (fill none))
    (fp_rect (start -0.499 0.249) (end 0.499 -0.249) (layer "B.Fab") (width 0.15) (fill none))
    (pad "1" smd roundrect (at -0.484 0 270) (size 0.59 0.64) (layers "B.Cu" "B.Paste" "B.Mask") (roundrect_rratio 0.25)
      (net 131 "3V3_SYS") (pintype "passive"))
    (pad "2" smd roundrect (at 0.484 0 270) (size 0.59 0.64) (layers "B.Cu" "B.Paste" "B.Mask") (roundrect_rratio 0.25)
      (net 1 "GND") (pintype "passive"))
  )

  (footprint "sa800u-baseboard-hw-footprints:C_0603_1608Metric" (layer "B.Cu")
    (tedit 5D5E94D2)
    (at 103.5 149.25 -90)
    (descr "Capacitor SMD 0603")
    (tags "capacitor 0603")
    (property "Author" "Antmicro")
    (property "Dielectric" "")
    (property "License" "Apache-2.0")
    (property "MPN" "GRM188R60J476ME15D")
    (property "Manufacturer" "Murata")
    (property "Sheetfile" "usb-c-interface.kicad_sch")
    (property "Sheetname" "USB-C Interface ")
    (property "Val" "47u")
    (property "Voltage" "")
    (attr smd)
    (fp_text reference "C89" (at -1.12 0.8 90) (layer "B.SilkS")
      (effects (font (size 0.7 0.7) (thickness 0.15)) (justify left bottom mirror))
    )
    (fp_text value "C_47u_0603" (at 0 -1.6 90) (layer "B.Fab")
      (effects (font (size 0.7 0.7) (thickness 0.15)) (justify left bottom mirror))
    )
    (fp_text user "Author: Antmicro" (at -1.682 -4.894 90) (layer "B.Fab") hide
      (effects (font (size 0.7 0.7) (thickness 0.15)) (justify left bottom mirror))
    )
    (fp_text user "${REFERENCE}" (at -1.682 -3.895 90) (layer "B.Fab") hide
      (effects (font (size 0.7 0.7) (thickness 0.15)) (justify left bottom mirror))
    )
    (fp_text user "License: Apache-2.0" (at -1.682 -5.895 90) (layer "B.Fab") hide
      (effects (font (size 0.7 0.7) (thickness 0.15)) (justify left bottom mirror))
    )
    (fp_line (start -0.3 0.3) (end 0.3 0.3) (layer "B.SilkS") (width 0.15))
    (fp_line (start -0.3 -0.3) (end 0.3 -0.3) (layer "B.SilkS") (width 0.15))
    (fp_rect (start -1.24 0.7) (end 1.24 -0.7) (layer "B.CrtYd") (width 0.05) (fill none))
    (fp_rect (start -0.8 0.4) (end 0.8 -0.4) (layer "B.Fab") (width 0.15) (fill none))
    (pad "1" smd roundrect (at -0.7 0 270) (size 0.6 0.8) (layers "B.Cu" "B.Paste" "B.Mask") (roundrect_rratio 0.2)
      (net 66 "USB_VBUS") (pintype "passive"))
    (pad "2" smd roundrect (at 0.7 0 270) (size 0.6 0.8) (layers "B.Cu" "B.Paste" "B.Mask") (roundrect_rratio 0.2)
      (net 1 "GND") (pintype "passive"))
  )

  (footprint "sa800u-baseboard-hw-footprints:C_0603_1608Metric" (layer "B.Cu")
    (tedit 5D5E94D2)
    (at 99.5 149.25 -90)
    (descr "Capacitor SMD 0603")
    (tags "capacitor 0603")
    (property "Author" "Antmicro")
    (property "Dielectric" "")
    (property "License" "Apache-2.0")
    (property "MPN" "GRM188R60J476ME15D")
    (property "Manufacturer" "Murata")
    (property "Sheetfile" "usb-c-interface.kicad_sch")
    (property "Sheetname" "USB-C Interface ")
    (property "Val" "47u")
    (property "Voltage" "")
    (attr smd)
    (fp_text reference "C96" (at -1.12 0.8 90) (layer "B.SilkS")
      (effects (font (size 0.7 0.7) (thickness 0.15)) (justify left bottom mirror))
    )
    (fp_text value "C_47u_0603" (at 0 -1.6 90) (layer "B.Fab")
      (effects (font (size 0.7 0.7) (thickness 0.15)) (justify left bottom mirror))
    )
    (fp_text user "License: Apache-2.0" (at -1.682 -5.895 90) (layer "B.Fab") hide
      (effects (font (size 0.7 0.7) (thickness 0.15)) (justify left bottom mirror))
    )
    (fp_text user "${REFERENCE}" (at -1.682 -3.895 90) (layer "B.Fab") hide
      (effects (font (size 0.7 0.7) (thickness 0.15)) (justify left bottom mirror))
    )
    (fp_text user "Author: Antmicro" (at -1.682 -4.894 90) (layer "B.Fab") hide
      (effects (font (size 0.7 0.7) (thickness 0.15)) (justify left bottom mirror))
    )
    (fp_line (start -0.3 -0.3) (end 0.3 -0.3) (layer "B.SilkS") (width 0.15))
    (fp_line (start -0.3 0.3) (end 0.3 0.3) (layer "B.SilkS") (width 0.15))
    (fp_rect (start -1.24 0.7) (end 1.24 -0.7) (layer "B.CrtYd") (width 0.05) (fill none))
    (fp_rect (start -0.8 0.4) (end 0.8 -0.4) (layer "B.Fab") (width 0.15) (fill none))
    (pad "1" smd roundrect (at -0.7 0 270) (size 0.6 0.8) (layers "B.Cu" "B.Paste" "B.Mask") (roundrect_rratio 0.2)
      (net 66 "USB_VBUS") (pintype "passive"))
    (pad "2" smd roundrect (at 0.7 0 270) (size 0.6 0.8) (layers "B.Cu" "B.Paste" "B.Mask") (roundrect_rratio 0.2)
      (net 1 "GND") (pintype "passive"))
  )

  (footprint "sa800u-baseboard-hw-footprints:C_0402_1005Metric" (layer "B.Cu")
    (tedit 616D63CF)
    (at 110.55 137.5 180)
    (descr "Capacitor SMD 0402")
    (tags "capacitor SMD 0402")
    (property "Author" "Antmicro")
    (property "Dielectric" "X5R")
    (property "License" "Apache-2.0")
    (property "MPN" "GRM155R61H104KE14D")
    (property "Manufacturer" "Murata")
    (property "Sheetfile" "usb-c-interface.kicad_sch")
    (property "Sheetname" "USB-C Interface ")
    (property "Val" "100n")
    (property "Voltage" "50V")
    (attr smd)
    (fp_text reference "C63" (at -1.39 1.55) (layer "B.SilkS")
      (effects (font (size 0.7 0.7) (thickness 0.15)) (justify left bottom mirror))
    )
    (fp_text value "C_100n_0402" (at 0 -1.4) (layer "B.Fab")
      (effects (font (size 0.7 0.7) (thickness 0.15)) (justify left bottom mirror))
    )
    (fp_text user "${REFERENCE}" (at -0.932 -3.168) (layer "B.Fab") hide
      (effects (font (size 0.7 0.7) (thickness 0.15)) (justify left bottom mirror))
    )
    (fp_text user "License: Apache-2.0" (at -0.932 -5.17) (layer "B.Fab") hide
      (effects (font (size 0.7 0.7) (thickness 0.15)) (justify left bottom mirror))
    )
    (fp_text user "Author: Antmicro" (at -0.932 -4.17) (layer "B.Fab") hide
      (effects (font (size 0.7 0.7) (thickness 0.15)) (justify left bottom mirror))
    )
    (fp_rect (start -0.94 0.47) (end 0.94 -0.47) (layer "B.CrtYd") (width 0.05) (fill none))
    (fp_rect (start -0.499 0.249) (end 0.499 -0.249) (layer "B.Fab") (width 0.15) (fill none))
    (pad "1" smd roundrect (at -0.484 0 180) (size 0.59 0.64) (layers "B.Cu" "B.Paste" "B.Mask") (roundrect_rratio 0.25)
      (net 134 "1V8_SYS") (pintype "passive"))
    (pad "2" smd roundrect (at 0.484 0 180) (size 0.59 0.64) (layers "B.Cu" "B.Paste" "B.Mask") (roundrect_rratio 0.25)
      (net 1 "GND") (pintype "passive"))
  )

  (footprint "sa800u-baseboard-hw-footprints:C_0402_1005Metric" (layer "B.Cu")
    (tedit 616D63CF)
    (at 110.55 138.7 180)
    (descr "Capacitor SMD 0402")
    (tags "capacitor SMD 0402")
    (property "Author" "Antmicro")
    (property "Dielectric" "X5R")
    (property "License" "Apache-2.0")
    (property "MPN" "GRM155R61H104KE14D")
    (property "Manufacturer" "Murata")
    (property "Sheetfile" "usb-c-interface.kicad_sch")
    (property "Sheetname" "USB-C Interface ")
    (property "Val" "100n")
    (property "Voltage" "50V")
    (attr smd)
    (fp_text reference "C65" (at -1.41 1.81) (layer "B.SilkS")
      (effects (font (size 0.7 0.7) (thickness 0.15)) (justify left bottom mirror))
    )
    (fp_text value "C_100n_0402" (at 0 -1.4) (layer "B.Fab")
      (effects (font (size 0.7 0.7) (thickness 0.15)) (justify left bottom mirror))
    )
    (fp_text user "Author: Antmicro" (at -0.932 -4.17) (layer "B.Fab") hide
      (effects (font (size 0.7 0.7) (thickness 0.15)) (justify left bottom mirror))
    )
    (fp_text user "${REFERENCE}" (at -0.932 -3.168) (layer "B.Fab") hide
      (effects (font (size 0.7 0.7) (thickness 0.15)) (justify left bottom mirror))
    )
    (fp_text user "License: Apache-2.0" (at -0.932 -5.17) (layer "B.Fab") hide
      (effects (font (size 0.7 0.7) (thickness 0.15)) (justify left bottom mirror))
    )
    (fp_rect (start -0.94 0.47) (end 0.94 -0.47) (layer "B.CrtYd") (width 0.05) (fill none))
    (fp_rect (start -0.499 0.249) (end 0.499 -0.249) (layer "B.Fab") (width 0.15) (fill none))
    (pad "1" smd roundrect (at -0.484 0 180) (size 0.59 0.64) (layers "B.Cu" "B.Paste" "B.Mask") (roundrect_rratio 0.25)
      (net 133 "5V_SYS") (pintype "passive"))
    (pad "2" smd roundrect (at 0.484 0 180) (size 0.59 0.64) (layers "B.Cu" "B.Paste" "B.Mask") (roundrect_rratio 0.25)
      (net 1 "GND") (pintype "passive"))
  )

  (footprint "sa800u-baseboard-hw-footprints:R_0402_1005Metric" (layer "B.Cu")
    (tedit 5FD9C158)
    (at 110 140.9 90)
    (descr "Resistor SMD 0402")
    (tags "resistor SMD 0402")
    (property "Author" "Antmicro")
    (property "License" "Apache-2.0")
    (property "MPN" "CR0402-FX-1003GLF")
    (property "Manufacturer" "Bourns")
    (property "Sheetfile" "usb-c-interface.kicad_sch")
    (property "Sheetname" "USB-C Interface ")
    (property "Tolerance" "1%")
    (property "Val" "100k")
    (attr smd)
    (fp_text reference "R63" (at 1.06 3.34 270) (layer "B.SilkS")
      (effects (font (size 0.7 0.7) (thickness 0.15)) (justify left bottom mirror))
    )
    (fp_text value "R_100k_0402" (at 0 -1.4 270) (layer "B.Fab")
      (effects (font (size 0.7 0.7) (thickness 0.15)) (justify left bottom mirror))
    )
    (fp_text user "Author: Antmicro" (at -0.95 -4.169 270) (layer "B.Fab") hide
      (effects (font (size 0.7 0.7) (thickness 0.15)) (justify left bottom mirror))
    )
    (fp_text user "License: Apache-2.0" (at -0.95 -5.169 270) (layer "B.Fab") hide
      (effects (font (size 0.7 0.7) (thickness 0.15)) (justify left bottom mirror))
    )
    (fp_text user "${REFERENCE}" (at -0.95 -3.168 270) (layer "B.Fab") hide
      (effects (font (size 0.7 0.7) (thickness 0.15)) (justify left bottom mirror))
    )
    (fp_rect (start -0.93 0.47) (end 0.93 -0.47) (layer "B.CrtYd") (width 0.05) (fill none))
    (fp_rect (start -0.5 0.25) (end 0.5 -0.25) (layer "B.Fab") (width 0.15) (fill none))
    (pad "1" smd roundrect (at -0.485 0 90) (size 0.59 0.64) (layers "B.Cu" "B.Paste" "B.Mask") (roundrect_rratio 0.25)
      (net 292 "/USB-C Interface /USB2_FAULT_5V") (pintype "passive"))
    (pad "2" smd roundrect (at 0.485 0 90) (size 0.59 0.64) (layers "B.Cu" "B.Paste" "B.Mask") (roundrect_rratio 0.25)
      (net 133 "5V_SYS") (pintype "passive"))
  )

  (footprint "sa800u-baseboard-hw-footprints:R_0402_1005Metric" (layer "B.Cu")
    (tedit 5FD9C158)
    (at 111 146.4)
    (descr "Resistor SMD 0402")
    (tags "resistor SMD 0402")
    (property "Author" "Antmicro")
    (property "License" "Apache-2.0")
    (property "MPN" "ERA2AED104X")
    (property "Manufacturer" "Panasonic")
    (property "Sheetfile" "usb-c-interface.kicad_sch")
    (property "Sheetname" "USB-C Interface ")
    (property "Val" "100k_0.5%")
    (attr smd)
    (fp_text reference "R59" (at 3.07 0.39 180) (layer "B.SilkS")
      (effects (font (size 0.7 0.7) (thickness 0.15)) (justify left bottom mirror))
    )
    (fp_text value "R_100k_0.5%_0402" (at 0 -1.4 180) (layer "B.Fab")
      (effects (font (size 0.7 0.7) (thickness 0.15)) (justify left bottom mirror))
    )
    (fp_text user "${REFERENCE}" (at -0.95 -3.168 180) (layer "B.Fab") hide
      (effects (font (size 0.7 0.7) (thickness 0.15)) (justify left bottom mirror))
    )
    (fp_text user "Author: Antmicro" (at -0.95 -4.169 180) (layer "B.Fab") hide
      (effects (font (size 0.7 0.7) (thickness 0.15)) (justify left bottom mirror))
    )
    (fp_text user "License: Apache-2.0" (at -0.95 -5.169 180) (layer "B.Fab") hide
      (effects (font (size 0.7 0.7) (thickness 0.15)) (justify left bottom mirror))
    )
    (fp_rect (start -0.93 0.47) (end 0.93 -0.47) (layer "B.CrtYd") (width 0.05) (fill none))
    (fp_rect (start -0.5 0.25) (end 0.5 -0.25) (layer "B.Fab") (width 0.15) (fill none))
    (pad "1" smd roundrect (at -0.485 0) (size 0.59 0.64) (layers "B.Cu" "B.Paste" "B.Mask") (roundrect_rratio 0.25)
      (net 396 "Net-(R59-Pad1)") (pintype "passive"))
    (pad "2" smd roundrect (at 0.485 0) (size 0.59 0.64) (layers "B.Cu" "B.Paste" "B.Mask") (roundrect_rratio 0.25)
      (net 1 "GND") (pintype "passive"))
  )

  (footprint "sa800u-baseboard-hw-footprints:R_0402_1005Metric" (layer "B.Cu")
    (tedit 5FD9C158)
    (at 112 140.9 90)
    (descr "Resistor SMD 0402")
    (tags "resistor SMD 0402")
    (property "Author" "Antmicro")
    (property "License" "Apache-2.0")
    (property "MPN" "CR0402-FX-1003GLF")
    (property "Manufacturer" "Bourns")
    (property "Sheetfile" "usb-c-interface.kicad_sch")
    (property "Sheetname" "USB-C Interface ")
    (property "Tolerance" "1%")
    (property "Val" "100k")
    (attr smd)
    (fp_text reference "R60" (at 1.06 3.34 270) (layer "B.SilkS")
      (effects (font (size 0.7 0.7) (thickness 0.15)) (justify left bottom mirror))
    )
    (fp_text value "R_100k_0402" (at 0 -1.4 270) (layer "B.Fab")
      (effects (font (size 0.7 0.7) (thickness 0.15)) (justify left bottom mirror))
    )
    (fp_text user "License: Apache-2.0" (at -0.95 -5.169 270) (layer "B.Fab") hide
      (effects (font (size 0.7 0.7) (thickness 0.15)) (justify left bottom mirror))
    )
    (fp_text user "${REFERENCE}" (at -0.95 -3.168 270) (layer "B.Fab") hide
      (effects (font (size 0.7 0.7) (thickness 0.15)) (justify left bottom mirror))
    )
    (fp_text user "Author: Antmicro" (at -0.95 -4.169 270) (layer "B.Fab") hide
      (effects (font (size 0.7 0.7) (thickness 0.15)) (justify left bottom mirror))
    )
    (fp_rect (start -0.93 0.47) (end 0.93 -0.47) (layer "B.CrtYd") (width 0.05) (fill none))
    (fp_rect (start -0.5 0.25) (end 0.5 -0.25) (layer "B.Fab") (width 0.15) (fill none))
    (pad "1" smd roundrect (at -0.485 0 90) (size 0.59 0.64) (layers "B.Cu" "B.Paste" "B.Mask") (roundrect_rratio 0.25)
      (net 290 "/USB-C Interface /USB2_CC_SELECT") (pintype "passive"))
    (pad "2" smd roundrect (at 0.485 0 90) (size 0.59 0.64) (layers "B.Cu" "B.Paste" "B.Mask") (roundrect_rratio 0.25)
      (net 133 "5V_SYS") (pintype "passive"))
  )

  (footprint "sa800u-baseboard-hw-footprints:C_0603_1608Metric" (layer "B.Cu")
    (tedit 5D5E94D2)
    (at 106.9 142.85 -90)
    (descr "Capacitor SMD 0603")
    (tags "capacitor 0603")
    (property "Author" "Antmicro")
    (property "Dielectric" "")
    (property "License" "Apache-2.0")
    (property "MPN" "GRM188R60J476ME15D")
    (property "Manufacturer" "Murata")
    (property "Sheetfile" "usb-c-interface.kicad_sch")
    (property "Sheetname" "USB-C Interface ")
    (property "Val" "47u")
    (property "Voltage" "")
    (attr smd)
    (fp_text reference "C58" (at -1.63 0.54 90) (layer "B.SilkS")
      (effects (font (size 0.7 0.7) (thickness 0.15)) (justify left bottom mirror))
    )
    (fp_text value "C_47u_0603" (at 0 -1.6 90) (layer "B.Fab")
      (effects (font (size 0.7 0.7) (thickness 0.15)) (justify left bottom mirror))
    )
    (fp_text user "License: Apache-2.0" (at -1.682 -5.895 90) (layer "B.Fab") hide
      (effects (font (size 0.7 0.7) (thickness 0.15)) (justify left bottom mirror))
    )
    (fp_text user "Author: Antmicro" (at -1.682 -4.894 90) (layer "B.Fab") hide
      (effects (font (size 0.7 0.7) (thickness 0.15)) (justify left bottom mirror))
    )
    (fp_text user "${REFERENCE}" (at -1.682 -3.895 90) (layer "B.Fab") hide
      (effects (font (size 0.7 0.7) (thickness 0.15)) (justify left bottom mirror))
    )
    (fp_line (start -0.3 -0.3) (end 0.3 -0.3) (layer "B.SilkS") (width 0.15))
    (fp_line (start -0.3 0.3) (end 0.3 0.3) (layer "B.SilkS") (width 0.15))
    (fp_rect (start -1.24 0.7) (end 1.24 -0.7) (layer "B.CrtYd") (width 0.05) (fill none))
    (fp_rect (start -0.8 0.4) (end 0.8 -0.4) (layer "B.Fab") (width 0.15) (fill none))
    (pad "1" smd roundrect (at -0.7 0 270) (size 0.6 0.8) (layers "B.Cu" "B.Paste" "B.Mask") (roundrect_rratio 0.2)
      (net 133 "5V_SYS") (pintype "passive"))
    (pad "2" smd roundrect (at 0.7 0 270) (size 0.6 0.8) (layers "B.Cu" "B.Paste" "B.Mask") (roundrect_rratio 0.2)
      (net 1 "GND") (pintype "passive"))
  )

  (footprint "sa800u-baseboard-hw-footprints:C_0603_1608Metric" (layer "B.Cu")
    (tedit 5D5E94D2)
    (at 107.25 139.6 90)
    (descr "Capacitor SMD 0603")
    (tags "capacitor 0603")
    (property "Author" "Antmicro")
    (property "Dielectric" "")
    (property "License" "Apache-2.0")
    (property "MPN" "GRM188R60J476ME15D")
    (property "Manufacturer" "Murata")
    (property "Sheetfile" "usb-c-interface.kicad_sch")
    (property "Sheetname" "USB-C Interface ")
    (property "Val" "47u")
    (property "Voltage" "")
    (attr smd)
    (fp_text reference "C59" (at 3.13 0.38 270) (layer "B.SilkS")
      (effects (font (size 0.7 0.7) (thickness 0.15)) (justify left bottom mirror))
    )
    (fp_text value "C_47u_0603" (at 0 -1.6 270) (layer "B.Fab")
      (effects (font (size 0.7 0.7) (thickness 0.15)) (justify left bottom mirror))
    )
    (fp_text user "License: Apache-2.0" (at -1.682 -5.895 270) (layer "B.Fab") hide
      (effects (font (size 0.7 0.7) (thickness 0.15)) (justify left bottom mirror))
    )
    (fp_text user "Author: Antmicro" (at -1.682 -4.894 270) (layer "B.Fab") hide
      (effects (font (size 0.7 0.7) (thickness 0.15)) (justify left bottom mirror))
    )
    (fp_text user "${REFERENCE}" (at -1.682 -3.895 270) (layer "B.Fab") hide
      (effects (font (size 0.7 0.7) (thickness 0.15)) (justify left bottom mirror))
    )
    (fp_line (start -0.3 -0.3) (end 0.3 -0.3) (layer "B.SilkS") (width 0.15))
    (fp_line (start -0.3 0.3) (end 0.3 0.3) (layer "B.SilkS") (width 0.15))
    (fp_rect (start -1.24 0.7) (end 1.24 -0.7) (layer "B.CrtYd") (width 0.05) (fill none))
    (fp_rect (start -0.8 0.4) (end 0.8 -0.4) (layer "B.Fab") (width 0.15) (fill none))
    (pad "1" smd roundrect (at -0.7 0 90) (size 0.6 0.8) (layers "B.Cu" "B.Paste" "B.Mask") (roundrect_rratio 0.2)
      (net 133 "5V_SYS") (pintype "passive"))
    (pad "2" smd roundrect (at 0.7 0 90) (size 0.6 0.8) (layers "B.Cu" "B.Paste" "B.Mask") (roundrect_rratio 0.2)
      (net 1 "GND") (pintype "passive"))
  )

  (footprint "sa800u-baseboard-hw-footprints:C_0603_1608Metric" (layer "B.Cu")
    (tedit 5D5E94D2)
    (at 108.75 139.6 90)
    (descr "Capacitor SMD 0603")
    (tags "capacitor 0603")
    (property "Author" "Antmicro")
    (property "Dielectric" "")
    (property "License" "Apache-2.0")
    (property "MPN" "GRM188R60J476ME15D")
    (property "Manufacturer" "Murata")
    (property "Sheetfile" "usb-c-interface.kicad_sch")
    (property "Sheetname" "USB-C Interface ")
    (property "Val" "47u")
    (property "Voltage" "")
    (attr smd)
    (fp_text reference "C62" (at 3.13 0.38 270) (layer "B.SilkS")
      (effects (font (size 0.7 0.7) (thickness 0.15)) (justify left bottom mirror))
    )
    (fp_text value "C_47u_0603" (at 0 -1.6 270) (layer "B.Fab")
      (effects (font (size 0.7 0.7) (thickness 0.15)) (justify left bottom mirror))
    )
    (fp_text user "${REFERENCE}" (at -1.682 -3.895 270) (layer "B.Fab") hide
      (effects (font (size 0.7 0.7) (thickness 0.15)) (justify left bottom mirror))
    )
    (fp_text user "License: Apache-2.0" (at -1.682 -5.895 270) (layer "B.Fab") hide
      (effects (font (size 0.7 0.7) (thickness 0.15)) (justify left bottom mirror))
    )
    (fp_text user "Author: Antmicro" (at -1.682 -4.894 270) (layer "B.Fab") hide
      (effects (font (size 0.7 0.7) (thickness 0.15)) (justify left bottom mirror))
    )
    (fp_line (start -0.3 -0.3) (end 0.3 -0.3) (layer "B.SilkS") (width 0.15))
    (fp_line (start -0.3 0.3) (end 0.3 0.3) (layer "B.SilkS") (width 0.15))
    (fp_rect (start -1.24 0.7) (end 1.24 -0.7) (layer "B.CrtYd") (width 0.05) (fill none))
    (fp_rect (start -0.8 0.4) (end 0.8 -0.4) (layer "B.Fab") (width 0.15) (fill none))
    (pad "1" smd roundrect (at -0.7 0 90) (size 0.6 0.8) (layers "B.Cu" "B.Paste" "B.Mask") (roundrect_rratio 0.2)
      (net 133 "5V_SYS") (pintype "passive"))
    (pad "2" smd roundrect (at 0.7 0 90) (size 0.6 0.8) (layers "B.Cu" "B.Paste" "B.Mask") (roundrect_rratio 0.2)
      (net 1 "GND") (pintype "passive"))
  )

  (footprint "sa800u-baseboard-hw-footprints:C_0402_1005Metric" (layer "B.Cu")
    (tedit 616D63CF)
    (at 107.5 147.25 -90)
    (descr "Capacitor SMD 0402")
    (tags "capacitor SMD 0402")
    (property "Author" "Antmicro")
    (property "Dielectric" "")
    (property "License" "Apache-2.0")
    (property "MPN" "CC0402MRX5R5BB106")
    (property "Manufacturer" "Yaego")
    (property "Sheetfile" "usb-c-interface.kicad_sch")
    (property "Sheetname" "USB-C Interface ")
    (property "Val" "10u")
    (property "Voltage" "")
    (attr smd)
    (fp_text reference "C71" (at -1.13 0.64 90) (layer "B.SilkS")
      (effects (font (size 0.7 0.7) (thickness 0.15)) (justify left bottom mirror))
    )
    (fp_text value "C_10u_0402" (at 0 -1.4 90) (layer "B.Fab")
      (effects (font (size 0.7 0.7) (thickness 0.15)) (justify left bottom mirror))
    )
    (fp_text user "License: Apache-2.0" (at -0.932 -5.17 90) (layer "B.Fab") hide
      (effects (font (size 0.7 0.7) (thickness 0.15)) (justify left bottom mirror))
    )
    (fp_text user "Author: Antmicro" (at -0.932 -4.17 90) (layer "B.Fab") hide
      (effects (font (size 0.7 0.7) (thickness 0.15)) (justify left bottom mirror))
    )
    (fp_text user "${REFERENCE}" (at -0.932 -3.168 90) (layer "B.Fab") hide
      (effects (font (size 0.7 0.7) (thickness 0.15)) (justify left bottom mirror))
    )
    (fp_rect (start -0.94 0.47) (end 0.94 -0.47) (layer "B.CrtYd") (width 0.05) (fill none))
    (fp_rect (start -0.499 0.249) (end 0.499 -0.249) (layer "B.Fab") (width 0.15) (fill none))
    (pad "1" smd roundrect (at -0.484 0 270) (size 0.59 0.64) (layers "B.Cu" "B.Paste" "B.Mask") (roundrect_rratio 0.25)
      (net 210 "/USB-C Interface /USB2_5V") (pintype "passive"))
    (pad "2" smd roundrect (at 0.484 0 270) (size 0.59 0.64) (layers "B.Cu" "B.Paste" "B.Mask") (roundrect_rratio 0.25)
      (net 1 "GND") (pintype "passive"))
  )

  (footprint "sa800u-baseboard-hw-footprints:R_0402_1005Metric" (layer "B.Cu")
    (tedit 5FD9C158)
    (at 111 140.9 90)
    (descr "Resistor SMD 0402")
    (tags "resistor SMD 0402")
    (property "Author" "Antmicro")
    (property "License" "Apache-2.0")
    (property "MPN" "CR0402-FX-1003GLF")
    (property "Manufacturer" "Bourns")
    (property "Sheetfile" "usb-c-interface.kicad_sch")
    (property "Sheetname" "USB-C Interface ")
    (property "Tolerance" "1%")
    (property "Val" "100k")
    (attr smd)
    (fp_text reference "R61" (at 1.06 3.34 270) (layer "B.SilkS")
      (effects (font (size 0.7 0.7) (thickness 0.15)) (justify left bottom mirror))
    )
    (fp_text value "R_100k_0402" (at 0 -1.4 270) (layer "B.Fab")
      (effects (font (size 0.7 0.7) (thickness 0.15)) (justify left bottom mirror))
    )
    (fp_text user "Author: Antmicro" (at -0.95 -4.169 270) (layer "B.Fab") hide
      (effects (font (size 0.7 0.7) (thickness 0.15)) (justify left bottom mirror))
    )
    (fp_text user "License: Apache-2.0" (at -0.95 -5.169 270) (layer "B.Fab") hide
      (effects (font (size 0.7 0.7) (thickness 0.15)) (justify left bottom mirror))
    )
    (fp_text user "${REFERENCE}" (at -0.95 -3.168 270) (layer "B.Fab") hide
      (effects (font (size 0.7 0.7) (thickness 0.15)) (justify left bottom mirror))
    )
    (fp_rect (start -0.93 0.47) (end 0.93 -0.47) (layer "B.CrtYd") (width 0.05) (fill none))
    (fp_rect (start -0.5 0.25) (end 0.5 -0.25) (layer "B.Fab") (width 0.15) (fill none))
    (pad "1" smd roundrect (at -0.485 0 90) (size 0.59 0.64) (layers "B.Cu" "B.Paste" "B.Mask") (roundrect_rratio 0.25)
      (net 291 "/USB-C Interface /USB2_SINK_5V") (pintype "passive"))
    (pad "2" smd roundrect (at 0.485 0 90) (size 0.59 0.64) (layers "B.Cu" "B.Paste" "B.Mask") (roundrect_rratio 0.25)
      (net 133 "5V_SYS") (pintype "passive"))
  )

  (footprint "sa800u-baseboard-hw-footprints:C_0402_1005Metric" (layer "B.Cu")
    (tedit 616D63CF)
    (at 99.5 138.1 -90)
    (descr "Capacitor SMD 0402")
    (tags "capacitor SMD 0402")
    (property "Author" "Antmicro")
    (property "Dielectric" "X5R")
    (property "License" "Apache-2.0")
    (property "MPN" "GRM155R61H104KE14D")
    (property "Manufacturer" "Murata")
    (property "Sheetfile" "usb-c-interface.kicad_sch")
    (property "Sheetname" "USB-C Interface ")
    (property "Val" "100n")
    (property "Voltage" "50V")
    (attr smd)
    (fp_text reference "C83" (at -3.1 -0.36 90) (layer "B.SilkS")
      (effects (font (size 0.7 0.7) (thickness 0.15)) (justify left bottom mirror))
    )
    (fp_text value "C_100n_0402" (at 0 -1.4 90) (layer "B.Fab")
      (effects (font (size 0.7 0.7) (thickness 0.15)) (justify left bottom mirror))
    )
    (fp_text user "Author: Antmicro" (at -0.932 -4.17 90) (layer "B.Fab") hide
      (effects (font (size 0.7 0.7) (thickness 0.15)) (justify left bottom mirror))
    )
    (fp_text user "${REFERENCE}" (at -0.932 -3.168 90) (layer "B.Fab") hide
      (effects (font (size 0.7 0.7) (thickness 0.15)) (justify left bottom mirror))
    )
    (fp_text user "License: Apache-2.0" (at -0.932 -5.17 90) (layer "B.Fab") hide
      (effects (font (size 0.7 0.7) (thickness 0.15)) (justify left bottom mirror))
    )
    (fp_rect (start -0.94 0.47) (end 0.94 -0.47) (layer "B.CrtYd") (width 0.05) (fill none))
    (fp_rect (start -0.499 0.249) (end 0.499 -0.249) (layer "B.Fab") (width 0.15) (fill none))
    (pad "1" smd roundrect (at -0.484 0 270) (size 0.59 0.64) (layers "B.Cu" "B.Paste" "B.Mask") (roundrect_rratio 0.25)
      (net 64 "USB1_SS_TX0_P") (pintype "passive"))
    (pad "2" smd roundrect (at 0.484 0 270) (size 0.59 0.64) (layers "B.Cu" "B.Paste" "B.Mask") (roundrect_rratio 0.25)
      (net 302 "/USB-C Interface /USB1C_TX0_C_P") (pintype "passive"))
  )

  (footprint "sa800u-baseboard-hw-footprints:C_0402_1005Metric" (layer "B.Cu")
    (tedit 616D63CF)
    (at 98.5 138.1 90)
    (descr "Capacitor SMD 0402")
    (tags "capacitor SMD 0402")
    (property "Author" "Antmicro")
    (property "Dielectric" "X5R")
    (property "License" "Apache-2.0")
    (property "MPN" "GRM155R61H104KE14D")
    (property "Manufacturer" "Murata")
    (property "Sheetfile" "usb-c-interface.kicad_sch")
    (property "Sheetname" "USB-C Interface ")
    (property "Val" "100n")
    (property "Voltage" "50V")
    (attr smd)
    (fp_text reference "C87" (at 3.07 0.36 270) (layer "B.SilkS")
      (effects (font (size 0.7 0.7) (thickness 0.15)) (justify left bottom mirror))
    )
    (fp_text value "C_100n_0402" (at 0 -1.4 270) (layer "B.Fab")
      (effects (font (size 0.7 0.7) (thickness 0.15)) (justify left bottom mirror))
    )
    (fp_text user "License: Apache-2.0" (at -0.932 -5.17 270) (layer "B.Fab") hide
      (effects (font (size 0.7 0.7) (thickness 0.15)) (justify left bottom mirror))
    )
    (fp_text user "Author: Antmicro" (at -0.932 -4.17 270) (layer "B.Fab") hide
      (effects (font (size 0.7 0.7) (thickness 0.15)) (justify left bottom mirror))
    )
    (fp_text user "${REFERENCE}" (at -0.932 -3.168 270) (layer "B.Fab") hide
      (effects (font (size 0.7 0.7) (thickness 0.15)) (justify left bottom mirror))
    )
    (fp_rect (start -0.94 0.47) (end 0.94 -0.47) (layer "B.CrtYd") (width 0.05) (fill none))
    (fp_rect (start -0.499 0.249) (end 0.499 -0.249) (layer "B.Fab") (width 0.15) (fill none))
    (pad "1" smd roundrect (at -0.484 0 90) (size 0.59 0.64) (layers "B.Cu" "B.Paste" "B.Mask") (roundrect_rratio 0.25)
      (net 323 "/USB-C Interface /USB1C_RX0_C_N") (pintype "passive"))
    (pad "2" smd roundrect (at 0.484 0 90) (size 0.59 0.64) (layers "B.Cu" "B.Paste" "B.Mask") (roundrect_rratio 0.25)
      (net 70 "USB1_SS_RX0_N") (pintype "passive"))
  )

  (footprint "sa800u-baseboard-hw-footprints:C_0402_1005Metric" (layer "B.Cu")
    (tedit 616D63CF)
    (at 100.5 138.1 -90)
    (descr "Capacitor SMD 0402")
    (tags "capacitor SMD 0402")
    (property "Author" "Antmicro")
    (property "Dielectric" "X5R")
    (property "License" "Apache-2.0")
    (property "MPN" "GRM155R61H104KE14D")
    (property "Manufacturer" "Murata")
    (property "Sheetfile" "usb-c-interface.kicad_sch")
    (property "Sheetname" "USB-C Interface ")
    (property "Val" "100n")
    (property "Voltage" "50V")
    (attr smd)
    (fp_text reference "C79" (at -3.098 -0.31 90) (layer "B.SilkS")
      (effects (font (size 0.7 0.7) (thickness 0.15)) (justify left bottom mirror))
    )
    (fp_text value "C_100n_0402" (at 0 -1.4 90) (layer "B.Fab")
      (effects (font (size 0.7 0.7) (thickness 0.15)) (justify left bottom mirror))
    )
    (fp_text user "License: Apache-2.0" (at -0.932 -5.17 90) (layer "B.Fab") hide
      (effects (font (size 0.7 0.7) (thickness 0.15)) (justify left bottom mirror))
    )
    (fp_text user "${REFERENCE}" (at -0.932 -3.168 90) (layer "B.Fab") hide
      (effects (font (size 0.7 0.7) (thickness 0.15)) (justify left bottom mirror))
    )
    (fp_text user "Author: Antmicro" (at -0.932 -4.17 90) (layer "B.Fab") hide
      (effects (font (size 0.7 0.7) (thickness 0.15)) (justify left bottom mirror))
    )
    (fp_rect (start -0.94 0.47) (end 0.94 -0.47) (layer "B.CrtYd") (width 0.05) (fill none))
    (fp_rect (start -0.499 0.249) (end 0.499 -0.249) (layer "B.Fab") (width 0.15) (fill none))
    (pad "1" smd roundrect (at -0.484 0 270) (size 0.59 0.64) (layers "B.Cu" "B.Paste" "B.Mask") (roundrect_rratio 0.25)
      (net 65 "USB1_SS_TX0_N") (pintype "passive"))
    (pad "2" smd roundrect (at 0.484 0 270) (size 0.59 0.64) (layers "B.Cu" "B.Paste" "B.Mask") (roundrect_rratio 0.25)
      (net 303 "/USB-C Interface /USB1C_TX0_C_N") (pintype "passive"))
  )

  (footprint "sa800u-baseboard-hw-footprints:C_0402_1005Metric" (layer "B.Cu")
    (tedit 616D63CF)
    (at 104 138.1 -90)
    (descr "Capacitor SMD 0402")
    (tags "capacitor SMD 0402")
    (property "Author" "Antmicro")
    (property "Dielectric" "X5R")
    (property "License" "Apache-2.0")
    (property "MPN" "GRM155R61H104KE14D")
    (property "Manufacturer" "Murata")
    (property "Sheetfile" "usb-c-interface.kicad_sch")
    (property "Sheetname" "USB-C Interface ")
    (property "Val" "100n")
    (property "Voltage" "50V")
    (attr smd)
    (fp_text reference "C80" (at -3.07 -0.34 90) (layer "B.SilkS")
      (effects (font (size 0.7 0.7) (thickness 0.15)) (justify left bottom mirror))
    )
    (fp_text value "C_100n_0402" (at 0 -1.4 90) (layer "B.Fab")
      (effects (font (size 0.7 0.7) (thickness 0.15)) (justify left bottom mirror))
    )
    (fp_text user "${REFERENCE}" (at -0.932 -3.168 90) (layer "B.Fab") hide
      (effects (font (size 0.7 0.7) (thickness 0.15)) (justify left bottom mirror))
    )
    (fp_text user "License: Apache-2.0" (at -0.932 -5.17 90) (layer "B.Fab") hide
      (effects (font (size 0.7 0.7) (thickness 0.15)) (justify left bottom mirror))
    )
    (fp_text user "Author: Antmicro" (at -0.932 -4.17 90) (layer "B.Fab") hide
      (effects (font (size 0.7 0.7) (thickness 0.15)) (justify left bottom mirror))
    )
    (fp_rect (start -0.94 0.47) (end 0.94 -0.47) (layer "B.CrtYd") (width 0.05) (fill none))
    (fp_rect (start -0.499 0.249) (end 0.499 -0.249) (layer "B.Fab") (width 0.15) (fill none))
    (pad "1" smd roundrect (at -0.484 0 270) (size 0.59 0.64) (layers "B.Cu" "B.Paste" "B.Mask") (roundrect_rratio 0.25)
      (net 68 "USB1_SS_RX1_P") (pintype "passive"))
    (pad "2" smd roundrect (at 0.484 0 270) (size 0.59 0.64) (layers "B.Cu" "B.Paste" "B.Mask") (roundrect_rratio 0.25)
      (net 305 "/USB-C Interface /USB1C_RX1_C_P") (pintype "passive"))
  )

  (footprint "sa800u-baseboard-hw-footprints:C_0402_1005Metric" (layer "B.Cu")
    (tedit 616D63CF)
    (at 103 138.1 -90)
    (descr "Capacitor SMD 0402")
    (tags "capacitor SMD 0402")
    (property "Author" "Antmicro")
    (property "Dielectric" "X5R")
    (property "License" "Apache-2.0")
    (property "MPN" "GRM155R61H104KE14D")
    (property "Manufacturer" "Murata")
    (property "Sheetfile" "usb-c-interface.kicad_sch")
    (property "Sheetname" "USB-C Interface ")
    (property "Val" "100n")
    (property "Voltage" "50V")
    (attr smd)
    (fp_text reference "C84" (at -3.07 -0.34 90) (layer "B.SilkS")
      (effects (font (size 0.7 0.7) (thickness 0.15)) (justify left bottom mirror))
    )
    (fp_text value "C_100n_0402" (at 0 -1.4 90) (layer "B.Fab")
      (effects (font (size 0.7 0.7) (thickness 0.15)) (justify left bottom mirror))
    )
    (fp_text user "Author: Antmicro" (at -0.932 -4.17 90) (layer "B.Fab") hide
      (effects (font (size 0.7 0.7) (thickness 0.15)) (justify left bottom mirror))
    )
    (fp_text user "${REFERENCE}" (at -0.932 -3.168 90) (layer "B.Fab") hide
      (effects (font (size 0.7 0.7) (thickness 0.15)) (justify left bottom mirror))
    )
    (fp_text user "License: Apache-2.0" (at -0.932 -5.17 90) (layer "B.Fab") hide
      (effects (font (size 0.7 0.7) (thickness 0.15)) (justify left bottom mirror))
    )
    (fp_rect (start -0.94 0.47) (end 0.94 -0.47) (layer "B.CrtYd") (width 0.05) (fill none))
    (fp_rect (start -0.499 0.249) (end 0.499 -0.249) (layer "B.Fab") (width 0.15) (fill none))
    (pad "1" smd roundrect (at -0.484 0 270) (size 0.59 0.64) (layers "B.Cu" "B.Paste" "B.Mask") (roundrect_rratio 0.25)
      (net 67 "USB1_SS_RX1_N") (pintype "passive"))
    (pad "2" smd roundrect (at 0.484 0 270) (size 0.59 0.64) (layers "B.Cu" "B.Paste" "B.Mask") (roundrect_rratio 0.25)
      (net 304 "/USB-C Interface /USB1C_RX1_C_N") (pintype "passive"))
  )

  (footprint "sa800u-baseboard-hw-footprints:C_0402_1005Metric" (layer "B.Cu")
    (tedit 616D63CF)
    (at 106 138.1 90)
    (descr "Capacitor SMD 0402")
    (tags "capacitor SMD 0402")
    (property "Author" "Antmicro")
    (property "Dielectric" "X5R")
    (property "License" "Apache-2.0")
    (property "MPN" "GRM155R61H104KE14D")
    (property "Manufacturer" "Murata")
    (property "Sheetfile" "usb-c-interface.kicad_sch")
    (property "Sheetname" "USB-C Interface ")
    (property "Val" "100n")
    (property "Voltage" "50V")
    (attr smd)
    (fp_text reference "C88" (at 3.04 0.38 270) (layer "B.SilkS")
      (effects (font (size 0.7 0.7) (thickness 0.15)) (justify left bottom mirror))
    )
    (fp_text value "C_100n_0402" (at 0 -1.4 270) (layer "B.Fab")
      (effects (font (size 0.7 0.7) (thickness 0.15)) (justify left bottom mirror))
    )
    (fp_text user "License: Apache-2.0" (at -0.932 -5.17 270) (layer "B.Fab") hide
      (effects (font (size 0.7 0.7) (thickness 0.15)) (justify left bottom mirror))
    )
    (fp_text user "Author: Antmicro" (at -0.932 -4.17 270) (layer "B.Fab") hide
      (effects (font (size 0.7 0.7) (thickness 0.15)) (justify left bottom mirror))
    )
    (fp_text user "${REFERENCE}" (at -0.932 -3.168 270) (layer "B.Fab") hide
      (effects (font (size 0.7 0.7) (thickness 0.15)) (justify left bottom mirror))
    )
    (fp_rect (start -0.94 0.47) (end 0.94 -0.47) (layer "B.CrtYd") (width 0.05) (fill none))
    (fp_rect (start -0.499 0.249) (end 0.499 -0.249) (layer "B.Fab") (width 0.15) (fill none))
    (pad "1" smd roundrect (at -0.484 0 90) (size 0.59 0.64) (layers "B.Cu" "B.Paste" "B.Mask") (roundrect_rratio 0.25)
      (net 307 "/USB-C Interface /USB1C_TX1_C_P") (pintype "passive"))
    (pad "2" smd roundrect (at 0.484 0 90) (size 0.59 0.64) (layers "B.Cu" "B.Paste" "B.Mask") (roundrect_rratio 0.25)
      (net 72 "USB1_SS_TX1_P") (pintype "passive"))
  )

  (footprint "sa800u-baseboard-hw-footprints:C_0402_1005Metric" (layer "B.Cu")
    (tedit 616D63CF)
    (at 105 138.1 90)
    (descr "Capacitor SMD 0402")
    (tags "capacitor SMD 0402")
    (property "Author" "Antmicro")
    (property "Dielectric" "X5R")
    (property "License" "Apache-2.0")
    (property "MPN" "GRM155R61H104KE14D")
    (property "Manufacturer" "Murata")
    (property "Sheetfile" "usb-c-interface.kicad_sch")
    (property "Sheetname" "USB-C Interface ")
    (property "Val" "100n")
    (property "Voltage" "50V")
    (attr smd)
    (fp_text reference "C93" (at 3.04 0.38 270) (layer "B.SilkS")
      (effects (font (size 0.7 0.7) (thickness 0.15)) (justify left bottom mirror))
    )
    (fp_text value "C_100n_0402" (at 0 -1.4 270) (layer "B.Fab")
      (effects (font (size 0.7 0.7) (thickness 0.15)) (justify left bottom mirror))
    )
    (fp_text user "License: Apache-2.0" (at -0.932 -5.17 270) (layer "B.Fab") hide
      (effects (font (size 0.7 0.7) (thickness 0.15)) (justify left bottom mirror))
    )
    (fp_text user "Author: Antmicro" (at -0.932 -4.17 270) (layer "B.Fab") hide
      (effects (font (size 0.7 0.7) (thickness 0.15)) (justify left bottom mirror))
    )
    (fp_text user "${REFERENCE}" (at -0.932 -3.168 270) (layer "B.Fab") hide
      (effects (font (size 0.7 0.7) (thickness 0.15)) (justify left bottom mirror))
    )
    (fp_rect (start -0.94 0.47) (end 0.94 -0.47) (layer "B.CrtYd") (width 0.05) (fill none))
    (fp_rect (start -0.499 0.249) (end 0.499 -0.249) (layer "B.Fab") (width 0.15) (fill none))
    (pad "1" smd roundrect (at -0.484 0 90) (size 0.59 0.64) (layers "B.Cu" "B.Paste" "B.Mask") (roundrect_rratio 0.25)
      (net 306 "/USB-C Interface /USB1C_TX1_C_N") (pintype "passive"))
    (pad "2" smd roundrect (at 0.484 0 90) (size 0.59 0.64) (layers "B.Cu" "B.Paste" "B.Mask") (roundrect_rratio 0.25)
      (net 71 "USB1_SS_TX1_N") (pintype "passive"))
  )

  (footprint "sa800u-baseboard-hw-footprints:WSON-12-1EP_2x3mm_P0.5mm" (layer "B.Cu")
    (tedit 6215ECFB)
    (at 109.3 143.8 -90)
    (property "Author" "Antmicro")
    (property "License" "Apache-2.0")
    (property "MPN" "TPS25820DSST")
    (property "Manufacturer" "Texas Instruments")
    (property "Sheetfile" "usb-c-interface.kicad_sch")
    (property "Sheetname" "USB-C Interface ")
    (attr smd)
    (fp_text reference "U6" (at 2.21 -0.21 180) (layer "B.SilkS")
      (effects (font (size 0.7 0.7) (thickness 0.15)) (justify left bottom mirror))
    )
    (fp_text value "TPS25820DSST" (at 0 -2.6 90) (layer "B.Fab")
      (effects (font (size 0.7 0.7) (thickness 0.15)) (justify left bottom mirror))
    )
    (fp_text user "Author: Antmicro" (at -1.702 -4.498 90) (layer "B.Fab") hide
      (effects (font (size 0.7 0.7) (thickness 0.15)) (justify left bottom mirror))
    )
    (fp_text user "${REFERENCE}" (at -1.702 -5.698 90) (layer "B.Fab") hide
      (effects (font (size 0.7 0.7) (thickness 0.15)) (justify left bottom mirror))
    )
    (fp_text user "License: Apache-2.0" (at -1.702 -6.898 90) (layer "B.Fab") hide
      (effects (font (size 0.7 0.7) (thickness 0.15)) (justify left bottom mirror))
    )
    (fp_poly (pts
        (xy 0.473 -1.3)
        (xy -0.476 -1.3)
        (xy -0.476 -0.122)
        (xy 0.473 -0.122)
      ) (layer "B.Paste") (width 0.01) (fill solid))
    (fp_poly (pts
        (xy -0.476 1.301)
        (xy 0.473 1.301)
        (xy 0.473 0.125)
        (xy -0.476 0.125)
      ) (layer "B.Paste") (width 0.01) (fill solid))
    (fp_line (start -1 1.5) (end 0.997 1.5) (layer "B.SilkS") (width 0.15))
    (fp_line (start 0.997 -1.499) (end -1 -1.499) (layer "B.SilkS") (width 0.15))
    (fp_circle (center -1.3 1.551) (end -1.249 1.551) (layer "B.SilkS") (width 0.15) (fill solid))
    (fp_rect (start -1.3 1.7) (end 1.3 -1.7) (layer "B.CrtYd") (width 0.05) (fill none))
    (pad "1" smd roundrect (at -0.951 1.25 270) (size 0.5 0.25) (layers "B.Cu" "B.Paste" "B.Mask") (roundrect_rratio 0.2)
      (net 133 "5V_SYS") (pinfunction "IN") (pintype "power_in"))
    (pad "2" smd roundrect (at -0.951 0.75 270) (size 0.5 0.25) (layers "B.Cu" "B.Paste" "B.Mask") (roundrect_rratio 0.2)
      (net 133 "5V_SYS") (pinfunction "IN") (pintype "passive"))
    (pad "3" smd roundrect (at -0.951 0.25 270) (size 0.5 0.25) (layers "B.Cu" "B.Paste" "B.Mask") (roundrect_rratio 0.2)
      (net 1 "GND") (pinfunction "CHG") (pintype "input"))
    (pad "4" smd roundrect (at -0.951 -0.247 270) (size 0.5 0.25) (layers "B.Cu" "B.Paste" "B.Mask") (roundrect_rratio 0.2)
      (net 301 "/USB-C Interface /USB2_EN_5V") (pinfunction "EN") (pintype "input"))
    (pad "5" smd roundrect (at -0.951 -0.747 270) (size 0.5 0.25) (layers "B.Cu" "B.Paste" "B.Mask") (roundrect_rratio 0.2)
      (net 292 "/USB-C Interface /USB2_FAULT_5V") (pinfunction "nFAULT") (pintype "output"))
    (pad "6" smd roundrect (at -0.951 -1.249 270) (size 0.5 0.25) (layers "B.Cu" "B.Paste" "B.Mask") (roundrect_rratio 0.2)
      (net 291 "/USB-C Interface /USB2_SINK_5V") (pinfunction "nSINK") (pintype "output"))
    (pad "7" smd roundrect (at 0.948 -1.249 90) (size 0.5 0.25) (layers "B.Cu" "B.Paste" "B.Mask") (roundrect_rratio 0.2)
      (net 290 "/USB-C Interface /USB2_CC_SELECT") (pinfunction "nPOL") (pintype "output"))
    (pad "8" smd roundrect (at 0.948 -0.747 90) (size 0.5 0.25) (layers "B.Cu" "B.Paste" "B.Mask") (roundrect_rratio 0.2)
      (net 396 "Net-(R59-Pad1)") (pinfunction "REF") (pintype "input"))
    (pad "9" smd roundrect (at 0.948 -0.247 90) (size 0.5 0.25) (layers "B.Cu" "B.Paste" "B.Mask") (roundrect_rratio 0.2)
      (net 265 "/USB-C Interface /USB2_CC1") (pinfunction "CC1") (pintype "bidirectional"))
    (pad "10" smd roundrect (at 0.948 0.25 90) (size 0.5 0.25) (layers "B.Cu" "B.Paste" "B.Mask") (roundrect_rratio 0.2)
      (net 1 "GND") (pinfunction "GND") (pintype "input"))
    (pad "11" smd roundrect (at 0.948 0.75 90) (size 0.5 0.25) (layers "B.Cu" "B.Paste" "B.Mask") (roundrect_rratio 0.2)
      (net 264 "/USB-C Interface /USB2_CC2") (pinfunction "CC2") (pintype "bidirectional"))
    (pad "12" smd roundrect (at 0.948 1.25 90) (size 0.5 0.25) (layers "B.Cu" "B.Paste" "B.Mask") (roundrect_rratio 0.2)
      (net 210 "/USB-C Interface /USB2_5V") (pinfunction "OUT") (pintype "power_out"))
    (pad "13" smd roundrect (at 0 0 270) (size 1 2.65) (layers "B.Cu" "B.Paste" "B.Mask") (roundrect_rratio 0.05)
      (net 1 "GND") (pinfunction "GND") (pintype "passive") (solder_paste_margin_ratio -0.5))
  )

  (footprint "sa800u-baseboard-hw-footprints:DHVQFN-20-1EP_2.5x4.5_P0.5mm" (layer "B.Cu")
    (tedit 6215E186)
    (at 115.75 133.5 -90)
    (property "Author" "Antmicro")
    (property "License" "Apache-2.0")
    (property "MPN" "CBTL02043ABQ,115")
    (property "Manufacturer" "Nexperia")
    (property "Sheetfile" "usb-c-interface.kicad_sch")
    (property "Sheetname" "USB-C Interface ")
    (attr smd)
    (fp_text reference "U9" (at -2.19 2.45 90) (layer "B.SilkS")
      (effects (font (size 0.7 0.7) (thickness 0.15)) (justify left bottom mirror))
    )
    (fp_text value "CBTL02043ABQ,115" (at 0 -3.85 90) (layer "B.Fab")
      (effects (font (size 0.7 0.7) (thickness 0.15)) (justify left bottom mirror))
    )
    (fp_text user "Author: Antmicro" (at -1.95 -5.849 90) (layer "B.Fab") hide
      (effects (font (size 0.7 0.7) (thickness 0.15)) (justify left bottom mirror))
    )
    (fp_text user "License: Apache-2.0" (at -1.95 -7.049 90) (layer "B.Fab") hide
      (effects (font (size 0.7 0.7) (thickness 0.15)) (justify left bottom mirror))
    )
    (fp_text user "${REFERENCE}" (at -1.95 -8.249 90) (layer "B.Fab") hide
      (effects (font (size 0.7 0.7) (thickness 0.15)) (justify left bottom mirror))
    )
    (fp_poly (pts
        (xy -0.203 -0.2)
        (xy 0.2 -0.2)
        (xy 0.2 -0.847)
        (xy -0.203 -0.847)
      ) (layer "B.Paste") (width 0.01) (fill solid))
    (fp_poly (pts
        (xy 0.2 0.203)
        (xy -0.203 0.203)
        (xy -0.203 0.85)
        (xy 0.2 0.85)
      ) (layer "B.Paste") (width 0.01) (fill solid))
    (fp_line (start -1.25 2.25) (end -1.25 2) (layer "B.SilkS") (width 0.15))
    (fp_line (start 1.249 -2.249) (end 0.5 -2.249) (layer "B.SilkS") (width 0.15))
    (fp_line (start 1.249 -2.249) (end 1.25 -2) (layer "B.SilkS") (width 0.15))
    (fp_line (start 1.249 2.25) (end 1.25 2) (layer "B.SilkS") (width 0.15))
    (fp_line (start -1.25 -2.249) (end -1.25 -2) (layer "B.SilkS") (width 0.15))
    (fp_line (start 1.249 2.25) (end 0.5 2.25) (layer "B.SilkS") (width 0.15))
    (fp_line (start -1.25 2.25) (end -0.5 2.25) (layer "B.SilkS") (width 0.15))
    (fp_line (start -1.25 -2.249) (end -0.5 -2.249) (layer "B.SilkS") (width 0.15))
    (fp_circle (center -0.6 2.5) (end -0.551 2.5) (layer "B.SilkS") (width 0.15) (fill solid))
    (fp_rect (start -1.8 2.8) (end 1.8 -2.7) (layer "B.CrtYd") (width 0.05) (fill none))
    (pad "1" smd rect (at -0.248 2.261 270) (size 0.29 0.8) (layers "B.Cu" "B.Paste" "B.Mask")
      (net 131 "3V3_SYS") (pinfunction "VDD") (pintype "power_in") (solder_paste_margin -0.025))
    (pad "2" smd rect (at -1.26 1.75 180) (size 0.29 0.8) (layers "B.Cu" "B.Paste" "B.Mask")
      (net 1 "GND") (pinfunction "XSD") (pintype "input") (solder_paste_margin -0.025))
    (pad "3" smd rect (at -1.26 1.25 180) (size 0.29 0.8) (layers "B.Cu" "B.Paste" "B.Mask")
      (net 105 "USB2_SS_RX_P") (pinfunction "A0_P") (pintype "bidirectional") (solder_paste_margin -0.025))
    (pad "4" smd rect (at -1.26 0.75 180) (size 0.29 0.8) (layers "B.Cu" "B.Paste" "B.Mask")
      (net 104 "USB2_SS_RX_N") (pinfunction "A0_N") (pintype "bidirectional") (solder_paste_margin -0.025))
    (pad "5" smd rect (at -1.26 0.25 180) (size 0.29 0.8) (layers "B.Cu" "B.Paste" "B.Mask")
      (net 1 "GND") (pinfunction "GND") (pintype "passive") (solder_paste_margin -0.025))
    (pad "6" smd rect (at -1.26 -0.247 180) (size 0.29 0.8) (layers "B.Cu" "B.Paste" "B.Mask")
      (net 131 "3V3_SYS") (pinfunction "VDD") (pintype "passive") (solder_paste_margin -0.025))
    (pad "7" smd rect (at -1.26 -0.747 180) (size 0.29 0.8) (layers "B.Cu" "B.Paste" "B.Mask")
      (net 103 "USB2_SS_TX_P") (pinfunction "A1_P") (pintype "bidirectional") (solder_paste_margin -0.025))
    (pad "8" smd rect (at -1.26 -1.249 180) (size 0.29 0.8) (layers "B.Cu" "B.Paste" "B.Mask")
      (net 102 "USB2_SS_TX_N") (pinfunction "A1_N") (pintype "bidirectional") (solder_paste_margin -0.025))
    (pad "9" smd rect (at -1.26 -1.749 180) (size 0.29 0.8) (layers "B.Cu" "B.Paste" "B.Mask")
      (net 290 "/USB-C Interface /USB2_CC_SELECT") (pinfunction "SEL") (pintype "input") (solder_paste_margin -0.025))
    (pad "10" smd rect (at -0.248 -2.15 270) (size 0.29 0.8) (layers "B.Cu" "B.Paste" "B.Mask")
      (net 131 "3V3_SYS") (pinfunction "VDD") (pintype "passive") (solder_paste_margin -0.025))
    (pad "11" smd rect (at 0.249 -2.15 270) (size 0.29 0.8) (layers "B.Cu" "B.Paste" "B.Mask")
      (net 1 "GND") (pinfunction "GND") (pintype "power_in") (solder_paste_margin -0.025))
    (pad "12" smd rect (at 1.259 -1.749 180) (size 0.29 0.8) (layers "B.Cu" "B.Paste" "B.Mask")
      (net 225 "/USB-C Interface /USB2C_TX2_N") (pinfunction "C1_N") (pintype "bidirectional") (solder_paste_margin -0.025))
    (pad "13" smd rect (at 1.259 -1.249 180) (size 0.29 0.8) (layers "B.Cu" "B.Paste" "B.Mask")
      (net 221 "/USB-C Interface /USB2C_TX2_P") (pinfunction "C1_P") (pintype "bidirectional") (solder_paste_margin -0.025))
    (pad "14" smd rect (at 1.259 -0.747 180) (size 0.29 0.8) (layers "B.Cu" "B.Paste" "B.Mask")
      (net 218 "/USB-C Interface /USB2C_RX2_N") (pinfunction "C0_N") (pintype "bidirectional") (solder_paste_margin -0.025))
    (pad "15" smd rect (at 1.259 -0.247 180) (size 0.29 0.8) (layers "B.Cu" "B.Paste" "B.Mask")
      (net 214 "/USB-C Interface /USB2C_RX2_P") (pinfunction "C0_P") (pintype "bidirectional") (solder_paste_margin -0.025))
    (pad "16" smd rect (at 1.259 0.25 180) (size 0.29 0.8) (layers "B.Cu" "B.Paste" "B.Mask")
      (net 212 "/USB-C Interface /USB2C_TX1_N") (pinfunction "B1_N") (pintype "bidirectional") (solder_paste_margin -0.025))
    (pad "17" smd rect (at 1.259 0.75 180) (size 0.29 0.8) (layers "B.Cu" "B.Paste" "B.Mask")
      (net 216 "/USB-C Interface /USB2C_TX1_P") (pinfunction "B1_P") (pintype "bidirectional") (solder_paste_margin -0.025))
    (pad "18" smd rect (at 1.259 1.25 180) (size 0.29 0.8) (layers "B.Cu" "B.Paste" "B.Mask")
      (net 219 "/USB-C Interface /USB2C_RX1_N") (pinfunction "B0_N") (pintype "bidirectional") (solder_paste_margin -0.025))
    (pad "19" smd rect (at 1.259 1.75 180) (size 0.29 0.8) (layers "B.Cu" "B.Paste" "B.Mask")
      (net 223 "/USB-C Interface /USB2C_RX1_P") (pinfunction "B0_P") (pintype "bidirectional") (solder_paste_margin -0.025))
    (pad "20" smd rect (at 0.249 2.261 270) (size 0.29 0.8) (layers "B.Cu" "B.Paste" "B.Mask")
      (net 1 "GND") (pinfunction "GND") (pintype "passive") (solder_paste_margin -0.025))
    (pad "21" smd rect (at 0 0 90) (size 0.9 2.9) (layers "B.Cu" "B.Paste" "B.Mask")
      (net 1 "GND") (pinfunction "GND") (pintype "passive") (solder_paste_margin_ratio -0.5))
  )

  (footprint "sa800u-baseboard-hw-footprints:C_0402_1005Metric" (layer "B.Cu")
    (tedit 616D63CF)
    (at 114.25 138.95 -90)
    (descr "Capacitor SMD 0402")
    (tags "capacitor SMD 0402")
    (property "Author" "Antmicro")
    (property "Dielectric" "X5R")
    (property "License" "Apache-2.0")
    (property "MPN" "GRM155R61H104KE14D")
    (property "Manufacturer" "Murata")
    (property "Sheetfile" "usb-c-interface.kicad_sch")
    (property "Sheetname" "USB-C Interface ")
    (property "Val" "100n")
    (property "Voltage" "50V")
    (attr smd)
    (fp_text reference "C85" (at -3.05 -0.34 90) (layer "B.SilkS")
      (effects (font (size 0.7 0.7) (thickness 0.15)) (justify left bottom mirror))
    )
    (fp_text value "C_100n_0402" (at 0 -1.4 90) (layer "B.Fab")
      (effects (font (size 0.7 0.7) (thickness 0.15)) (justify left bottom mirror))
    )
    (fp_text user "${REFERENCE}" (at -0.932 -3.168 90) (layer "B.Fab") hide
      (effects (font (size 0.7 0.7) (thickness 0.15)) (justify left bottom mirror))
    )
    (fp_text user "Author: Antmicro" (at -0.932 -4.17 90) (layer "B.Fab") hide
      (effects (font (size 0.7 0.7) (thickness 0.15)) (justify left bottom mirror))
    )
    (fp_text user "License: Apache-2.0" (at -0.932 -5.17 90) (layer "B.Fab") hide
      (effects (font (size 0.7 0.7) (thickness 0.15)) (justify left bottom mirror))
    )
    (fp_rect (start -0.94 0.47) (end 0.94 -0.47) (layer "B.CrtYd") (width 0.05) (fill none))
    (fp_rect (start -0.499 0.249) (end 0.499 -0.249) (layer "B.Fab") (width 0.15) (fill none))
    (pad "1" smd roundrect (at -0.484 0 270) (size 0.59 0.64) (layers "B.Cu" "B.Paste" "B.Mask") (roundrect_rratio 0.25)
      (net 216 "/USB-C Interface /USB2C_TX1_P") (pintype "passive"))
    (pad "2" smd roundrect (at 0.484 0 270) (size 0.59 0.64) (layers "B.Cu" "B.Paste" "B.Mask") (roundrect_rratio 0.25)
      (net 215 "/USB-C Interface /USB2C_TX1_C_P") (pintype "passive"))
  )

  (footprint "sa800u-baseboard-hw-footprints:Nexperia_DFN-10_2.5x1mm_P0.5mm" (layer "B.Cu")
    (tedit 6215DC23)
    (at 101.75 140.6 180)
    (property "Author" "Antmicro")
    (property "License" "Apache-2.0")
    (property "MPN" "PUSB3F96X")
    (property "Manufacturer" "Nexperia")
    (property "Sheetfile" "usb-c-interface.kicad_sch")
    (property "Sheetname" "USB-C Interface ")
    (attr smd)
    (fp_text reference "D8" (at -0.66 -1.69) (layer "B.SilkS")
      (effects (font (size 0.7 0.7) (thickness 0.15)) (justify left bottom mirror))
    )
    (fp_text value "PUSB3F96X_PASS" (at -0.016 -1.705) (layer "B.Fab")
      (effects (font (size 0.7 0.7) (thickness 0.15)) (justify left bottom mirror))
    )
    (fp_text user "Author: Antmicro" (at -1.367 -4.905) (layer "B.Fab") hide
      (effects (font (size 0.7 0.7) (thickness 0.15)) (justify left bottom mirror))
    )
    (fp_text user "${REFERENCE}" (at -1.367 -3.704) (layer "B.Fab") hide
      (effects (font (size 0.7 0.7) (thickness 0.15)) (justify left bottom mirror))
    )
    (fp_text user "License: Apache-2.0" (at -1.367 -6.105) (layer "B.Fab") hide
      (effects (font (size 0.7 0.7) (thickness 0.15)) (justify left bottom mirror))
    )
    (fp_line (start 1.233 -0.405) (end 1.233 0.396) (layer "B.SilkS") (width 0.15))
    (fp_line (start -1.266 0.396) (end -1.266 -0.405) (layer "B.SilkS") (width 0.15))
    (fp_circle (center -1.317 -0.704) (end -1.266 -0.704) (layer "B.SilkS") (width 0.15) (fill solid))
    (fp_rect (start -1.4 0.7) (end 1.4 -0.7) (layer "B.CrtYd") (width 0.05) (fill none))
    (pad "1" smd rect (at -1.016 -0.392 180) (size 0.2 0.475) (layers "B.Cu" "B.Paste" "B.Mask")
      (net 327 "USB_CC2") (pinfunction "CH1") (pintype "passive"))
    (pad "2" smd rect (at -0.517 -0.392 180) (size 0.2 0.475) (layers "B.Cu" "B.Paste" "B.Mask")
      (net 322 "USB1_D_N") (pinfunction "CH2") (pintype "passive"))
    (pad "3" smd rect (at -0.016 -0.392 180) (size 0.2 0.475) (layers "B.Cu" "B.Paste" "B.Mask")
      (net 1 "GND") (pinfunction "GND") (pintype "passive"))
    (pad "4" smd rect (at 0.482 -0.392 180) (size 0.2 0.475) (layers "B.Cu" "B.Paste" "B.Mask")
      (net 321 "USB1_D_P") (pinfunction "CH3") (pintype "passive"))
    (pad "5" smd rect (at 0.982 -0.392 180) (size 0.2 0.475) (layers "B.Cu" "B.Paste" "B.Mask")
      (net 326 "USB_CC1") (pinfunction "CH4") (pintype "passive"))
    (pad "6" smd rect (at 0.982 0.383) (size 0.2 0.475) (layers "B.Cu" "B.Paste" "B.Mask")
      (net 326 "USB_CC1") (pinfunction "CH4") (pintype "passive"))
    (pad "7" smd rect (at 0.482 0.383) (size 0.2 0.475) (layers "B.Cu" "B.Paste" "B.Mask")
      (net 321 "USB1_D_P") (pinfunction "CH3") (pintype "passive"))
    (pad "8" smd rect (at -0.016 0.383) (size 0.2 0.475) (layers "B.Cu" "B.Paste" "B.Mask")
      (net 1 "GND") (pinfunction "GND") (pintype "passive"))
    (pad "9" smd rect (at -0.517 0.383) (size 0.2 0.475) (layers "B.Cu" "B.Paste" "B.Mask")
      (net 322 "USB1_D_N") (pinfunction "CH2") (pintype "passive"))
    (pad "10" smd rect (at -1.016 0.383) (size 0.2 0.475) (layers "B.Cu" "B.Paste" "B.Mask")
      (net 327 "USB_CC2") (pinfunction "CH1") (pintype "passive"))
  )

  (footprint "sa800u-baseboard-hw-footprints:Nexperia_DFN-10_2.5x1mm_P0.5mm" (layer "B.Cu")
    (tedit 6215DC23)
    (at 104.5 140.6)
    (property "Author" "Antmicro")
    (property "License" "Apache-2.0")
    (property "MPN" "PUSB3F96X")
    (property "Manufacturer" "Nexperia")
    (property "Sheetfile" "usb-c-interface.kicad_sch")
    (property "Sheetname" "USB-C Interface ")
    (attr smd)
    (fp_text reference "D10" (at 0.72 1.57 180) (layer "B.SilkS")
      (effects (font (size 0.7 0.7) (thickness 0.15)) (justify left bottom mirror))
    )
    (fp_text value "PUSB3F96X_PASS" (at -0.016 -1.705 180) (layer "B.Fab")
      (effects (font (size 0.7 0.7) (thickness 0.15)) (justify left bottom mirror))
    )
    (fp_text user "Author: Antmicro" (at -1.367 -4.905 180) (layer "B.Fab") hide
      (effects (font (size 0.7 0.7) (thickness 0.15)) (justify left bottom mirror))
    )
    (fp_text user "License: Apache-2.0" (at -1.367 -6.105 180) (layer "B.Fab") hide
      (effects (font (size 0.7 0.7) (thickness 0.15)) (justify left bottom mirror))
    )
    (fp_text user "${REFERENCE}" (at -1.367 -3.704 180) (layer "B.Fab") hide
      (effects (font (size 0.7 0.7) (thickness 0.15)) (justify left bottom mirror))
    )
    (fp_line (start 1.233 -0.405) (end 1.233 0.396) (layer "B.SilkS") (width 0.15))
    (fp_line (start -1.266 0.396) (end -1.266 -0.405) (layer "B.SilkS") (width 0.15))
    (fp_circle (center -1.317 -0.704) (end -1.266 -0.704) (layer "B.SilkS") (width 0.15) (fill solid))
    (fp_rect (start -1.4 0.7) (end 1.4 -0.7) (layer "B.CrtYd") (width 0.05) (fill none))
    (pad "1" smd rect (at -1.016 -0.392) (size 0.2 0.475) (layers "B.Cu" "B.Paste" "B.Mask")
      (net 304 "/USB-C Interface /USB1C_RX1_C_N") (pinfunction "CH1") (pintype "passive"))
    (pad "2" smd rect (at -0.517 -0.392) (size 0.2 0.475) (layers "B.Cu" "B.Paste" "B.Mask")
      (net 305 "/USB-C Interface /USB1C_RX1_C_P") (pinfunction "CH2") (pintype "passive"))
    (pad "3" smd rect (at -0.016 -0.392) (size 0.2 0.475) (layers "B.Cu" "B.Paste" "B.Mask")
      (net 1 "GND") (pinfunction "GND") (pintype "passive"))
    (pad "4" smd rect (at 0.482 -0.392) (size 0.2 0.475) (layers "B.Cu" "B.Paste" "B.Mask")
      (net 306 "/USB-C Interface /USB1C_TX1_C_N") (pinfunction "CH3") (pintype "passive"))
    (pad "5" smd rect (at 0.982 -0.392) (size 0.2 0.475) (layers "B.Cu" "B.Paste" "B.Mask")
      (net 307 "/USB-C Interface /USB1C_TX1_C_P") (pinfunction "CH4") (pintype "passive"))
    (pad "6" smd rect (at 0.982 0.383 180) (size 0.2 0.475) (layers "B.Cu" "B.Paste" "B.Mask")
      (net 307 "/USB-C Interface /USB1C_TX1_C_P") (pinfunction "CH4") (pintype "passive"))
    (pad "7" smd rect (at 0.482 0.383 180) (size 0.2 0.475) (layers "B.Cu" "B.Paste" "B.Mask")
      (net 306 "/USB-C Interface /USB1C_TX1_C_N") (pinfunction "CH3") (pintype "passive"))
    (pad "8" smd rect (at -0.016 0.383 180) (size 0.2 0.475) (layers "B.Cu" "B.Paste" "B.Mask")
      (net 1 "GND") (pinfunction "GND") (pintype "passive"))
    (pad "9" smd rect (at -0.517 0.383 180) (size 0.2 0.475) (layers "B.Cu" "B.Paste" "B.Mask")
      (net 305 "/USB-C Interface /USB1C_RX1_C_P") (pinfunction "CH2") (pintype "passive"))
    (pad "10" smd rect (at -1.016 0.383 180) (size 0.2 0.475) (layers "B.Cu" "B.Paste" "B.Mask")
      (net 304 "/USB-C Interface /USB1C_RX1_C_N") (pinfunction "CH1") (pintype "passive"))
  )

  (footprint "sa800u-baseboard-hw-footprints:C_0402_1005Metric" (layer "B.Cu")
    (tedit 616D63CF)
    (at 125 133.9 180)
    (descr "Capacitor SMD 0402")
    (tags "capacitor SMD 0402")
    (property "Author" "Antmicro")
    (property "Dielectric" "X5R")
    (property "License" "Apache-2.0")
    (property "MPN" "GRM155R61H104KE14D")
    (property "Manufacturer" "Murata")
    (property "Sheetfile" "usb-c-interface.kicad_sch")
    (property "Sheetname" "USB-C Interface ")
    (property "Val" "100n")
    (property "Voltage" "50V")
    (attr smd)
    (fp_text reference "C64" (at -0.99 0.61) (layer "B.SilkS")
      (effects (font (size 0.7 0.7) (thickness 0.15)) (justify left bottom mirror))
    )
    (fp_text value "C_100n_0402" (at 0 -1.4) (layer "B.Fab")
      (effects (font (size 0.7 0.7) (thickness 0.15)) (justify left bottom mirror))
    )
    (fp_text user "${REFERENCE}" (at -0.932 -3.168) (layer "B.Fab") hide
      (effects (font (size 0.7 0.7) (thickness 0.15)) (justify left bottom mirror))
    )
    (fp_text user "License: Apache-2.0" (at -0.932 -5.17) (layer "B.Fab") hide
      (effects (font (size 0.7 0.7) (thickness 0.15)) (justify left bottom mirror))
    )
    (fp_text user "Author: Antmicro" (at -0.932 -4.17) (layer "B.Fab") hide
      (effects (font (size 0.7 0.7) (thickness 0.15)) (justify left bottom mirror))
    )
    (fp_rect (start -0.94 0.47) (end 0.94 -0.47) (layer "B.CrtYd") (width 0.05) (fill none))
    (fp_rect (start -0.499 0.249) (end 0.499 -0.249) (layer "B.Fab") (width 0.15) (fill none))
    (pad "1" smd roundrect (at -0.484 0 180) (size 0.59 0.64) (layers "B.Cu" "B.Paste" "B.Mask") (roundrect_rratio 0.25)
      (net 127 "1V8_DBG") (pintype "passive"))
    (pad "2" smd roundrect (at 0.484 0 180) (size 0.59 0.64) (layers "B.Cu" "B.Paste" "B.Mask") (roundrect_rratio 0.25)
      (net 1 "GND") (pintype "passive"))
  )

  (footprint "sa800u-baseboard-hw-footprints:C_0603_1608Metric" (layer "B.Cu")
    (tedit 5D5E94D2)
    (at 127.7 137.95 90)
    (descr "Capacitor SMD 0603")
    (tags "capacitor 0603")
    (property "Author" "Antmicro")
    (property "Dielectric" "")
    (property "License" "Apache-2.0")
    (property "MPN" "C1608X5R1V225K080AC")
    (property "Manufacturer" "TDK")
    (property "Sheetfile" "usb-c-interface.kicad_sch")
    (property "Sheetname" "USB-C Interface ")
    (property "Val" "2u2")
    (property "Voltage" "")
    (attr smd)
    (fp_text reference "C77" (at 1.13 1.37 270) (layer "B.SilkS")
      (effects (font (size 0.7 0.7) (thickness 0.15)) (justify left bottom mirror))
    )
    (fp_text value "C_2u2_0603" (at 0 -1.6 270) (layer "B.Fab")
      (effects (font (size 0.7 0.7) (thickness 0.15)) (justify left bottom mirror))
    )
    (fp_text user "License: Apache-2.0" (at -1.682 -5.895 270) (layer "B.Fab") hide
      (effects (font (size 0.7 0.7) (thickness 0.15)) (justify left bottom mirror))
    )
    (fp_text user "Author: Antmicro" (at -1.682 -4.894 270) (layer "B.Fab") hide
      (effects (font (size 0.7 0.7) (thickness 0.15)) (justify left bottom mirror))
    )
    (fp_text user "${REFERENCE}" (at -1.682 -3.895 270) (layer "B.Fab") hide
      (effects (font (size 0.7 0.7) (thickness 0.15)) (justify left bottom mirror))
    )
    (fp_line (start -0.3 0.3) (end 0.3 0.3) (layer "B.SilkS") (width 0.15))
    (fp_line (start -0.3 -0.3) (end 0.3 -0.3) (layer "B.SilkS") (width 0.15))
    (fp_rect (start -1.24 0.7) (end 1.24 -0.7) (layer "B.CrtYd") (width 0.05) (fill none))
    (fp_rect (start -0.8 0.4) (end 0.8 -0.4) (layer "B.Fab") (width 0.15) (fill none))
    (pad "1" smd roundrect (at -0.7 0 90) (size 0.6 0.8) (layers "B.Cu" "B.Paste" "B.Mask") (roundrect_rratio 0.2)
      (net 228 "/USB-C Interface /5V0_DBG") (pintype "passive"))
    (pad "2" smd roundrect (at 0.7 0 90) (size 0.6 0.8) (layers "B.Cu" "B.Paste" "B.Mask") (roundrect_rratio 0.2)
      (net 1 "GND") (pintype "passive"))
  )

  (footprint "sa800u-baseboard-hw-footprints:C_0402_1005Metric" (layer "B.Cu")
    (tedit 616D63CF)
    (at 131.4 142.25)
    (descr "Capacitor SMD 0402")
    (tags "capacitor SMD 0402")
    (property "Author" "Antmicro")
    (property "Dielectric" "C0G")
    (property "License" "Apache-2.0")
    (property "MPN" "GRM1555C1E470JA01D")
    (property "Manufacturer" "Murata")
    (property "Sheetfile" "usb-c-interface.kicad_sch")
    (property "Sheetname" "USB-C Interface ")
    (property "Val" "47p")
    (property "Voltage" "")
    (attr smd)
    (fp_text reference "C68" (at 1.05 -0.56 180) (layer "B.SilkS")
      (effects (font (size 0.7 0.7) (thickness 0.15)) (justify left bottom mirror))
    )
    (fp_text value "C_47p_0402" (at 0 -1.4 180) (layer "B.Fab")
      (effects (font (size 0.7 0.7) (thickness 0.15)) (justify left bottom mirror))
    )
    (fp_text user "Author: Antmicro" (at -0.932 -4.17 180) (layer "B.Fab") hide
      (effects (font (size 0.7 0.7) (thickness 0.15)) (justify left bottom mirror))
    )
    (fp_text user "License: Apache-2.0" (at -0.932 -5.17 180) (layer "B.Fab") hide
      (effects (font (size 0.7 0.7) (thickness 0.15)) (justify left bottom mirror))
    )
    (fp_text user "${REFERENCE}" (at -0.932 -3.168 180) (layer "B.Fab") hide
      (effects (font (size 0.7 0.7) (thickness 0.15)) (justify left bottom mirror))
    )
    (fp_rect (start -0.94 0.47) (end 0.94 -0.47) (layer "B.CrtYd") (width 0.05) (fill none))
    (fp_rect (start -0.499 0.249) (end 0.499 -0.249) (layer "B.Fab") (width 0.15) (fill none))
    (pad "1" smd roundrect (at -0.484 0) (size 0.59 0.64) (layers "B.Cu" "B.Paste" "B.Mask") (roundrect_rratio 0.25)
      (net 229 "/USB-C Interface /DBG_USB_D_N") (pintype "passive"))
    (pad "2" smd roundrect (at 0.484 0) (size 0.59 0.64) (layers "B.Cu" "B.Paste" "B.Mask") (roundrect_rratio 0.25)
      (net 1 "GND") (pintype "passive"))
  )

  (footprint "sa800u-baseboard-hw-footprints:C_0603_1608Metric" (layer "B.Cu")
    (tedit 5D5E94D2)
    (at 127.7 135.35 -90)
    (descr "Capacitor SMD 0603")
    (tags "capacitor 0603")
    (property "Author" "Antmicro")
    (property "Dielectric" "")
    (property "License" "Apache-2.0")
    (property "MPN" "0603YD105KAT2A")
    (property "Manufacturer" "Walsin")
    (property "Sheetfile" "usb-c-interface.kicad_sch")
    (property "Sheetname" "USB-C Interface ")
    (property "Val" "1u")
    (property "Voltage" "")
    (attr smd)
    (fp_text reference "C75" (at -1.18 -1.37 90) (layer "B.SilkS")
      (effects (font (size 0.7 0.7) (thickness 0.15)) (justify left bottom mirror))
    )
    (fp_text value "C_1u_0603" (at 0 -1.6 90) (layer "B.Fab")
      (effects (font (size 0.7 0.7) (thickness 0.15)) (justify left bottom mirror))
    )
    (fp_text user "Author: Antmicro" (at -1.682 -4.894 90) (layer "B.Fab") hide
      (effects (font (size 0.7 0.7) (thickness 0.15)) (justify left bottom mirror))
    )
    (fp_text user "${REFERENCE}" (at -1.682 -3.895 90) (layer "B.Fab") hide
      (effects (font (size 0.7 0.7) (thickness 0.15)) (justify left bottom mirror))
    )
    (fp_text user "License: Apache-2.0" (at -1.682 -5.895 90) (layer "B.Fab") hide
      (effects (font (size 0.7 0.7) (thickness 0.15)) (justify left bottom mirror))
    )
    (fp_line (start -0.3 -0.3) (end 0.3 -0.3) (layer "B.SilkS") (width 0.15))
    (fp_line (start -0.3 0.3) (end 0.3 0.3) (layer "B.SilkS") (width 0.15))
    (fp_rect (start -1.24 0.7) (end 1.24 -0.7) (layer "B.CrtYd") (width 0.05) (fill none))
    (fp_rect (start -0.8 0.4) (end 0.8 -0.4) (layer "B.Fab") (width 0.15) (fill none))
    (pad "1" smd roundrect (at -0.7 0 270) (size 0.6 0.8) (layers "B.Cu" "B.Paste" "B.Mask") (roundrect_rratio 0.2)
      (net 127 "1V8_DBG") (pintype "passive"))
    (pad "2" smd roundrect (at 0.7 0 270) (size 0.6 0.8) (layers "B.Cu" "B.Paste" "B.Mask") (roundrect_rratio 0.2)
      (net 1 "GND") (pintype "passive"))
  )

  (footprint "sa800u-baseboard-hw-footprints:SOT-23-5" (layer "B.Cu")
    (tedit 5D64D240)
    (at 125.1 136.65 90)
    (property "Author" "Antmicro")
    (property "License" "Apache-2.0")
    (property "MPN" "TPS7A0518PDBVT")
    (property "Manufacturer" "Texas Instruments")
    (property "Sheetfile" "usb-c-interface.kicad_sch")
    (property "Sheetname" "USB-C Interface ")
    (attr smd)
    (fp_text reference "IC1" (at -1 -1.9 90) (layer "B.SilkS")
      (effects (font (size 0.7 0.7) (thickness 0.15)) (justify right bottom mirror))
    )
    (fp_text value "TPS7A0518P_SOT23-5" (at 0.002 -2.799 90) (layer "B.Fab")
      (effects (font (size 0.7 0.7) (thickness 0.15)) (justify right bottom mirror))
    )
    (fp_text user "License: Apache-2.0" (at -1.898 -6.7 90) (layer "B.Fab") hide
      (effects (font (size 0.7 0.7) (thickness 0.15)) (justify right bottom mirror))
    )
    (fp_text user "${REFERENCE}" (at -1.898 -4.299 90) (layer "B.Fab") hide
      (effects (font (size 0.7 0.7) (thickness 0.15)) (justify right bottom mirror))
    )
    (fp_text user "Author: Antmicro" (at -1.898 -5.499 90) (layer "B.Fab") hide
      (effects (font (size 0.7 0.7) (thickness 0.15)) (justify right bottom mirror))
    )
    (fp_line (start 0.8 -0.55) (end 0.8 0.55) (layer "B.SilkS") (width 0.15))
    (fp_line (start 0.8 1.3) (end 0.8 1.6) (layer "B.SilkS") (width 0.15))
    (fp_line (start 0.8 -1.3) (end 0.8 -1.599) (layer "B.SilkS") (width 0.15))
    (fp_line (start -0.8 1.6) (end -0.5 1.6) (layer "B.SilkS") (width 0.15))
    (fp_line (start -0.85 -1.6) (end -0.85 -1.301) (layer "B.SilkS") (width 0.15))
    (fp_line (start -0.8 1.6) (end -0.8 1.3) (layer "B.SilkS") (width 0.15))
    (fp_line (start 0.8 -1.599) (end 0.549 -1.599) (layer "B.SilkS") (width 0.15))
    (fp_line (start -0.55 -1.6) (end -0.85 -1.6) (layer "B.SilkS") (width 0.15))
    (fp_line (start 0.8 1.6) (end 0.5 1.6) (layer "B.SilkS") (width 0.15))
    (fp_circle (center -1.25 1.5) (end -1.2 1.5) (layer "B.SilkS") (width 0.15) (fill solid))
    (fp_rect (start 1.9 1.76) (end -1.9 -1.75) (layer "B.CrtYd") (width 0.05) (fill none))
    (fp_line (start -0.398 1.526) (end -0.874 1.05) (layer "B.Fab") (width 0.15))
    (fp_rect (start 0.874 -1.523) (end -0.873 1.525) (layer "B.Fab") (width 0.15) (fill none))
    (pad "1" smd rect (at -1.351 0.951 180) (size 0.55 1) (layers "B.Cu" "B.Paste" "B.Mask")
      (net 228 "/USB-C Interface /5V0_DBG") (pinfunction "VIN") (pintype "power_in"))
    (pad "2" smd rect (at -1.351 0 180) (size 0.55 1) (layers "B.Cu" "B.Paste" "B.Mask")
      (net 1 "GND") (pinfunction "GND") (pintype "power_in"))
    (pad "3" smd rect (at -1.351 -0.949 180) (size 0.55 1) (layers "B.Cu" "B.Paste" "B.Mask")
      (net 228 "/USB-C Interface /5V0_DBG") (pinfunction "EN") (pintype "input"))
    (pad "4" smd rect (at 1.35 -0.949 180) (size 0.55 1) (layers "B.Cu" "B.Paste" "B.Mask")
      (net 413 "unconnected-(IC1-Pad4)") (pinfunction "NC") (pintype "no_connect"))
    (pad "5" smd rect (at 1.35 0.951 180) (size 0.55 1) (layers "B.Cu" "B.Paste" "B.Mask")
      (net 127 "1V8_DBG") (pinfunction "VOUT") (pintype "power_out"))
  )

  (footprint "sa800u-baseboard-hw-footprints:C_0402_1005Metric" (layer "B.Cu")
    (tedit 616D63CF)
    (at 128.1 142.25 180)
    (descr "Capacitor SMD 0402")
    (tags "capacitor SMD 0402")
    (property "Author" "Antmicro")
    (property "Dielectric" "C0G")
    (property "License" "Apache-2.0")
    (property "MPN" "GRM1555C1E470JA01D")
    (property "Manufacturer" "Murata")
    (property "Sheetfile" "usb-c-interface.kicad_sch")
    (property "Sheetname" "USB-C Interface ")
    (property "Val" "47p")
    (property "Voltage" "")
    (attr smd)
    (fp_text reference "C70" (at -1.07 0.63) (layer "B.SilkS")
      (effects (font (size 0.7 0.7) (thickness 0.15)) (justify left bottom mirror))
    )
    (fp_text value "C_47p_0402" (at 0 -1.4) (layer "B.Fab")
      (effects (font (size 0.7 0.7) (thickness 0.15)) (justify left bottom mirror))
    )
    (fp_text user "${REFERENCE}" (at -0.932 -3.168) (layer "B.Fab") hide
      (effects (font (size 0.7 0.7) (thickness 0.15)) (justify left bottom mirror))
    )
    (fp_text user "License: Apache-2.0" (at -0.932 -5.17) (layer "B.Fab") hide
      (effects (font (size 0.7 0.7) (thickness 0.15)) (justify left bottom mirror))
    )
    (fp_text user "Author: Antmicro" (at -0.932 -4.17) (layer "B.Fab") hide
      (effects (font (size 0.7 0.7) (thickness 0.15)) (justify left bottom mirror))
    )
    (fp_rect (start -0.94 0.47) (end 0.94 -0.47) (layer "B.CrtYd") (width 0.05) (fill none))
    (fp_rect (start -0.499 0.249) (end 0.499 -0.249) (layer "B.Fab") (width 0.15) (fill none))
    (pad "1" smd roundrect (at -0.484 0 180) (size 0.59 0.64) (layers "B.Cu" "B.Paste" "B.Mask") (roundrect_rratio 0.25)
      (net 230 "/USB-C Interface /DBG_USB_D_P") (pintype "passive"))
    (pad "2" smd roundrect (at 0.484 0 180) (size 0.59 0.64) (layers "B.Cu" "B.Paste" "B.Mask") (roundrect_rratio 0.25)
      (net 1 "GND") (pintype "passive"))
  )

  (footprint "sa800u-baseboard-hw-footprints:SOT-23-3" (layer "B.Cu")
    (tedit 5D5D4314)
    (at 94.75 147.3 180)
    (property "Author" "Antmicro")
    (property "License" "Apache-2.0")
    (property "MPN" "BSS84")
    (property "Manufacturer" "ON Semiconductor")
    (property "Sheetfile" "psu.kicad_sch")
    (property "Sheetname" "PSU")
    (attr smd)
    (fp_text reference "Q10" (at 0.88 0.71) (layer "B.SilkS")
      (effects (font (size 0.7 0.7) (thickness 0.15)) (justify left bottom mirror))
    )
    (fp_text value "BSS84" (at -1.9 -2.7) (layer "B.Fab")
      (effects (font (size 0.7 0.7) (thickness 0.15)) (justify left bottom mirror))
    )
    (fp_text user "${REFERENCE}" (at -1.837 -4) (layer "B.Fab") hide
      (effects (font (size 0.7 0.7) (thickness 0.15)) (justify left bottom mirror))
    )
    (fp_text user "Author: Antmicro" (at -1.837 -5.3) (layer "B.Fab") hide
      (effects (font (size 0.7 0.7) (thickness 0.15)) (justify left bottom mirror))
    )
    (fp_text user "License: Apache-2.0" (at -1.8 -6.8) (layer "B.Fab") hide
      (effects (font (size 0.7 0.7) (thickness 0.15)) (justify left bottom mirror))
    )
    (fp_line (start -1.45 1.35) (end -0.85 1.35) (layer "B.SilkS") (width 0.15))
    (fp_line (start 0.7 -1.5) (end -0.7 -1.5) (layer "B.SilkS") (width 0.15))
    (fp_line (start 0.7 1.5) (end -0.7 1.5) (layer "B.SilkS") (width 0.15))
    (fp_line (start 0.7 -0.4) (end 0.7 -1.5) (layer "B.SilkS") (width 0.15))
    (fp_line (start 0.7 0.4) (end 0.7 1.5) (layer "B.SilkS") (width 0.15))
    (fp_line (start -0.7 -1.5) (end -0.7 -1.35) (layer "B.SilkS") (width 0.15))
    (fp_line (start -0.85 1.35) (end -0.7 1.5) (layer "B.SilkS") (width 0.15))
    (fp_line (start -0.85 -1.65) (end -0.85 -1.4) (layer "B.CrtYd") (width 0.05))
    (fp_line (start -1.75 -1.4) (end -1.75 -0.5) (layer "B.CrtYd") (width 0.05))
    (fp_line (start 0.85 -0.45) (end 0.85 -1.65) (layer "B.CrtYd") (width 0.05))
    (fp_line (start -0.85 -1.4) (end -1.75 -1.4) (layer "B.CrtYd") (width 0.05))
    (fp_line (start -0.9 1.4) (end -1.75 1.4) (layer "B.CrtYd") (width 0.05))
    (fp_line (start 0.85 -1.65) (end -0.85 -1.65) (layer "B.CrtYd") (width 0.05))
    (fp_line (start -0.85 0.5) (end -1.75 0.5) (layer "B.CrtYd") (width 0.05))
    (fp_line (start -0.9 1.6) (end 0.825 1.6) (layer "B.CrtYd") (width 0.05))
    (fp_line (start -0.9 1.6) (end -0.9 1.4) (layer "B.CrtYd") (width 0.05))
    (fp_line (start 0.825 1.6) (end 0.825 0.45) (layer "B.CrtYd") (width 0.05))
    (fp_line (start -1.75 -0.5) (end -0.85 -0.5) (layer "B.CrtYd") (width 0.05))
    (fp_line (start -1.75 0.5) (end -1.75 1.4) (layer "B.CrtYd") (width 0.05))
    (fp_line (start 1.75 0.45) (end 1.75 -0.45) (layer "B.CrtYd") (width 0.05))
    (fp_line (start -0.85 -0.5) (end -0.85 0.5) (layer "B.CrtYd") (width 0.05))
    (fp_line (start 0.825 0.45) (end 1.75 0.45) (layer "B.CrtYd") (width 0.05))
    (fp_line (start 1.75 -0.45) (end 0.85 -0.45) (layer "B.CrtYd") (width 0.05))
    (fp_line (start 0.688 -1.519) (end 0.688 1.52) (layer "B.Fab") (width 0.15))
    (fp_line (start -0.437 1.526) (end -0.712 1.325) (layer "B.Fab") (width 0.15))
    (fp_line (start -0.712 -1.519) (end 0.688 -1.519) (layer "B.Fab") (width 0.15))
    (fp_line (start -0.437 1.526) (end 0.688 1.526) (layer "B.Fab") (width 0.15))
    (fp_line (start -0.712 1.325) (end -0.712 -1.523) (layer "B.Fab") (width 0.15))
    (pad "1" smd roundrect (at -1.1 0.951 180) (size 1 0.6) (layers "B.Cu" "B.Paste" "B.Mask") (roundrect_rratio 0.15)
      (net 341 "/PSU/USB_PD_VALID") (pinfunction "G") (pintype "bidirectional"))
    (pad "2" smd roundrect (at -1.1 -0.949 180) (size 1 0.6) (layers "B.Cu" "B.Paste" "B.Mask") (roundrect_rratio 0.15)
      (net 1 "GND") (pinfunction "D") (pintype "bidirectional"))
    (pad "3" smd roundrect (at 1.1 0.0005 180) (size 1 0.6) (layers "B.Cu" "B.Paste" "B.Mask") (roundrect_rratio 0.15)
      (net 389 "Net-(Q10-Pad3)") (pinfunction "S") (pintype "bidirectional"))
  )

  (footprint "sa800u-baseboard-hw-footprints:C_0603_1608Metric" (layer "B.Cu")
    (tedit 5D5E94D2)
    (at 117.5 149.25 -90)
    (descr "Capacitor SMD 0603")
    (tags "capacitor 0603")
    (property "Author" "Antmicro")
    (property "Dielectric" "")
    (property "License" "Apache-2.0")
    (property "MPN" "GRM188R60J476ME15D")
    (property "Manufacturer" "Murata")
    (property "Sheetfile" "usb-c-interface.kicad_sch")
    (property "Sheetname" "USB-C Interface ")
    (property "Val" "47u")
    (property "Voltage" "")
    (attr smd)
    (fp_text reference "C76" (at -1.11 0.78 90) (layer "B.SilkS")
      (effects (font (size 0.7 0.7) (thickness 0.15)) (justify left bottom mirror))
    )
    (fp_text value "C_47u_0603" (at 0 -1.6 90) (layer "B.Fab")
      (effects (font (size 0.7 0.7) (thickness 0.15)) (justify left bottom mirror))
    )
    (fp_text user "License: Apache-2.0" (at -1.682 -5.895 90) (layer "B.Fab") hide
      (effects (font (size 0.7 0.7) (thickness 0.15)) (justify left bottom mirror))
    )
    (fp_text user "Author: Antmicro" (at -1.682 -4.894 90) (layer "B.Fab") hide
      (effects (font (size 0.7 0.7) (thickness 0.15)) (justify left bottom mirror))
    )
    (fp_text user "${REFERENCE}" (at -1.682 -3.895 90) (layer "B.Fab") hide
      (effects (font (size 0.7 0.7) (thickness 0.15)) (justify left bottom mirror))
    )
    (fp_line (start -0.3 -0.3) (end 0.3 -0.3) (layer "B.SilkS") (width 0.15))
    (fp_line (start -0.3 0.3) (end 0.3 0.3) (layer "B.SilkS") (width 0.15))
    (fp_rect (start -1.24 0.7) (end 1.24 -0.7) (layer "B.CrtYd") (width 0.05) (fill none))
    (fp_rect (start -0.8 0.4) (end 0.8 -0.4) (layer "B.Fab") (width 0.15) (fill none))
    (pad "1" smd roundrect (at -0.7 0 270) (size 0.6 0.8) (layers "B.Cu" "B.Paste" "B.Mask") (roundrect_rratio 0.2)
      (net 210 "/USB-C Interface /USB2_5V") (pintype "passive"))
    (pad "2" smd roundrect (at 0.7 0 270) (size 0.6 0.8) (layers "B.Cu" "B.Paste" "B.Mask") (roundrect_rratio 0.2)
      (net 1 "GND") (pintype "passive"))
  )

  (footprint "sa800u-baseboard-hw-footprints:C_0402_1005Metric" (layer "B.Cu")
    (tedit 616D63CF)
    (at 97.5 138.1 90)
    (descr "Capacitor SMD 0402")
    (tags "capacitor SMD 0402")
    (property "Author" "Antmicro")
    (property "Dielectric" "X5R")
    (property "License" "Apache-2.0")
    (property "MPN" "GRM155R61H104KE14D")
    (property "Manufacturer" "Murata")
    (property "Sheetfile" "usb-c-interface.kicad_sch")
    (property "Sheetname" "USB-C Interface ")
    (property "Val" "100n")
    (property "Voltage" "50V")
    (attr smd)
    (fp_text reference "C92" (at 3.07 0.36 270) (layer "B.SilkS")
      (effects (font (size 0.7 0.7) (thickness 0.15)) (justify left bottom mirror))
    )
    (fp_text value "C_100n_0402" (at 0 -1.4 270) (layer "B.Fab")
      (effects (font (size 0.7 0.7) (thickness 0.15)) (justify left bottom mirror))
    )
    (fp_text user "Author: Antmicro" (at -0.932 -4.17 270) (layer "B.Fab") hide
      (effects (font (size 0.7 0.7) (thickness 0.15)) (justify left bottom mirror))
    )
    (fp_text user "License: Apache-2.0" (at -0.932 -5.17 270) (layer "B.Fab") hide
      (effects (font (size 0.7 0.7) (thickness 0.15)) (justify left bottom mirror))
    )
    (fp_text user "${REFERENCE}" (at -0.932 -3.168 270) (layer "B.Fab") hide
      (effects (font (size 0.7 0.7) (thickness 0.15)) (justify left bottom mirror))
    )
    (fp_rect (start -0.94 0.47) (end 0.94 -0.47) (layer "B.CrtYd") (width 0.05) (fill none))
    (fp_rect (start -0.499 0.249) (end 0.499 -0.249) (layer "B.Fab") (width 0.15) (fill none))
    (pad "1" smd roundrect (at -0.484 0 90) (size 0.59 0.64) (layers "B.Cu" "B.Paste" "B.Mask") (roundrect_rratio 0.25)
      (net 308 "/USB-C Interface /USB1C_RX0_C_P") (pintype "passive"))
    (pad "2" smd roundrect (at 0.484 0 90) (size 0.59 0.64) (layers "B.Cu" "B.Paste" "B.Mask") (roundrect_rratio 0.25)
      (net 69 "USB1_SS_RX0_P") (pintype "passive"))
  )

  (footprint "sa800u-baseboard-hw-footprints:MicroSD_DM3AT-SF-PEJM5" locked (layer "B.Cu")
    (tedit 600CE7C2)
    (at 131.331 90.998)
    (descr "Micro SD, SMD, right-angle, push-pull")
    (tags "Micro SD")
    (property "Author" "Antmicro")
    (property "License" "Apache-2.0")
    (property "MPN" "DM3AT-SF-PEJM5")
    (property "Manufacturer" "Hirose")
    (property "Sheetfile" "other-interfaces.kicad_sch")
    (property "Sheetname" "Other Interfaces")
    (attr smd)
    (fp_text reference "J8" (at -6.25 9.3 180) (layer "B.SilkS")
      (effects (font (size 0.7 0.7) (thickness 0.15)) (justify left bottom mirror))
    )
    (fp_text value "DM3AT-SF-PEJM5" (at 8.14 -6.17 -90) (layer "B.Fab")
      (effects (font (size 0.7 0.7) (thickness 0.15)) (justify left bottom mirror))
    )
    (fp_text user "License: Apache-2.0" (at -7.927 -16.698 180) (layer "B.Fab") hide
      (effects (font (size 0.7 0.7) (thickness 0.15)) (justify left bottom mirror))
    )
    (fp_text user "Author: Antmicro" (at -7.927 -15.498 180) (layer "B.Fab") hide
      (effects (font (size 0.7 0.7) (thickness 0.15)) (justify left bottom mirror))
    )
    (fp_text user "${REFERENCE}" (at -7.927 -17.898 180) (layer "B.Fab") hide
      (effects (font (size 0.7 0.7) (thickness 0.15)) (justify left bottom mirror))
    )
    (fp_line (start -5.971 -8.157) (end -4.111 -8.157) (layer "B.SilkS") (width 0.15))
    (fp_line (start 5.289 -8.157) (end 5.488 -7.959) (layer "B.SilkS") (width 0.15))
    (fp_line (start 6.967 8.11) (end 6.967 -5.897) (layer "B.SilkS") (width 0.15))
    (fp_line (start -3.9 -7.809) (end 2.47 -7.809) (layer "B.SilkS") (width 0.15))
    (fp_line (start -5.971 -8.157) (end -6.17 -7.959) (layer "B.SilkS") (width 0.15))
    (fp_line (start -7 8.11) (end -7 4.502) (layer "B.SilkS") (width 0.15))
    (fp_line (start 5.289 -8.157) (end 2.979 -8.157) (layer "B.SilkS") (width 0.15))
    (fp_line (start 5.049 8.11) (end 6.967 8.11) (layer "B.SilkS") (width 0.15))
    (fp_line (start -7 2.802) (end -7 -1.898) (layer "B.SilkS") (width 0.15))
    (fp_line (start 2.979 -8.157) (end 2.47 -7.809) (layer "B.SilkS") (width 0.15))
    (fp_line (start -3.9 -7.809) (end -3.9 -7.959) (layer "B.SilkS") (width 0.15))
    (fp_line (start -4.111 -8.157) (end -3.9 -7.959) (layer "B.SilkS") (width 0.15))
    (fp_line (start 5.488 -7.959) (end 5.749 -7.959) (layer "B.SilkS") (width 0.15))
    (fp_line (start -6.553 8.11) (end -7 8.11) (layer "B.SilkS") (width 0.15))
    (fp_line (start -7 -3.197) (end -7 -4.998) (layer "B.SilkS") (width 0.15))
    (fp_circle (center 3.19 8.71) (end 3.239 8.71) (layer "B.SilkS") (width 0.15) (fill solid))
    (fp_rect (start -7.7 8.9) (end 7.4 -8.6) (layer "B.CrtYd") (width 0.05) (fill none))
    (fp_line (start 5.049 -12.998) (end 5.049 -8.099) (layer "B.Fab") (width 0.15))
    (fp_line (start 5.459 -7.898) (end 6.898 -7.898) (layer "B.Fab") (width 0.15))
    (fp_line (start -5.451 -13.498) (end 4.549 -13.498) (layer "B.Fab") (width 0.15))
    (fp_line (start -3.94 -7.898) (end -3.94 -7.748) (layer "B.Fab") (width 0.15))
    (fp_line (start -6.141 -7.898) (end -6.951 -7.898) (layer "B.Fab") (width 0.15))
    (fp_line (start -5.941 -8.099) (end -6.141 -7.898) (layer "B.Fab") (width 0.15))
    (fp_line (start -4.141 -8.099) (end -5.941 -8.099) (layer "B.Fab") (width 0.15))
    (fp_line (start 5.259 -8.099) (end 3.01 -8.099) (layer "B.Fab") (width 0.15))
    (fp_line (start -3.94 -7.898) (end -4.141 -8.099) (layer "B.Fab") (width 0.15))
    (fp_line (start 3.01 -8.099) (end 2.483 -7.748) (layer "B.Fab") (width 0.15))
    (fp_line (start 6.898 -7.898) (end 6.898 8.051) (layer "B.Fab") (width 0.15))
    (fp_line (start 5.259 -8.099) (end 5.459 -7.898) (layer "B.Fab") (width 0.15))
    (fp_line (start -5.451 -9.497) (end 4.549 -9.497) (layer "B.Fab") (width 0.15))
    (fp_line (start 6.898 8.051) (end -6.951 8.051) (layer "B.Fab") (width 0.15))
    (fp_line (start -5.951 -8.099) (end -5.951 -12.998) (layer "B.Fab") (width 0.15))
    (fp_line (start 2.483 -7.748) (end -3.94 -7.748) (layer "B.Fab") (width 0.15))
    (fp_line (start -6.951 -7.898) (end -6.951 8.051) (layer "B.Fab") (width 0.15))
    (fp_arc (start 4.549 -9.497) (mid 4.903498 -9.351498) (end 5.049 -8.997) (layer "B.Fab") (width 0.15))
    (fp_arc (start -5.951 -12.998) (mid -5.805 -13.352) (end -5.451 -13.498) (layer "B.Fab") (width 0.15))
    (fp_arc (start 4.549 -13.498) (mid 4.902994 -13.351994) (end 5.049 -12.998) (layer "B.Fab") (width 0.15))
    (fp_arc (start -5.951 -8.997) (mid -5.8055 -9.3515) (end -5.451 -9.497) (layer "B.Fab") (width 0.15))
    (pad "1" smd rect locked (at 2.749 7.952) (size 0.7 1.2) (layers "B.Cu" "B.Paste" "B.Mask")
      (net 247 "/Other Interfaces/SD_DATA2_R") (pinfunction "DAT2") (pintype "bidirectional"))
    (pad "2" smd rect locked (at 1.65 7.952) (size 0.7 1.2) (layers "B.Cu" "B.Paste" "B.Mask")
      (net 249 "/Other Interfaces/SD_DATA3_R") (pinfunction "DAT3/CD") (pintype "bidirectional"))
    (pad "3" smd rect locked (at 0.549 7.952) (size 0.7 1.2) (layers "B.Cu" "B.Paste" "B.Mask")
      (net 248 "/Other Interfaces/SD_CMD_R") (pinfunction "CMD") (pintype "input"))
    (pad "4" smd rect locked (at -0.552 7.952) (size 0.7 1.2) (layers "B.Cu" "B.Paste" "B.Mask")
      (net 227 "/Other Interfaces/SD_VDD_R") (pinfunction "VDD") (pintype "power_in"))
    (pad "5" smd rect locked (at -1.651 7.952) (size 0.7 1.2) (layers "B.Cu" "B.Paste" "B.Mask")
      (net 250 "/Other Interfaces/SD_CLK_R") (pinfunction "CLK") (pintype "input"))
    (pad "6" smd rect locked (at -2.751 7.952) (size 0.7 1.2) (layers "B.Cu" "B.Paste" "B.Mask")
      (net 1 "GND") (pinfunction "VSS") (pintype "power_in"))
    (pad "7" smd rect locked (at -3.851 7.952) (size 0.7 1.2) (layers "B.Cu" "B.Paste" "B.Mask")
      (net 252 "/Other Interfaces/SD_DATA0_R") (pinfunction "DAT0") (pintype "input"))
    (pad "8" smd rect locked (at -4.951 7.952) (size 0.7 1.2) (layers "B.Cu" "B.Paste" "B.Mask")
      (net 251 "/Other Interfaces/SD_DATA1_R") (pinfunction "DAT1") (pintype "input"))
    (pad "9" smd rect locked (at -5.901 7.952) (size 0.7 1.2) (layers "B.Cu" "B.Paste" "B.Mask")
      (net 1 "GND") (pinfunction "DET_B") (pintype "passive"))
    (pad "10" smd rect locked (at -6.851 -2.547) (size 1 0.8) (layers "B.Cu" "B.Paste" "B.Mask")
      (net 246 "/Other Interfaces/SD_DET_R") (pinfunction "DET_A") (pintype "passive"))
    (pad "11" smd rect locked (at 4.299 7.952) (size 1 1.2) (layers "B.Cu" "B.Paste" "B.Mask")
      (net 1 "GND") (pinfunction "SHIELD") (pintype "passive"))
    (pad "11" smd rect locked (at -6.851 3.652) (size 1 1.2) (layers "B.Cu" "B.Paste" "B.Mask")
      (net 1 "GND") (pinfunction "SHIELD") (pintype "passive"))
    (pad "11" smd rect locked (at -6.851 -6.698) (size 1 2.8) (layers "B.Cu" "B.Paste" "B.Mask")
      (net 1 "GND") (pinfunction "SHIELD") (pintype "passive"))
    (pad "11" smd rect locked (at 6.648 -7.148) (size 1.3 1.9) (layers "B.Cu" "B.Paste" "B.Mask")
      (net 1 "GND") (pinfunction "SHIELD") (pintype "passive"))
  )

  (footprint "sa800u-baseboard-hw-footprints:R_0402_1005Metric" (layer "B.Cu")
    (tedit 5FD9C158)
    (at 121.88 93.8 90)
    (descr "Resistor SMD 0402")
    (tags "resistor SMD 0402")
    (property "Author" "Antmicro")
    (property "DNP" "DNP")
    (property "License" "Apache-2.0")
    (property "MPN" "CR0402-FX-1003GLF")
    (property "Manufacturer" "Bourns")
    (property "Sheetfile" "other-interfaces.kicad_sch")
    (property "Sheetname" "Other Interfaces")
    (property "Tolerance" "1%")
    (property "Val" "100k")
    (attr exclude_from_pos_files)
    (fp_text reference "R94" (at -0.87 0.5 270) (layer "B.SilkS")
      (effects (font (size 0.7 0.7) (thickness 0.15)) (justify left bottom mirror))
    )
    (fp_text value "R_100k_0402" (at 0 -1.4 270) (layer "B.Fab")
      (effects (font (size 0.7 0.7) (thickness 0.15)) (justify left bottom mirror))
    )
    (fp_text user "Author: Antmicro" (at -0.95 -4.169 270) (layer "B.Fab") hide
      (effects (font (size 0.7 0.7) (thickness 0.15)) (justify left bottom mirror))
    )
    (fp_text user "License: Apache-2.0" (at -0.95 -5.169 270) (layer "B.Fab") hide
      (effects (font (size 0.7 0.7) (thickness 0.15)) (justify left bottom mirror))
    )
    (fp_text user "${REFERENCE}" (at -0.95 -3.168 270) (layer "B.Fab") hide
      (effects (font (size 0.7 0.7) (thickness 0.15)) (justify left bottom mirror))
    )
    (fp_rect (start -0.93 0.47) (end 0.93 -0.47) (layer "B.CrtYd") (width 0.05) (fill none))
    (fp_rect (start -0.5 0.25) (end 0.5 -0.25) (layer "B.Fab") (width 0.15) (fill none))
    (pad "1" smd roundrect (at -0.485 0 90) (size 0.59 0.64) (layers "B.Cu" "B.Paste" "B.Mask") (roundrect_rratio 0.25)
      (net 132 "VREG_S4A_1V8") (pintype "passive"))
    (pad "2" smd roundrect (at 0.485 0 90) (size 0.59 0.64) (layers "B.Cu" "B.Paste" "B.Mask") (roundrect_rratio 0.25)
      (net 112 "SD_DET") (pintype "passive"))
  )

  (footprint "sa800u-baseboard-hw-footprints:Nexperia_DFN-10_2.5x1mm_P0.5mm" (layer "B.Cu")
    (tedit 6215DC23)
    (at 133.519 100.7925)
    (property "Author" "Antmicro")
    (property "License" "Apache-2.0")
    (property "MPN" "PUSB3F96X")
    (property "Manufacturer" "Nexperia")
    (property "Sheetfile" "other-interfaces.kicad_sch")
    (property "Sheetname" "Other Interfaces")
    (attr smd)
    (fp_text reference "D22" (at 0.96 1.59 180) (layer "B.SilkS")
      (effects (font (size 0.7 0.7) (thickness 0.15)) (justify left bottom mirror))
    )
    (fp_text value "PUSB3F96X_PASS" (at -0.016 -1.705 180) (layer "B.Fab")
      (effects (font (size 0.7 0.7) (thickness 0.15)) (justify left bottom mirror))
    )
    (fp_text user "Author: Antmicro" (at -1.367 -4.905 180) (layer "B.Fab") hide
      (effects (font (size 0.7 0.7) (thickness 0.15)) (justify left bottom mirror))
    )
    (fp_text user "License: Apache-2.0" (at -1.367 -6.105 180) (layer "B.Fab") hide
      (effects (font (size 0.7 0.7) (thickness 0.15)) (justify left bottom mirror))
    )
    (fp_text user "${REFERENCE}" (at -1.367 -3.704 180) (layer "B.Fab") hide
      (effects (font (size 0.7 0.7) (thickness 0.15)) (justify left bottom mirror))
    )
    (fp_line (start 1.233 -0.405) (end 1.233 0.396) (layer "B.SilkS") (width 0.15))
    (fp_line (start -1.266 0.396) (end -1.266 -0.405) (layer "B.SilkS") (width 0.15))
    (fp_circle (center -1.317 -0.704) (end -1.266 -0.704) (layer "B.SilkS") (width 0.15) (fill solid))
    (fp_rect (start -1.4 0.7) (end 1.4 -0.7) (layer "B.CrtYd") (width 0.05) (fill none))
    (pad "1" smd rect (at -1.016 -0.392) (size 0.2 0.475) (layers "B.Cu" "B.Paste" "B.Mask")
      (net 248 "/Other Interfaces/SD_CMD_R") (pinfunction "CH1") (pintype "passive"))
    (pad "2" smd rect (at -0.517 -0.392) (size 0.2 0.475) (layers "B.Cu" "B.Paste" "B.Mask")
      (net 249 "/Other Interfaces/SD_DATA3_R") (pinfunction "CH2") (pintype "passive"))
    (pad "3" smd rect (at -0.016 -0.392) (size 0.2 0.475) (layers "B.Cu" "B.Paste" "B.Mask")
      (net 1 "GND") (pinfunction "GND") (pintype "passive"))
    (pad "4" smd rect (at 0.482 -0.392) (size 0.2 0.475) (layers "B.Cu" "B.Paste" "B.Mask")
      (net 247 "/Other Interfaces/SD_DATA2_R") (pinfunction "CH3") (pintype "passive"))
    (pad "5" smd rect (at 0.982 -0.392) (size 0.2 0.475) (layers "B.Cu" "B.Paste" "B.Mask")
      (net 246 "/Other Interfaces/SD_DET_R") (pinfunction "CH4") (pintype "passive"))
    (pad "6" smd rect (at 0.982 0.383 180) (size 0.2 0.475) (layers "B.Cu" "B.Paste" "B.Mask")
      (net 246 "/Other Interfaces/SD_DET_R") (pinfunction "CH4") (pintype "passive"))
    (pad "7" smd rect (at 0.482 0.383 180) (size 0.2 0.475) (layers "B.Cu" "B.Paste" "B.Mask")
      (net 247 "/Other Interfaces/SD_DATA2_R") (pinfunction "CH3") (pintype "passive"))
    (pad "8" smd rect (at -0.016 0.383 180) (size 0.2 0.475) (layers "B.Cu" "B.Paste" "B.Mask")
      (net 1 "GND") (pinfunction "GND") (pintype "passive"))
    (pad "9" smd rect (at -0.517 0.383 180) (size 0.2 0.475) (layers "B.Cu" "B.Paste" "B.Mask")
      (net 249 "/Other Interfaces/SD_DATA3_R") (pinfunction "CH2") (pintype "passive"))
    (pad "10" smd rect (at -1.016 0.383 180) (size 0.2 0.475) (layers "B.Cu" "B.Paste" "B.Mask")
      (net 248 "/Other Interfaces/SD_CMD_R") (pinfunction "CH1") (pintype "passive"))
  )

  (footprint "sa800u-baseboard-hw-footprints:Nexperia_DFN-10_2.5x1mm_P0.5mm" (layer "B.Cu")
    (tedit 6215DC23)
    (at 128.36 100.79)
    (property "Author" "Antmicro")
    (property "License" "Apache-2.0")
    (property "MPN" "PUSB3F96X")
    (property "Manufacturer" "Nexperia")
    (property "Sheetfile" "other-interfaces.kicad_sch")
    (property "Sheetname" "Other Interfaces")
    (attr smd)
    (fp_text reference "D23" (at 1.04 1.55 180) (layer "B.SilkS")
      (effects (font (size 0.7 0.7) (thickness 0.15)) (justify left bottom mirror))
    )
    (fp_text value "PUSB3F96X_PASS" (at -0.016 -1.705 180) (layer "B.Fab")
      (effects (font (size 0.7 0.7) (thickness 0.15)) (justify left bottom mirror))
    )
    (fp_text user "Author: Antmicro" (at -1.367 -4.905 180) (layer "B.Fab") hide
      (effects (font (size 0.7 0.7) (thickness 0.15)) (justify left bottom mirror))
    )
    (fp_text user "${REFERENCE}" (at -1.367 -3.704 180) (layer "B.Fab") hide
      (effects (font (size 0.7 0.7) (thickness 0.15)) (justify left bottom mirror))
    )
    (fp_text user "License: Apache-2.0" (at -1.367 -6.105 180) (layer "B.Fab") hide
      (effects (font (size 0.7 0.7) (thickness 0.15)) (justify left bottom mirror))
    )
    (fp_line (start 1.233 -0.405) (end 1.233 0.396) (layer "B.SilkS") (width 0.15))
    (fp_line (start -1.266 0.396) (end -1.266 -0.405) (layer "B.SilkS") (width 0.15))
    (fp_circle (center -1.317 -0.704) (end -1.266 -0.704) (layer "B.SilkS") (width 0.15) (fill solid))
    (fp_rect (start -1.4 0.7) (end 1.4 -0.7) (layer "B.CrtYd") (width 0.05) (fill none))
    (pad "1" smd rect (at -1.016 -0.392) (size 0.2 0.475) (layers "B.Cu" "B.Paste" "B.Mask")
      (net 251 "/Other Interfaces/SD_DATA1_R") (pinfunction "CH1") (pintype "passive"))
    (pad "2" smd rect (at -0.517 -0.392) (size 0.2 0.475) (layers "B.Cu" "B.Paste" "B.Mask")
      (net 252 "/Other Interfaces/SD_DATA0_R") (pinfunction "CH2") (pintype "passive"))
    (pad "3" smd rect (at -0.016 -0.392) (size 0.2 0.475) (layers "B.Cu" "B.Paste" "B.Mask")
      (net 1 "GND") (pinfunction "GND") (pintype "passive"))
    (pad "4" smd rect (at 0.482 -0.392) (size 0.2 0.475) (layers "B.Cu" "B.Paste" "B.Mask")
      (net 250 "/Other Interfaces/SD_CLK_R") (pinfunction "CH3") (pintype "passive"))
    (pad "5" smd rect (at 0.982 -0.392) (size 0.2 0.475) (layers "B.Cu" "B.Paste" "B.Mask")
      (net 227 "/Other Interfaces/SD_VDD_R") (pinfunction "CH4") (pintype "passive"))
    (pad "6" smd rect (at 0.982 0.383 180) (size 0.2 0.475) (layers "B.Cu" "B.Paste" "B.Mask")
      (net 227 "/Other Interfaces/SD_VDD_R") (pinfunction "CH4") (pintype "passive"))
    (pad "7" smd rect (at 0.482 0.383 180) (size 0.2 0.475) (layers "B.Cu" "B.Paste" "B.Mask")
      (net 250 "/Other Interfaces/SD_CLK_R") (pinfunction "CH3") (pintype "passive"))
    (pad "8" smd rect (at -0.016 0.383 180) (size 0.2 0.475) (layers "B.Cu" "B.Paste" "B.Mask")
      (net 1 "GND") (pinfunction "GND") (pintype "passive"))
    (pad "9" smd rect (at -0.517 0.383 180) (size 0.2 0.475) (layers "B.Cu" "B.Paste" "B.Mask")
      (net 252 "/Other Interfaces/SD_DATA0_R") (pinfunction "CH2") (pintype "passive"))
    (pad "10" smd rect (at -1.016 0.383 180) (size 0.2 0.475) (layers "B.Cu" "B.Paste" "B.Mask")
      (net 251 "/Other Interfaces/SD_DATA1_R") (pinfunction "CH1") (pintype "passive"))
  )

  (footprint "sa800u-baseboard-hw-footprints:R_0402_1005Metric" (layer "B.Cu")
    (tedit 5FD9C158)
    (at 81.35 120.4 -90)
    (descr "Resistor SMD 0402")
    (tags "resistor SMD 0402")
    (property "Author" "Antmicro")
    (property "License" "Apache-2.0")
    (property "MPN" "CR0402-FX-2201GLF")
    (property "Manufacturer" "Bourns")
    (property "Sheetfile" "psu.kicad_sch")
    (property "Sheetname" "PSU")
    (property "Tolerance" "1%")
    (property "Val" "2k2")
    (attr smd)
    (fp_text reference "R124" (at 0.78 -0.52 90) (layer "B.SilkS")
      (effects (font (size 0.7 0.7) (thickness 0.15)) (justify left bottom mirror))
    )
    (fp_text value "R_2k2_0402" (at 0 -1.4 90) (layer "B.Fab")
      (effects (font (size 0.7 0.7) (thickness 0.15)) (justify left bottom mirror))
    )
    (fp_text user "${REFERENCE}" (at -0.95 -3.168 90) (layer "B.Fab") hide
      (effects (font (size 0.7 0.7) (thickness 0.15)) (justify left bottom mirror))
    )
    (fp_text user "License: Apache-2.0" (at -0.95 -5.169 90) (layer "B.Fab") hide
      (effects (font (size 0.7 0.7) (thickness 0.15)) (justify left bottom mirror))
    )
    (fp_text user "Author: Antmicro" (at -0.95 -4.169 90) (layer "B.Fab") hide
      (effects (font (size 0.7 0.7) (thickness 0.15)) (justify left bottom mirror))
    )
    (fp_rect (start -0.93 0.47) (end 0.93 -0.47) (layer "B.CrtYd") (width 0.05) (fill none))
    (fp_rect (start -0.5 0.25) (end 0.5 -0.25) (layer "B.Fab") (width 0.15) (fill none))
    (pad "1" smd roundrect (at -0.485 0 270) (size 0.59 0.64) (layers "B.Cu" "B.Paste" "B.Mask") (roundrect_rratio 0.25)
      (net 405 "Net-(R123-Pad2)") (pintype "passive"))
    (pad "2" smd roundrect (at 0.485 0 270) (size 0.59 0.64) (layers "B.Cu" "B.Paste" "B.Mask") (roundrect_rratio 0.25)
      (net 1 "GND") (pintype "passive"))
  )

  (footprint "sa800u-baseboard-hw-footprints:F52R-1A7H1-11020" (layer "B.Cu")
    (tedit 6215E19A)
    (at 152 126.5 -90)
    (property "Author" "Antmicro")
    (property "License" "Apache-2.0")
    (property "MPN" "F52R-1A7H1-11020")
    (property "Manufacturer" "Amphenol")
    (property "Sheetfile" "lcm.kicad_sch")
    (property "Sheetname" "LCM")
    (attr smd)
    (fp_text reference "J6" (at -13.2 3.8 90) (layer "B.SilkS")
      (effects (font (size 0.65 0.65) (thickness 0.15)) (justify mirror))
    )
    (fp_text value "F52R-1A7H1-11020" (at 0 -1.2 90) (layer "B.Fab")
      (effects (font (size 0.65 0.65) (thickness 0.15)) (justify mirror))
    )
    (fp_text user "${REFERENCE}" (at 0 0 90) (layer "B.Fab")
      (effects (font (size 0.65 0.65) (thickness 0.15)) (justify mirror))
    )
    (fp_text user "License: Apache-2.0" (at -14.148 -7.559 90) (layer "B.Fab") hide
      (effects (font (size 0.7 0.7) (thickness 0.15)) (justify left bottom mirror))
    )
    (fp_text user "Author: Antmicro" (at -14.148 -6.358 90) (layer "B.Fab") hide
      (effects (font (size 0.7 0.7) (thickness 0.15)) (justify left bottom mirror))
    )
    (fp_line (start -14.022 -3.031) (end 14.019 -3.031) (layer "B.SilkS") (width 0.15))
    (fp_line (start 14.019 -3.031) (end 14.019 2.734) (layer "B.SilkS") (width 0.15))
    (fp_line (start 14.019 2.734) (end 9.992 2.734) (layer "B.SilkS") (width 0.15))
    (fp_line (start -9.994 2.734) (end -14.022 2.734) (layer "B.SilkS") (width 0.15))
    (fp_line (start -14.022 2.734) (end -14.022 -3.031) (layer "B.SilkS") (width 0.15))
    (fp_circle (center -10.2 2.4) (end -10.15 2.4) (layer "B.SilkS") (width 0.15) (fill solid))
    (fp_rect (start -14.4 3.1) (end 14.4 -3.4) (layer "B.CrtYd") (width 0.05) (fill none))
    (fp_line (start 13.893 -2.905) (end 13.893 2.606) (layer "B.Fab") (width 0.15))
    (fp_line (start -13.894 -2.905) (end 13.893 -2.905) (layer "B.Fab") (width 0.15))
    (fp_line (start -13.894 2.606) (end -13.894 -2.905) (layer "B.Fab") (width 0.15))
    (fp_line (start 13.893 2.606) (end -13.894 2.606) (layer "B.Fab") (width 0.15))
    (pad "1" smd rect (at -9.5 2.351 270) (size 0.3048 1.0922) (layers "B.Cu" "B.Paste" "B.Mask")
      (net 1 "GND") (pinfunction "1") (pintype "unspecified"))
    (pad "2" smd rect (at -8.5 2.351 270) (size 0.3048 1.0922) (layers "B.Cu" "B.Paste" "B.Mask")
      (net 318 "/LCM/DSI_LN3_L_N") (pinfunction "2") (pintype "unspecified"))
    (pad "3" smd rect (at -7.5 2.351 270) (size 0.3048 1.0922) (layers "B.Cu" "B.Paste" "B.Mask")
      (net 317 "/LCM/DSI_LN3_L_P") (pinfunction "3") (pintype "unspecified"))
    (pad "4" smd rect (at -6.5 2.351 270) (size 0.3048 1.0922) (layers "B.Cu" "B.Paste" "B.Mask")
      (net 1 "GND") (pinfunction "4") (pintype "unspecified"))
    (pad "5" smd rect (at -5.5 2.351 270) (size 0.3048 1.0922) (layers "B.Cu" "B.Paste" "B.Mask")
      (net 316 "/LCM/DSI_LN2_L_N") (pinfunction "5") (pintype "unspecified"))
    (pad "6" smd rect (at -4.5 2.351 270) (size 0.3048 1.0922) (layers "B.Cu" "B.Paste" "B.Mask")
      (net 315 "/LCM/DSI_LN2_L_P") (pinfunction "6") (pintype "unspecified"))
    (pad "7" smd rect (at -3.5 2.351 270) (size 0.3048 1.0922) (layers "B.Cu" "B.Paste" "B.Mask")
      (net 1 "GND") (pinfunction "7") (pintype "unspecified"))
    (pad "8" smd rect (at -2.5 2.351 270) (size 0.3048 1.0922) (layers "B.Cu" "B.Paste" "B.Mask")
      (net 314 "/LCM/DSI_LN1_L_N") (pinfunction "8") (pintype "unspecified"))
    (pad "9" smd rect (at -1.5 2.351 270) (size 0.3048 1.0922) (layers "B.Cu" "B.Paste" "B.Mask")
      (net 313 "/LCM/DSI_LN1_L_P") (pinfunction "9") (pintype "unspecified"))
    (pad "10" smd rect (at -0.5 2.351 270) (size 0.3048 1.0922) (layers "B.Cu" "B.Paste" "B.Mask")
      (net 1 "GND") (pinfunction "10") (pintype "unspecified"))
    (pad "11" smd rect (at 0.498 2.351 270) (size 0.3048 1.0922) (layers "B.Cu" "B.Paste" "B.Mask")
      (net 312 "/LCM/DSI_LN0_L_N") (pinfunction "11") (pintype "unspecified"))
    (pad "12" smd rect (at 1.499 2.351 270) (size 0.3048 1.0922) (layers "B.Cu" "B.Paste" "B.Mask")
      (net 311 "/LCM/DSI_LN0_L_P") (pinfunction "12") (pintype "unspecified"))
    (pad "13" smd rect (at 2.499 2.351 270) (size 0.3048 1.0922) (layers "B.Cu" "B.Paste" "B.Mask")
      (net 1 "GND") (pinfunction "13") (pintype "unspecified"))
    (pad "14" smd rect (at 3.499 2.351 270) (size 0.3048 1.0922) (layers "B.Cu" "B.Paste" "B.Mask")
      (net 310 "/LCM/DSI_CLK_L_N") (pinfunction "14") (pintype "unspecified"))
    (pad "15" smd rect (at 4.498 2.351 270) (size 0.3048 1.0922) (layers "B.Cu" "B.Paste" "B.Mask")
      (net 309 "/LCM/DSI_CLK_L_P") (pinfunction "15") (pintype "unspecified"))
    (pad "16" smd rect (at 5.499 2.351 270) (size 0.3048 1.0922) (layers "B.Cu" "B.Paste" "B.Mask")
      (net 1 "GND") (pinfunction "16") (pintype "unspecified"))
    (pad "17" smd rect (at 6.499 2.351 270) (size 0.3048 1.0922) (layers "B.Cu" "B.Paste" "B.Mask")
      (net 148 "/LCM/TP_I2C_SCL_3V3") (pinfunction "17") (pintype "unspecified"))
    (pad "18" smd rect (at 7.499 2.351 270) (size 0.3048 1.0922) (layers "B.Cu" "B.Paste" "B.Mask")
      (net 149 "/LCM/TP_I2C_SDA_3V3") (pinfunction "18") (pintype "unspecified"))
    (pad "19" smd rect (at 8.499 2.351 270) (size 0.3048 1.0922) (layers "B.Cu" "B.Paste" "B.Mask")
      (net 1 "GND") (pinfunction "19") (pintype "unspecified"))
    (pad "20" smd rect (at 9.499 2.351 270) (size 0.3048 1.0922) (layers "B.Cu" "B.Paste" "B.Mask")
      (net 131 "3V3_SYS") (pinfunction "20") (pintype "unspecified"))
    (pad "21" smd rect (at -11.85 1.18 180) (size 2.0541 1.40005) (layers "B.Cu" "B.Paste" "B.Mask")
      (net 662 "unconnected-(J6-Pad21)") (pinfunction "SH1") (pintype "unspecified+no_connect"))
    (pad "21" smd rect (at -12.251 1.357 270) (size 2.1082 1.6002) (layers "B.Cu" "B.Paste" "B.Mask")
      (net 662 "unconnected-(J6-Pad21)") (pinfunction "SH1") (pintype "unspecified+no_connect"))
    (pad "22" smd rect (at 12.249 1.357 270) (size 2.1082 1.6002) (layers "B.Cu" "B.Paste" "B.Mask")
      (net 663 "unconnected-(J6-Pad22)") (pinfunction "SH2") (pintype "unspecified+no_connect"))
    (pad "22" smd rect (at 11.84 1.18 180) (size 2.0541 1.40005) (layers "B.Cu" "B.Paste" "B.Mask")
      (net 663 "unconnected-(J6-Pad22)") (pinfunction "SH2") (pintype "unspecified+no_connect"))
  )

  (footprint "sa800u-baseboard-hw-footprints:R_0402_1005Metric" (layer "B.Cu")
    (tedit 5FD9C158)
    (at 75.6 121.25)
    (descr "Resistor SMD 0402")
    (tags "resistor SMD 0402")
    (property "Author" "Antmicro")
    (property "License" "Apache-2.0")
    (property "MPN" "CR0402-FX-2201GLF")
    (property "Manufacturer" "Bourns")
    (property "Sheetfile" "psu.kicad_sch")
    (property "Sheetname" "PSU")
    (property "Tolerance" "1%")
    (property "Val" "2k2")
    (attr smd)
    (fp_text reference "R125" (at -0.22 -4.79 180) (layer "B.SilkS")
      (effects (font (size 0.7 0.7) (thickness 0.15)) (justify left bottom mirror))
    )
    (fp_text value "R_2k2_0402" (at 0 -1.4 180) (layer "B.Fab")
      (effects (font (size 0.7 0.7) (thickness 0.15)) (justify left bottom mirror))
    )
    (fp_text user "License: Apache-2.0" (at -0.95 -5.169 180) (layer "B.Fab") hide
      (effects (font (size 0.7 0.7) (thickness 0.15)) (justify left bottom mirror))
    )
    (fp_text user "Author: Antmicro" (at -0.95 -4.169 180) (layer "B.Fab") hide
      (effects (font (size 0.7 0.7) (thickness 0.15)) (justify left bottom mirror))
    )
    (fp_text user "${REFERENCE}" (at -0.95 -3.168 180) (layer "B.Fab") hide
      (effects (font (size 0.7 0.7) (thickness 0.15)) (justify left bottom mirror))
    )
    (fp_rect (start -0.93 0.47) (end 0.93 -0.47) (layer "B.CrtYd") (width 0.05) (fill none))
    (fp_rect (start -0.5 0.25) (end 0.5 -0.25) (layer "B.Fab") (width 0.15) (fill none))
    (pad "1" smd roundrect (at -0.485 0) (size 0.59 0.64) (layers "B.Cu" "B.Paste" "B.Mask") (roundrect_rratio 0.25)
      (net 74 "VDD") (pintype "passive"))
    (pad "2" smd roundrect (at 0.485 0) (size 0.59 0.64) (layers "B.Cu" "B.Paste" "B.Mask") (roundrect_rratio 0.25)
      (net 406 "Net-(R125-Pad2)") (pintype "passive"))
  )

  (footprint "sa800u-baseboard-hw-footprints:R_0402_1005Metric" (layer "B.Cu")
    (tedit 5FD9C158)
    (at 73.6 121.25 180)
    (descr "Resistor SMD 0402")
    (tags "resistor SMD 0402")
    (property "Author" "Antmicro")
    (property "License" "Apache-2.0")
    (property "MPN" "CR0402-FX-1001GLF")
    (property "Manufacturer" "Bourns")
    (property "Sheetfile" "psu.kicad_sch")
    (property "Sheetname" "PSU")
    (property "Tolerance" "1%")
    (property "Val" "1k")
    (attr smd)
    (fp_text reference "R126" (at 0.82 4.75) (layer "B.SilkS")
      (effects (font (size 0.7 0.7) (thickness 0.15)) (justify left bottom mirror))
    )
    (fp_text value "R_1k_0402" (at 0 -1.4) (layer "B.Fab")
      (effects (font (size 0.7 0.7) (thickness 0.15)) (justify left bottom mirror))
    )
    (fp_text user "${REFERENCE}" (at -0.95 -3.168) (layer "B.Fab") hide
      (effects (font (size 0.7 0.7) (thickness 0.15)) (justify left bottom mirror))
    )
    (fp_text user "Author: Antmicro" (at -0.95 -4.169) (layer "B.Fab") hide
      (effects (font (size 0.7 0.7) (thickness 0.15)) (justify left bottom mirror))
    )
    (fp_text user "License: Apache-2.0" (at -0.95 -5.169) (layer "B.Fab") hide
      (effects (font (size 0.7 0.7) (thickness 0.15)) (justify left bottom mirror))
    )
    (fp_rect (start -0.93 0.47) (end 0.93 -0.47) (layer "B.CrtYd") (width 0.05) (fill none))
    (fp_rect (start -0.5 0.25) (end 0.5 -0.25) (layer "B.Fab") (width 0.15) (fill none))
    (pad "1" smd roundrect (at -0.485 0 180) (size 0.59 0.64) (layers "B.Cu" "B.Paste" "B.Mask") (roundrect_rratio 0.25)
      (net 406 "Net-(R125-Pad2)") (pintype "passive"))
    (pad "2" smd roundrect (at 0.485 0 180) (size 0.59 0.64) (layers "B.Cu" "B.Paste" "B.Mask") (roundrect_rratio 0.25)
      (net 390 "Net-(Q15-Pad1)") (pintype "passive"))
  )

  (footprint "sa800u-baseboard-hw-footprints:R_0402_1005Metric" (layer "B.Cu")
    (tedit 5FD9C158)
    (at 75.6 120.25)
    (descr "Resistor SMD 0402")
    (tags "resistor SMD 0402")
    (property "Author" "Antmicro")
    (property "License" "Apache-2.0")
    (property "MPN" "CR0402-FX-7501GLF")
    (property "Manufacturer" "Bourns")
    (property "Sheetfile" "psu.kicad_sch")
    (property "Sheetname" "PSU")
    (property "Tolerance" "1%")
    (property "Val" "7k5")
    (attr smd)
    (fp_text reference "R123" (at -0.21 -4.79 180) (layer "B.SilkS")
      (effects (font (size 0.7 0.7) (thickness 0.15)) (justify left bottom mirror))
    )
    (fp_text value "R_7k5_0402" (at 0 -1.4 180) (layer "B.Fab")
      (effects (font (size 0.7 0.7) (thickness 0.15)) (justify left bottom mirror))
    )
    (fp_text user "Author: Antmicro" (at -0.95 -4.169 180) (layer "B.Fab") hide
      (effects (font (size 0.7 0.7) (thickness 0.15)) (justify left bottom mirror))
    )
    (fp_text user "${REFERENCE}" (at -0.95 -3.168 180) (layer "B.Fab") hide
      (effects (font (size 0.7 0.7) (thickness 0.15)) (justify left bottom mirror))
    )
    (fp_text user "License: Apache-2.0" (at -0.95 -5.169 180) (layer "B.Fab") hide
      (effects (font (size 0.7 0.7) (thickness 0.15)) (justify left bottom mirror))
    )
    (fp_rect (start -0.93 0.47) (end 0.93 -0.47) (layer "B.CrtYd") (width 0.05) (fill none))
    (fp_rect (start -0.5 0.25) (end 0.5 -0.25) (layer "B.Fab") (width 0.15) (fill none))
    (pad "1" smd roundrect (at -0.485 0) (size 0.59 0.64) (layers "B.Cu" "B.Paste" "B.Mask") (roundrect_rratio 0.25)
      (net 74 "VDD") (pintype "passive"))
    (pad "2" smd roundrect (at 0.485 0) (size 0.59 0.64) (layers "B.Cu" "B.Paste" "B.Mask") (roundrect_rratio 0.25)
      (net 405 "Net-(R123-Pad2)") (pintype "passive"))
  )

  (footprint "sa800u-baseboard-hw-footprints:C_0402_1005Metric" (layer "B.Cu")
    (tedit 616D63CF)
    (at 72.7 102.2 90)
    (descr "Capacitor SMD 0402")
    (tags "capacitor SMD 0402")
    (property "Author" "Antmicro")
    (property "Dielectric" "")
    (property "License" "Apache-2.0")
    (property "MPN" "C1005X6S1A105K050BC")
    (property "Manufacturer" "TDK")
    (property "Sheetfile" "poe.kicad_sch")
    (property "Sheetname" "PoE")
    (property "Val" "1u")
    (property "Voltage" "")
    (attr smd)
    (fp_text reference "C150" (at 1.46 -1.67 270) (layer "B.SilkS")
      (effects (font (size 0.7 0.7) (thickness 0.15)) (justify left bottom mirror))
    )
    (fp_text value "C_1u_0402" (at 0 -1.4 270) (layer "B.Fab")
      (effects (font (size 0.7 0.7) (thickness 0.15)) (justify left bottom mirror))
    )
    (fp_text user "${REFERENCE}" (at -0.932 -3.168 270) (layer "B.Fab") hide
      (effects (font (size 0.7 0.7) (thickness 0.15)) (justify left bottom mirror))
    )
    (fp_text user "License: Apache-2.0" (at -0.932 -5.17 270) (layer "B.Fab") hide
      (effects (font (size 0.7 0.7) (thickness 0.15)) (justify left bottom mirror))
    )
    (fp_text user "Author: Antmicro" (at -0.932 -4.17 270) (layer "B.Fab") hide
      (effects (font (size 0.7 0.7) (thickness 0.15)) (justify left bottom mirror))
    )
    (fp_rect (start -0.94 0.47) (end 0.94 -0.47) (layer "B.CrtYd") (width 0.05) (fill none))
    (fp_rect (start -0.499 0.249) (end 0.499 -0.249) (layer "B.Fab") (width 0.15) (fill none))
    (pad "1" smd roundrect (at -0.484 0 90) (size 0.59 0.64) (layers "B.Cu" "B.Paste" "B.Mask") (roundrect_rratio 0.25)
      (net 136 "5V_POE") (pintype "passive"))
    (pad "2" smd roundrect (at 0.484 0 90) (size 0.59 0.64) (layers "B.Cu" "B.Paste" "B.Mask") (roundrect_rratio 0.25)
      (net 1 "GND") (pintype "passive"))
  )

  (footprint "sa800u-baseboard-hw-footprints:PowerPak-1212" (layer "B.Cu")
    (tedit 625E61BE)
    (at 74.75 106.9)
    (property "Author" "Antmicro")
    (property "License" "Apache-2.0")
    (property "MPN" "SI7223DN-T1-GE3")
    (property "Manufacturer" "Vishay")
    (property "Sheetfile" "psu.kicad_sch")
    (property "Sheetname" "PSU")
    (attr smd)
    (fp_text reference "Q12" (at 0 2.5 180) (layer "B.SilkS")
      (effects (font (size 0.65 0.65) (thickness 0.15)) (justify mirror))
    )
    (fp_text value "Si7223DN" (at 0 -3 180) (layer "B.Fab") hide
      (effects (font (size 0.65 0.65) (thickness 0.15)) (justify mirror))
    )
    (fp_text user "License: Apache-2.0" (at -2.667 -8.599 180) (layer "B.Fab") hide
      (effects (font (size 0.7 0.7) (thickness 0.15)) (justify left bottom mirror))
    )
    (fp_text user "${REFERENCE}" (at 0 0 180) (layer "B.Fab") hide
      (effects (font (size 0.65 0.65) (thickness 0.15)) (justify mirror))
    )
    (fp_text user "Author: Antmicro" (at -2.667 -7.4 180) (layer "B.Fab") hide
      (effects (font (size 0.7 0.7) (thickness 0.15)) (justify left bottom mirror))
    )
    (fp_poly (pts
        (xy 1.699 0.122)
        (xy 1.699 0.529)
        (xy 1.14 0.529)
        (xy 1.14 0.772)
        (xy 1.699 0.772)
        (xy 1.699 1.179)
        (xy 1.14 1.179)
        (xy 1.14 1.12)
        (xy -0.047 1.12)
        (xy -0.047 1.7)
        (xy -0.387 1.7)
        (xy -0.387 1.12)
        (xy -0.386607 0.174507)
        (xy 1.14 0.175)
        (xy 1.14 0.122)
      ) (layer "B.Paste") (width 0.1) (fill solid))
    (fp_poly (pts
        (xy 1.699 -1.178)
        (xy 1.699 -0.771)
        (xy 1.14 -0.771)
        (xy 1.14 -0.528)
        (xy 1.699 -0.528)
        (xy 1.699 -0.121)
        (xy 1.14 -0.121)
        (xy 1.14 -0.174)
        (xy -0.387 -0.174)
        (xy -0.387 -1.119)
        (xy -0.386607 -1.698508)
        (xy -0.047 -1.699)
        (xy -0.047 -1.119)
        (xy 1.14 -1.119)
        (xy 1.14 -1.178)
      ) (layer "B.Paste") (width 0.1) (fill solid))
    (fp_line (start 1.701 1.702) (end 1.701 1.511) (layer "B.SilkS") (width 0.15))
    (fp_line (start -1.702 1.511) (end -1.702 1.702) (layer "B.SilkS") (width 0.15))
    (fp_line (start -1.702 -1.701) (end -1.702 -1.51) (layer "B.SilkS") (width 0.15))
    (fp_line (start 0.2 1.702) (end 1.701 1.702) (layer "B.SilkS") (width 0.15))
    (fp_line (start 1.701 -1.51) (end 1.701 -1.701) (layer "B.SilkS") (width 0.15))
    (fp_line (start 1.701 -1.701) (end 0.2 -1.7) (layer "B.SilkS") (width 0.15))
    (fp_line (start -0.6 -1.7) (end -1.702 -1.701) (layer "B.SilkS") (width 0.15))
    (fp_line (start -1.702 1.702) (end -0.6 1.7) (layer "B.SilkS") (width 0.15))
    (fp_circle (center -1.85 1.3) (end -1.8 1.3) (layer "B.SilkS") (width 0.15) (fill solid))
    (fp_poly (pts
        (xy 1.699 1.179)
        (xy 1.14 1.179)
        (xy 1.14 1.12)
        (xy -0.047 1.12)
        (xy -0.047 1.7)
        (xy -0.387 1.7)
        (xy -0.387 0.175)
        (xy 1.14 0.175)
        (xy 1.14 0.122)
        (xy 1.699 0.122)
        (xy 1.699 0.529)
        (xy 1.14 0.529)
        (xy 1.14 0.772)
        (xy 1.699 0.772)
      ) (layer "B.Mask") (width 0.1) (fill solid))
    (fp_poly (pts
        (xy -0.387 -0.174)
        (xy -0.387 -1.699)
        (xy -0.047 -1.699)
        (xy -0.047 -1.119)
        (xy 1.14 -1.119)
        (xy 1.14 -1.178)
        (xy 1.699 -1.178)
        (xy 1.699 -0.771)
        (xy 1.14 -0.771)
        (xy 1.14 -0.528)
        (xy 1.699 -0.528)
        (xy 1.699 -0.121)
        (xy 1.14 -0.121)
        (xy 1.14 -0.174)
      ) (layer "B.Mask") (width 0.1) (fill solid))
    (fp_line (start 1.95 -1.95) (end -1.96 -1.95) (layer "B.CrtYd") (width 0.05))
    (fp_line (start -1.96 -1.95) (end -1.96 1.96) (layer "B.CrtYd") (width 0.05))
    (fp_line (start 1.95 1.96) (end 1.95 -1.95) (layer "B.CrtYd") (width 0.05))
    (fp_line (start -1.96 1.96) (end 1.95 1.96) (layer "B.CrtYd") (width 0.05))
    (fp_line (start -1.575 1.575) (end 1.574 1.575) (layer "B.Fab") (width 0.15))
    (fp_line (start -1.575 -1.574) (end -1.575 1.575) (layer "B.Fab") (width 0.15))
    (fp_line (start 1.574 -1.574) (end -1.575 -1.574) (layer "B.Fab") (width 0.15))
    (fp_line (start 1.574 1.575) (end 1.574 -1.574) (layer "B.Fab") (width 0.15))
    (fp_circle (center 0.99 0.975) (end 0.914 0.975) (layer "B.Fab") (width 0.15) (fill none))
    (pad "1" smd rect (at -1.446 0.975) (size 0.508 0.4064) (layers "B.Cu" "B.Paste" "B.Mask")
      (net 159 "/PSU/VS3") (pinfunction "S1") (pintype "passive"))
    (pad "2" smd rect (at -1.446 0.325) (size 0.508 0.4064) (layers "B.Cu" "B.Paste" "B.Mask")
      (net 367 "/PSU/G3") (pinfunction "G1") (pintype "passive"))
    (pad "3" smd rect (at -1.446 -0.324) (size 0.508 0.4064) (layers "B.Cu" "B.Paste" "B.Mask")
      (net 159 "/PSU/VS3") (pinfunction "S2") (pintype "passive"))
    (pad "4" smd rect (at -1.446 -0.974) (size 0.508 0.4064) (layers "B.Cu" "B.Paste" "B.Mask")
      (net 367 "/PSU/G3") (pinfunction "G2") (pintype "passive"))
    (pad "5" smd rect (at 1.42 -0.974) (size 0.5588 0.4064) (layers "B.Cu" "B.Paste" "B.Mask")
      (net 136 "5V_POE") (pinfunction "D2") (pintype "passive"))
    (pad "6" smd custom (at 1.42 -0.324) (size 0.5588 0.4064) (layers "B.Cu" "B.Paste" "B.Mask")
      (net 136 "5V_POE") (pinfunction "D2") (pintype "passive") (zone_connect 2)
      (options (clearance outline) (anchor rect))
      (primitives
        (gr_poly (pts
            (xy 0.2794 -0.853186)
            (xy 0.2794 -0.446786)
            (xy -0.2794 -0.446786)
            (xy -0.2794 -0.2032)
            (xy 0.2794 -0.2032)
            (xy 0.2794 0.2032)
            (xy -0.2794 0.2032)
            (xy -0.279407 0.150493)
            (xy -1.806607 0.150493)
            (xy -1.806607 -1.374508)
            (xy -1.466602 -1.374508)
            (xy -1.466602 -0.794499)
            (xy -0.279407 -0.794507)
            (xy -0.2794 -0.853186)
          ) (width 0.1) (fill yes))
      ))
    (pad "7" smd custom (at 1.42 0.325) (size 0.5588 0.4064) (layers "B.Cu" "B.Paste" "B.Mask")
      (net 74 "VDD") (pinfunction "D1") (pintype "passive") (zone_connect 2)
      (options (clearance outline) (anchor rect))
      (primitives
        (gr_poly (pts
            (xy 0.2794 0.446786)
            (xy 0.2794 0.853186)
            (xy -0.2794 0.853186)
            (xy -0.279407 0.794507)
            (xy -1.466602 0.794499)
            (xy -1.466602 1.374508)
            (xy -1.806607 1.374508)
            (xy -1.806607 -0.150493)
            (xy -0.279407 -0.150493)
            (xy -0.2794 -0.2032)
            (xy 0.2794 -0.2032)
            (xy 0.2794 0.2032)
            (xy -0.2794 0.2032)
            (xy -0.2794 0.446786)
          ) (width 0.1) (fill yes))
      ))
    (pad "8" smd rect (at 1.42 0.975) (size 0.5588 0.4064) (layers "B.Cu" "B.Paste" "B.Mask")
      (net 74 "VDD") (pinfunction "D1") (pintype "passive"))
  )

  (footprint "sa800u-baseboard-hw-footprints:C_0402_1005Metric" (layer "B.Cu")
    (tedit 616D63CF)
    (at 73.6 125.15)
    (descr "Capacitor SMD 0402")
    (tags "capacitor SMD 0402")
    (property "Author" "Antmicro")
    (property "Dielectric" "X5R")
    (property "License" "Apache-2.0")
    (property "MPN" "GRM155R61H104KE14D")
    (property "Manufacturer" "Murata")
    (property "Sheetfile" "psu.kicad_sch")
    (property "Sheetname" "PSU")
    (property "Val" "100n")
    (property "Voltage" "50V")
    (attr smd)
    (fp_text reference "C123" (at 1.71 3.35 180) (layer "B.SilkS")
      (effects (font (size 0.7 0.7) (thickness 0.15)) (justify left bottom mirror))
    )
    (fp_text value "C_100n_0402" (at 0 -1.4 180) (layer "B.Fab")
      (effects (font (size 0.7 0.7) (thickness 0.15)) (justify left bottom mirror))
    )
    (fp_text user "${REFERENCE}" (at -0.932 -3.168 180) (layer "B.Fab") hide
      (effects (font (size 0.7 0.7) (thickness 0.15)) (justify left bottom mirror))
    )
    (fp_text user "License: Apache-2.0" (at -0.932 -5.17 180) (layer "B.Fab") hide
      (effects (font (size 0.7 0.7) (thickness 0.15)) (justify left bottom mirror))
    )
    (fp_text user "Author: Antmicro" (at -0.932 -4.17 180) (layer "B.Fab") hide
      (effects (font (size 0.7 0.7) (thickness 0.15)) (justify left bottom mirror))
    )
    (fp_rect (start -0.94 0.47) (end 0.94 -0.47) (layer "B.CrtYd") (width 0.05) (fill none))
    (fp_rect (start -0.499 0.249) (end 0.499 -0.249) (layer "B.Fab") (width 0.15) (fill none))
    (pad "1" smd roundrect (at -0.484 0) (size 0.59 0.64) (layers "B.Cu" "B.Paste" "B.Mask") (roundrect_rratio 0.25)
      (net 354 "/PSU/G1") (pintype "passive"))
    (pad "2" smd roundrect (at 0.484 0) (size 0.59 0.64) (layers "B.Cu" "B.Paste" "B.Mask") (roundrect_rratio 0.25)
      (net 1 "GND") (pintype "passive"))
  )

  (footprint "sa800u-baseboard-hw-footprints:C_0402_1005Metric" (layer "B.Cu")
    (tedit 616D63CF)
    (at 73.6 124.15)
    (descr "Capacitor SMD 0402")
    (tags "capacitor SMD 0402")
    (property "Author" "Antmicro")
    (property "Dielectric" "X5R")
    (property "License" "Apache-2.0")
    (property "MPN" "GRM155R61H104KE14D")
    (property "Manufacturer" "Murata")
    (property "Sheetfile" "psu.kicad_sch")
    (property "Sheetname" "PSU")
    (property "Val" "100n")
    (property "Voltage" "50V")
    (attr smd)
    (fp_text reference "C124" (at 1.71 3.35 180) (layer "B.SilkS")
      (effects (font (size 0.7 0.7) (thickness 0.15)) (justify left bottom mirror))
    )
    (fp_text value "C_100n_0402" (at 0 -1.4 180) (layer "B.Fab")
      (effects (font (size 0.7 0.7) (thickness 0.15)) (justify left bottom mirror))
    )
    (fp_text user "License: Apache-2.0" (at -0.932 -5.17 180) (layer "B.Fab") hide
      (effects (font (size 0.7 0.7) (thickness 0.15)) (justify left bottom mirror))
    )
    (fp_text user "Author: Antmicro" (at -0.932 -4.17 180) (layer "B.Fab") hide
      (effects (font (size 0.7 0.7) (thickness 0.15)) (justify left bottom mirror))
    )
    (fp_text user "${REFERENCE}" (at -0.932 -3.168 180) (layer "B.Fab") hide
      (effects (font (size 0.7 0.7) (thickness 0.15)) (justify left bottom mirror))
    )
    (fp_rect (start -0.94 0.47) (end 0.94 -0.47) (layer "B.CrtYd") (width 0.05) (fill none))
    (fp_rect (start -0.499 0.249) (end 0.499 -0.249) (layer "B.Fab") (width 0.15) (fill none))
    (pad "1" smd roundrect (at -0.484 0) (size 0.59 0.64) (layers "B.Cu" "B.Paste" "B.Mask") (roundrect_rratio 0.25)
      (net 355 "/PSU/G2") (pintype "passive"))
    (pad "2" smd roundrect (at 0.484 0) (size 0.59 0.64) (layers "B.Cu" "B.Paste" "B.Mask") (roundrect_rratio 0.25)
      (net 1 "GND") (pintype "passive"))
  )

  (footprint "sa800u-baseboard-hw-footprints:D_0201_0603Metric" (layer "B.Cu")
    (tedit 62026EA2)
    (at 80.05 139.55 -90)
    (property "Author" "Antmicro")
    (property "License" "Apache-2.0")
    (property "MPN" "PESD18VF1BSFYL")
    (property "Manufacturer" "Nexperia")
    (property "Sheetfile" "usb-pd.kicad_sch")
    (property "Sheetname" "USB-PD")
    (attr smd)
    (fp_text reference "D37" (at -0.89 0.47 90) (layer "B.SilkS")
      (effects (font (size 0.7 0.7) (thickness 0.15)) (justify left bottom mirror))
    )
    (fp_text value "PESD18VF1BSFYL" (at 0 -1.25 90) (layer "B.Fab")
      (effects (font (size 0.7 0.7) (thickness 0.15)) (justify left bottom mirror))
    )
    (fp_text user "License: Apache-2.0" (at -0.72 -5.281 90) (layer "B.Fab") hide
      (effects (font (size 0.7 0.7) (thickness 0.15)) (justify left bottom mirror))
    )
    (fp_text user "Author: Antmicro" (at -0.72 -4.081 90) (layer "B.Fab") hide
      (effects (font (size 0.7 0.7) (thickness 0.15)) (justify left bottom mirror))
    )
    (fp_text user "${REFERENCE}" (at -0.72 -2.882 90) (layer "B.Fab") hide
      (effects (font (size 0.7 0.7) (thickness 0.15)) (justify left bottom mirror))
    )
    (fp_line (start -0.025 0.201) (end -0.025 -0.199) (layer "B.SilkS") (width 0.12))
    (fp_rect (start -0.5 0.3) (end 0.5 -0.3) (layer "B.CrtYd") (width 0.05) (fill none))
    (fp_line (start -0.32 0.172) (end 0.32 0.172) (layer "B.Fab") (width 0.15))
    (fp_line (start -0.32 -0.17) (end 0.32 -0.17) (layer "B.Fab") (width 0.15))
    (fp_line (start 0.32 0.172) (end 0.32 -0.17) (layer "B.Fab") (width 0.15))
    (fp_line (start -0.32 0.172) (end -0.32 -0.17) (layer "B.Fab") (width 0.15))
    (pad "1" smd roundrect (at -0.282 0 270) (size 0.38 0.4) (layers "B.Cu" "B.Paste" "B.Mask") (roundrect_rratio 0.05)
      (net 142 "PD_VDD") (pinfunction "1") (pintype "input"))
    (pad "2" smd rect (at 0.28 0 270) (size 0.38 0.4) (layers "B.Cu" "B.Paste" "B.Mask")
      (net 1 "GND") (pinfunction "2") (pintype "input"))
  )

  (footprint "sa800u-baseboard-hw-footprints:C_0402_1005Metric" (layer "B.Cu")
    (tedit 616D63CF)
    (at 73.6 123.15)
    (descr "Capacitor SMD 0402")
    (tags "capacitor SMD 0402")
    (property "Author" "Antmicro")
    (property "Dielectric" "X5R")
    (property "License" "Apache-2.0")
    (property "MPN" "GRM155R61H104KE14D")
    (property "Manufacturer" "Murata")
    (property "Sheetfile" "psu.kicad_sch")
    (property "Sheetname" "PSU")
    (property "Val" "100n")
    (property "Voltage" "50V")
    (attr smd)
    (fp_text reference "C125" (at 1.71 3.35 180) (layer "B.SilkS")
      (effects (font (size 0.7 0.7) (thickness 0.15)) (justify left bottom mirror))
    )
    (fp_text value "C_100n_0402" (at 0 -1.4 180) (layer "B.Fab")
      (effects (font (size 0.7 0.7) (thickness 0.15)) (justify left bottom mirror))
    )
    (fp_text user "Author: Antmicro" (at -0.932 -4.17 180) (layer "B.Fab") hide
      (effects (font (size 0.7 0.7) (thickness 0.15)) (justify left bottom mirror))
    )
    (fp_text user "License: Apache-2.0" (at -0.932 -5.17 180) (layer "B.Fab") hide
      (effects (font (size 0.7 0.7) (thickness 0.15)) (justify left bottom mirror))
    )
    (fp_text user "${REFERENCE}" (at -0.932 -3.168 180) (layer "B.Fab") hide
      (effects (font (size 0.7 0.7) (thickness 0.15)) (justify left bottom mirror))
    )
    (fp_rect (start -0.94 0.47) (end 0.94 -0.47) (layer "B.CrtYd") (width 0.05) (fill none))
    (fp_rect (start -0.499 0.249) (end 0.499 -0.249) (layer "B.Fab") (width 0.15) (fill none))
    (pad "1" smd roundrect (at -0.484 0) (size 0.59 0.64) (layers "B.Cu" "B.Paste" "B.Mask") (roundrect_rratio 0.25)
      (net 367 "/PSU/G3") (pintype "passive"))
    (pad "2" smd roundrect (at 0.484 0) (size 0.59 0.64) (layers "B.Cu" "B.Paste" "B.Mask") (roundrect_rratio 0.25)
      (net 1 "GND") (pintype "passive"))
  )

  (footprint "sa800u-baseboard-hw-footprints:D_SOD-323F" (layer "B.Cu")
    (tedit 60F16F6B)
    (at 137.17 148.425 180)
    (property "Author" "Antmicro")
    (property "License" "Apache-2.0")
    (property "MPN" "1N4148WS")
    (property "Manufacturer" "ON Semiconductor")
    (property "Sheetfile" "hdmi-converter.kicad_sch")
    (property "Sheetname" "HDMI converter")
    (attr smd)
    (fp_text reference "D1" (at -0.62 -1.725) (layer "B.SilkS")
      (effects (font (size 0.7 0.7) (thickness 0.15)) (justify left bottom mirror))
    )
    (fp_text value "1N4148WS" (at -1.7 -1.9) (layer "B.Fab")
      (effects (font (size 0.7 0.7) (thickness 0.15)) (justify left bottom mirror))
    )
    (fp_text user "License: Apache-2.0" (at -1.8 -5.8) (layer "B.Fab") hide
      (effects (font (size 0.7 0.7) (thickness 0.15)) (justify left bottom mirror))
    )
    (fp_text user "${REFERENCE}" (at -1.8 -3.2) (layer "B.Fab") hide
      (effects (font (size 0.7 0.7) (thickness 0.15)) (justify left bottom mirror))
    )
    (fp_text user "Author: Antmicro" (at -1.8 -4.46) (layer "B.Fab") hide
      (effects (font (size 0.7 0.7) (thickness 0.15)) (justify left bottom mirror))
    )
    (fp_line (start 0.623 0.75) (end 0.973 0.75) (layer "B.SilkS") (width 0.15))
    (fp_line (start -0.5 0.426) (end -0.5 -0.424) (layer "B.SilkS") (width 0.15))
    (fp_line (start -0.625 0.75) (end -0.975 0.75) (layer "B.SilkS") (width 0.15))
    (fp_line (start -0.975 -0.748) (end -0.975 -0.45) (layer "B.SilkS") (width 0.15))
    (fp_line (start -0.975 0.75) (end -0.975 0.45) (layer "B.SilkS") (width 0.15))
    (fp_line (start 0.973 0.75) (end 0.973 0.45) (layer "B.SilkS") (width 0.15))
    (fp_line (start 0.973 -0.45) (end 0.973 -0.748) (layer "B.SilkS") (width 0.15))
    (fp_line (start -0.625 -0.748) (end -0.975 -0.748) (layer "B.SilkS") (width 0.15))
    (fp_line (start 0.973 -0.748) (end 0.623 -0.748) (layer "B.SilkS") (width 0.15))
    (fp_rect (start -1.6 0.827) (end 1.599 -0.825) (layer "B.CrtYd") (width 0.05) (fill none))
    (fp_line (start 0.848 0.625) (end 0.848 -0.623) (layer "B.Fab") (width 0.15))
    (fp_line (start -0.85 0.625) (end 0.848 0.625) (layer "B.Fab") (width 0.15))
    (fp_line (start -0.85 -0.623) (end -0.85 0.625) (layer "B.Fab") (width 0.15))
    (fp_line (start -0.85 -0.623) (end 0.848 -0.623) (layer "B.Fab") (width 0.15))
    (pad "A" smd roundrect (at 1.05 0 180) (size 0.8 0.6) (layers "B.Cu" "B.Paste" "B.Mask") (roundrect_rratio 0.15)
      (net 131 "3V3_SYS") (pinfunction "A") (pintype "passive"))
    (pad "K" smd roundrect (at -1.051 0 180) (size 0.8 0.6) (layers "B.Cu" "B.Paste" "B.Mask") (roundrect_rratio 0.15)
      (net 366 "Net-(D1-PadK)") (pinfunction "K") (pintype "passive"))
  )

  (footprint "sa800u-baseboard-hw-footprints:R_0402_1005Metric" (layer "B.Cu")
    (tedit 5FD9C158)
    (at 139.25 147.5 90)
    (descr "Resistor SMD 0402")
    (tags "resistor SMD 0402")
    (property "Author" "Antmicro")
    (property "License" "Apache-2.0")
    (property "MPN" "CR0402-FX-2702GLF")
    (property "Manufacturer" "Bourns")
    (property "Sheetfile" "hdmi-converter.kicad_sch")
    (property "Sheetname" "HDMI converter")
    (property "Tolerance" "1%")
    (property "Val" "27k")
    (attr smd)
    (fp_text reference "R33" (at -0.8 0.45 270) (layer "B.SilkS")
      (effects (font (size 0.7 0.7) (thickness 0.15)) (justify left bottom mirror))
    )
    (fp_text value "R_27k_0402" (at 0 -1.4 270) (layer "B.Fab")
      (effects (font (size 0.7 0.7) (thickness 0.15)) (justify left bottom mirror))
    )
    (fp_text user "License: Apache-2.0" (at -0.95 -5.169 270) (layer "B.Fab") hide
      (effects (font (size 0.7 0.7) (thickness 0.15)) (justify left bottom mirror))
    )
    (fp_text user "Author: Antmicro" (at -0.95 -4.169 270) (layer "B.Fab") hide
      (effects (font (size 0.7 0.7) (thickness 0.15)) (justify left bottom mirror))
    )
    (fp_text user "${REFERENCE}" (at -0.95 -3.168 270) (layer "B.Fab") hide
      (effects (font (size 0.7 0.7) (thickness 0.15)) (justify left bottom mirror))
    )
    (fp_rect (start -0.93 0.47) (end 0.93 -0.47) (layer "B.CrtYd") (width 0.05) (fill none))
    (fp_rect (start -0.5 0.25) (end 0.5 -0.25) (layer "B.Fab") (width 0.15) (fill none))
    (pad "1" smd roundrect (at -0.485 0 90) (size 0.59 0.64) (layers "B.Cu" "B.Paste" "B.Mask") (roundrect_rratio 0.25)
      (net 366 "Net-(D1-PadK)") (pintype "passive"))
    (pad "2" smd roundrect (at 0.485 0 90) (size 0.59 0.64) (layers "B.Cu" "B.Paste" "B.Mask") (roundrect_rratio 0.25)
      (net 233 "/HDMI converter/HDMI_CEC") (pintype "passive"))
  )

  (footprint "sa800u-baseboard-hw-footprints:R_0402_1005Metric" (layer "B.Cu")
    (tedit 5FD9C158)
    (at 139.25 145.55 90)
    (descr "Resistor SMD 0402")
    (tags "resistor SMD 0402")
    (property "Author" "Antmicro")
    (property "Current" "1A")
    (property "DNP" "DNP")
    (property "License" "Apache-2.0")
    (property "MPN" "ERJ2GE0R00X")
    (property "Manufacturer" "Panasonic")
    (property "Sheetfile" "hdmi-converter.kicad_sch")
    (property "Sheetname" "HDMI converter")
    (property "Tolerance" "")
    (property "Val" "0R")
    (attr exclude_from_pos_files)
    (fp_text reference "R31" (at 3.01 0.44 270) (layer "B.SilkS")
      (effects (font (size 0.7 0.7) (thickness 0.15)) (justify left bottom mirror))
    )
    (fp_text value "R_0R_0402" (at 0 -1.4 270) (layer "B.Fab")
      (effects (font (size 0.7 0.7) (thickness 0.15)) (justify left bottom mirror))
    )
    (fp_text user "License: Apache-2.0" (at -0.95 -5.169 270) (layer "B.Fab") hide
      (effects (font (size 0.7 0.7) (thickness 0.15)) (justify left bottom mirror))
    )
    (fp_text user "Author: Antmicro" (at -0.95 -4.169 270) (layer "B.Fab") hide
      (effects (font (size 0.7 0.7) (thickness 0.15)) (justify left bottom mirror))
    )
    (fp_text user "${REFERENCE}" (at -0.95 -3.168 270) (layer "B.Fab") hide
      (effects (font (size 0.7 0.7) (thickness 0.15)) (justify left bottom mirror))
    )
    (fp_rect (start -0.93 0.47) (end 0.93 -0.47) (layer "B.CrtYd") (width 0.05) (fill none))
    (fp_rect (start -0.5 0.25) (end 0.5 -0.25) (layer "B.Fab") (width 0.15) (fill none))
    (pad "1" smd roundrect (at -0.485 0 90) (size 0.59 0.64) (layers "B.Cu" "B.Paste" "B.Mask") (roundrect_rratio 0.25)
      (net 233 "/HDMI converter/HDMI_CEC") (pintype "passive"))
    (pad "2" smd roundrect (at 0.485 0 90) (size 0.59 0.64) (layers "B.Cu" "B.Paste" "B.Mask") (roundrect_rratio 0.25)
      (net 285 "/HDMI converter/LT9611_CEC") (pintype "passive"))
  )

  (footprint "sa800u-baseboard-hw-footprints:R_0402_1005Metric" (layer "B.Cu")
    (tedit 5FD9C158)
    (at 135.65 145.55 90)
    (descr "Resistor SMD 0402")
    (tags "resistor SMD 0402")
    (property "Author" "Antmicro")
    (property "License" "Apache-2.0")
    (property "MPN" "CR0402-FX-1002GLF")
    (property "Manufacturer" "Bourns")
    (property "Sheetfile" "hdmi-converter.kicad_sch")
    (property "Sheetname" "HDMI converter")
    (property "Tolerance" "1%")
    (property "Val" "10k")
    (attr smd)
    (fp_text reference "R29" (at 3.05 0.41 270) (layer "B.SilkS")
      (effects (font (size 0.7 0.7) (thickness 0.15)) (justify left bottom mirror))
    )
    (fp_text value "R_10k_0402" (at 0 -1.4 270) (layer "B.Fab")
      (effects (font (size 0.7 0.7) (thickness 0.15)) (justify left bottom mirror))
    )
    (fp_text user "Author: Antmicro" (at -0.95 -4.169 270) (layer "B.Fab") hide
      (effects (font (size 0.7 0.7) (thickness 0.15)) (justify left bottom mirror))
    )
    (fp_text user "${REFERENCE}" (at -0.95 -3.168 270) (layer "B.Fab") hide
      (effects (font (size 0.7 0.7) (thickness 0.15)) (justify left bottom mirror))
    )
    (fp_text user "License: Apache-2.0" (at -0.95 -5.169 270) (layer "B.Fab") hide
      (effects (font (size 0.7 0.7) (thickness 0.15)) (justify left bottom mirror))
    )
    (fp_rect (start -0.93 0.47) (end 0.93 -0.47) (layer "B.CrtYd") (width 0.05) (fill none))
    (fp_rect (start -0.5 0.25) (end 0.5 -0.25) (layer "B.Fab") (width 0.15) (fill none))
    (pad "1" smd roundrect (at -0.485 0 90) (size 0.59 0.64) (layers "B.Cu" "B.Paste" "B.Mask") (roundrect_rratio 0.25)
      (net 131 "3V3_SYS") (pintype "passive"))
    (pad "2" smd roundrect (at 0.485 0 90) (size 0.59 0.64) (layers "B.Cu" "B.Paste" "B.Mask") (roundrect_rratio 0.25)
      (net 154 "Net-(Q3-Pad1)") (pintype "passive"))
  )

  (footprint "sa800u-baseboard-hw-footprints:SC70-3" (layer "B.Cu")
    (tedit 615FF353)
    (at 137.45 146.05 -90)
    (property "Author" "Antmicro")
    (property "License" "Apache-2.0")
    (property "MPN" "BSS138PW")
    (property "Manufacturer" "Nexperia")
    (property "Sheetfile" "hdmi-converter.kicad_sch")
    (property "Sheetname" "HDMI converter")
    (attr smd)
    (fp_text reference "Q3" (at -1.56 -0.84 180) (layer "B.SilkS")
      (effects (font (size 0.7 0.7) (thickness 0.15)) (justify left bottom mirror))
    )
    (fp_text value "BSS138PW" (at 0 -2.3 90) (layer "B.Fab")
      (effects (font (size 0.7 0.7) (thickness 0.15)) (justify left bottom mirror))
    )
    (fp_text user "Author: Antmicro" (at -1.45 -5.782 90) (layer "B.Fab") hide
      (effects (font (size 0.7 0.7) (thickness 0.15)) (justify left bottom mirror))
    )
    (fp_text user "License: Apache-2.0" (at -1.45 -6.782 90) (layer "B.Fab") hide
      (effects (font (size 0.7 0.7) (thickness 0.15)) (justify left bottom mirror))
    )
    (fp_text user "${REFERENCE}" (at -1.45 -4.783 90) (layer "B.Fab") hide
      (effects (font (size 0.7 0.7) (thickness 0.15)) (justify left bottom mirror))
    )
    (fp_line (start 0.627 -0.6) (end 0.627 -1.001) (layer "B.SilkS") (width 0.15))
    (fp_line (start 0.627 0.6) (end 0.627 0.999) (layer "B.SilkS") (width 0.15))
    (fp_line (start -0.3 1) (end 0.627 0.999) (layer "B.SilkS") (width 0.15))
    (fp_line (start -0.3 -1) (end 0.627 -1.001) (layer "B.SilkS") (width 0.15))
    (fp_line (start 0.9 -0.4) (end 0.9 -1.3) (layer "B.CrtYd") (width 0.05))
    (fp_line (start 0.9 -1.3) (end -0.9 -1.3) (layer "B.CrtYd") (width 0.05))
    (fp_line (start -0.9 1) (end -1.4 1) (layer "B.CrtYd") (width 0.05))
    (fp_line (start -0.9 -1) (end -1.4 -1) (layer "B.CrtYd") (width 0.05))
    (fp_line (start 0.9 1.3) (end 0.9 0.4) (layer "B.CrtYd") (width 0.05))
    (fp_line (start -0.9 1.3) (end -0.9 1) (layer "B.CrtYd") (width 0.05))
    (fp_line (start -0.9 1.3) (end 0.9 1.3) (layer "B.CrtYd") (width 0.05))
    (fp_line (start 1.4 0.4) (end 1.4 -0.4) (layer "B.CrtYd") (width 0.05))
    (fp_line (start 0.9 0.4) (end 1.4 0.4) (layer "B.CrtYd") (width 0.05))
    (fp_line (start -1.4 -1) (end -1.4 1) (layer "B.CrtYd") (width 0.05))
    (fp_line (start -0.9 -1.3) (end -0.9 -1) (layer "B.CrtYd") (width 0.05))
    (fp_line (start 1.4 -0.4) (end 0.9 -0.4) (layer "B.CrtYd") (width 0.05))
    (fp_rect (start -0.623 0.999) (end 0.627 -1.001) (layer "B.Fab") (width 0.15) (fill none))
    (pad "1" smd rect (at -1.051 0.65 180) (size 0.6 0.6) (layers "B.Cu" "B.Paste" "B.Mask")
      (net 154 "Net-(Q3-Pad1)") (pinfunction "G") (pintype "bidirectional"))
    (pad "2" smd rect (at -1.051 -0.65 180) (size 0.6 0.6) (layers "B.Cu" "B.Paste" "B.Mask")
      (net 285 "/HDMI converter/LT9611_CEC") (pinfunction "S") (pintype "bidirectional"))
    (pad "3" smd rect (at 1.05 0 180) (size 0.6 0.6) (layers "B.Cu" "B.Paste" "B.Mask")
      (net 233 "/HDMI converter/HDMI_CEC") (pinfunction "D") (pintype "bidirectional"))
  )

  (footprint "sa800u-baseboard-hw-footprints:TP_SMD_0.75mm" (layer "B.Cu")
    (tedit 5E4A9375)
    (at 124.4 130.5)
    (property "Author" "Antmicro")
    (property "License" "Apache-2.0")
    (property "MPN" "")
    (property "Manufacturer" "")
    (property "Sheetfile" "usb-c-interface.kicad_sch")
    (property "Sheetname" "USB-C Interface ")
    (attr smd)
    (fp_text reference "TP99" (at -0.31 0.4 180) (layer "B.SilkS")
      (effects (font (size 0.7 0.7) (thickness 0.15)) (justify left bottom mirror))
    )
    (fp_text value "TP_0.75mm_SMD" (at 0 -1.2 180) (layer "B.Fab")
      (effects (font (size 0.7 0.7) (thickness 0.15)) (justify left bottom mirror))
    )
    (fp_text user "License: Apache-2.0" (at -0.4 -5.101 180) (layer "B.Fab") hide
      (effects (font (size 0.7 0.7) (thickness 0.15)) (justify left bottom mirror))
    )
    (fp_text user "${REFERENCE}" (at -0.4 -2.7 180) (layer "B.Fab") hide
      (effects (font (size 0.7 0.7) (thickness 0.15)) (justify left bottom mirror))
    )
    (fp_text user "Author: Antmicro" (at -0.4 -3.901 180) (layer "B.Fab") hide
      (effects (font (size 0.7 0.7) (thickness 0.15)) (justify left bottom mirror))
    )
    (pad "1" smd circle (at 0 0) (size 0.75 0.75) (layers "B.Cu" "B.Mask")
      (net 130 "DBG_TXD") (pinfunction "1") (pintype "passive"))
  )

  (footprint "sa800u-baseboard-hw-footprints:TP_SMD_0.75mm" (layer "B.Cu")
    (tedit 5E4A9375)
    (at 126.4 132.8 180)
    (property "Author" "Antmicro")
    (property "License" "Apache-2.0")
    (property "MPN" "")
    (property "Manufacturer" "")
    (property "Sheetfile" "usb-c-interface.kicad_sch")
    (property "Sheetname" "USB-C Interface ")
    (attr smd)
    (fp_text reference "TP101" (at -3.75 -0.35) (layer "B.SilkS")
      (effects (font (size 0.7 0.7) (thickness 0.15)) (justify left bottom mirror))
    )
    (fp_text value "TP_0.75mm_SMD" (at 0 -1.2) (layer "B.Fab")
      (effects (font (size 0.7 0.7) (thickness 0.15)) (justify left bottom mirror))
    )
    (fp_text user "License: Apache-2.0" (at -0.4 -5.101) (layer "B.Fab") hide
      (effects (font (size 0.7 0.7) (thickness 0.15)) (justify left bottom mirror))
    )
    (fp_text user "${REFERENCE}" (at -0.4 -2.7) (layer "B.Fab") hide
      (effects (font (size 0.7 0.7) (thickness 0.15)) (justify left bottom mirror))
    )
    (fp_text user "Author: Antmicro" (at -0.4 -3.901) (layer "B.Fab") hide
      (effects (font (size 0.7 0.7) (thickness 0.15)) (justify left bottom mirror))
    )
    (pad "1" smd circle (at 0 0 180) (size 0.75 0.75) (layers "B.Cu" "B.Mask")
      (net 127 "1V8_DBG") (pinfunction "1") (pintype "passive"))
  )

  (footprint "sa800u-baseboard-hw-footprints:TP_SMD_0.75mm" (layer "B.Cu")
    (tedit 5E4A9375)
    (at 108.8 147.6 90)
    (property "Author" "Antmicro")
    (property "License" "Apache-2.0")
    (property "MPN" "")
    (property "Manufacturer" "")
    (property "Sheetfile" "usb-c-interface.kicad_sch")
    (property "Sheetname" "USB-C Interface ")
    (attr smd)
    (fp_text reference "TP102" (at -0.33 -0.03 270) (layer "B.SilkS")
      (effects (font (size 0.7 0.7) (thickness 0.15)) (justify left bottom mirror))
    )
    (fp_text value "TP_0.75mm_SMD" (at 0 -1.2 270) (layer "B.Fab")
      (effects (font (size 0.7 0.7) (thickness 0.15)) (justify left bottom mirror))
    )
    (fp_text user "${REFERENCE}" (at -0.4 -2.7 270) (layer "B.Fab") hide
      (effects (font (size 0.7 0.7) (thickness 0.15)) (justify left bottom mirror))
    )
    (fp_text user "Author: Antmicro" (at -0.4 -3.901 270) (layer "B.Fab") hide
      (effects (font (size 0.7 0.7) (thickness 0.15)) (justify left bottom mirror))
    )
    (fp_text user "License: Apache-2.0" (at -0.4 -5.101 270) (layer "B.Fab") hide
      (effects (font (size 0.7 0.7) (thickness 0.15)) (justify left bottom mirror))
    )
    (pad "1" smd circle (at 0 0 90) (size 0.75 0.75) (layers "B.Cu" "B.Mask")
      (net 301 "/USB-C Interface /USB2_EN_5V") (pinfunction "1") (pintype "passive"))
  )

  (footprint "sa800u-baseboard-hw-footprints:TP_SMD_0.75mm" (layer "B.Cu")
    (tedit 5E4A9375)
    (at 93.6 144.6)
    (property "Author" "Antmicro")
    (property "License" "Apache-2.0")
    (property "MPN" "")
    (property "Manufacturer" "")
    (property "Sheetfile" "usb-c-interface.kicad_sch")
    (property "Sheetname" "USB-C Interface ")
    (attr smd)
    (fp_text reference "TP103" (at 0.63 -3.72 90) (layer "B.SilkS")
      (effects (font (size 0.7 0.7) (thickness 0.15)) (justify left bottom mirror))
    )
    (fp_text value "TP_0.75mm_SMD" (at 0 -1.2 180) (layer "B.Fab")
      (effects (font (size 0.7 0.7) (thickness 0.15)) (justify left bottom mirror))
    )
    (fp_text user "${REFERENCE}" (at -0.4 -2.7 180) (layer "B.Fab") hide
      (effects (font (size 0.7 0.7) (thickness 0.15)) (justify left bottom mirror))
    )
    (fp_text user "Author: Antmicro" (at -0.4 -3.901 180) (layer "B.Fab") hide
      (effects (font (size 0.7 0.7) (thickness 0.15)) (justify left bottom mirror))
    )
    (fp_text user "License: Apache-2.0" (at -0.4 -5.101 180) (layer "B.Fab") hide
      (effects (font (size 0.7 0.7) (thickness 0.15)) (justify left bottom mirror))
    )
    (pad "1" smd circle (at 0 0) (size 0.75 0.75) (layers "B.Cu" "B.Mask")
      (net 93 "SBU_SW_OE") (pinfunction "1") (pintype "passive"))
  )

  (footprint "sa800u-baseboard-hw-footprints:TP_SMD_0.75mm" (layer "B.Cu")
    (tedit 5E4A9375)
    (at 96.4 144.6)
    (property "Author" "Antmicro")
    (property "License" "Apache-2.0")
    (property "MPN" "")
    (property "Manufacturer" "")
    (property "Sheetfile" "usb-c-interface.kicad_sch")
    (property "Sheetname" "USB-C Interface ")
    (attr smd)
    (fp_text reference "TP104" (at 0.85 -3.67 270) (layer "B.SilkS")
      (effects (font (size 0.7 0.7) (thickness 0.15)) (justify left bottom mirror))
    )
    (fp_text value "TP_0.75mm_SMD" (at 0 -1.2 180) (layer "B.Fab")
      (effects (font (size 0.7 0.7) (thickness 0.15)) (justify left bottom mirror))
    )
    (fp_text user "License: Apache-2.0" (at -0.4 -5.101 180) (layer "B.Fab") hide
      (effects (font (size 0.7 0.7) (thickness 0.15)) (justify left bottom mirror))
    )
    (fp_text user "${REFERENCE}" (at -0.4 -2.7 180) (layer "B.Fab") hide
      (effects (font (size 0.7 0.7) (thickness 0.15)) (justify left bottom mirror))
    )
    (fp_text user "Author: Antmicro" (at -0.4 -3.901 180) (layer "B.Fab") hide
      (effects (font (size 0.7 0.7) (thickness 0.15)) (justify left bottom mirror))
    )
    (pad "1" smd circle (at 0 0) (size 0.75 0.75) (layers "B.Cu" "B.Mask")
      (net 98 "SBU_SW_SEL") (pinfunction "1") (pintype "passive"))
  )

  (footprint "sa800u-baseboard-hw-footprints:TP_SMD_0.75mm" (layer "B.Cu")
    (tedit 5E4A9375)
    (at 108.3 135.9 -90)
    (property "Author" "Antmicro")
    (property "License" "Apache-2.0")
    (property "MPN" "")
    (property "Manufacturer" "")
    (property "Sheetfile" "usb-c-interface.kicad_sch")
    (property "Sheetname" "USB-C Interface ")
    (attr smd)
    (fp_text reference "TP105" (at -3.71 -0.37 90) (layer "B.SilkS")
      (effects (font (size 0.7 0.7) (thickness 0.15)) (justify left bottom mirror))
    )
    (fp_text value "TP_0.75mm_SMD" (at 0 -1.2 90) (layer "B.Fab")
      (effects (font (size 0.7 0.7) (thickness 0.15)) (justify left bottom mirror))
    )
    (fp_text user "Author: Antmicro" (at -0.4 -3.901 90) (layer "B.Fab") hide
      (effects (font (size 0.7 0.7) (thickness 0.15)) (justify left bottom mirror))
    )
    (fp_text user "License: Apache-2.0" (at -0.4 -5.101 90) (layer "B.Fab") hide
      (effects (font (size 0.7 0.7) (thickness 0.15)) (justify left bottom mirror))
    )
    (fp_text user "${REFERENCE}" (at -0.4 -2.7 90) (layer "B.Fab") hide
      (effects (font (size 0.7 0.7) (thickness 0.15)) (justify left bottom mirror))
    )
    (pad "1" smd circle (at 0 0 270) (size 0.75 0.75) (layers "B.Cu" "B.Mask")
      (net 99 "USB2_SINK") (pinfunction "1") (pintype "passive"))
  )

  (footprint "sa800u-baseboard-hw-footprints:TP_SMD_0.75mm" (layer "B.Cu")
    (tedit 5E4A9375)
    (at 107.1 135.9 -90)
    (property "Author" "Antmicro")
    (property "License" "Apache-2.0")
    (property "MPN" "")
    (property "Manufacturer" "")
    (property "Sheetfile" "usb-c-interface.kicad_sch")
    (property "Sheetname" "USB-C Interface ")
    (attr smd)
    (fp_text reference "TP106" (at -3.71 -0.37 90) (layer "B.SilkS")
      (effects (font (size 0.7 0.7) (thickness 0.15)) (justify left bottom mirror))
    )
    (fp_text value "TP_0.75mm_SMD" (at 0 -1.2 90) (layer "B.Fab")
      (effects (font (size 0.7 0.7) (thickness 0.15)) (justify left bottom mirror))
    )
    (fp_text user "Author: Antmicro" (at -0.4 -3.901 90) (layer "B.Fab") hide
      (effects (font (size 0.7 0.7) (thickness 0.15)) (justify left bottom mirror))
    )
    (fp_text user "License: Apache-2.0" (at -0.4 -5.101 90) (layer "B.Fab") hide
      (effects (font (size 0.7 0.7) (thickness 0.15)) (justify left bottom mirror))
    )
    (fp_text user "${REFERENCE}" (at -0.4 -2.7 90) (layer "B.Fab") hide
      (effects (font (size 0.7 0.7) (thickness 0.15)) (justify left bottom mirror))
    )
    (pad "1" smd circle (at 0 0 270) (size 0.75 0.75) (layers "B.Cu" "B.Mask")
      (net 100 "USB2_FAULT") (pinfunction "1") (pintype "passive"))
  )

  (footprint "sa800u-baseboard-hw-footprints:TP_SMD_0.75mm" (layer "B.Cu")
    (tedit 5E4A9375)
    (at 109.5 135.9 -90)
    (property "Author" "Antmicro")
    (property "License" "Apache-2.0")
    (property "MPN" "")
    (property "Manufacturer" "")
    (property "Sheetfile" "usb-c-interface.kicad_sch")
    (property "Sheetname" "USB-C Interface ")
    (attr smd)
    (fp_text reference "TP107" (at -3.71 -0.37 90) (layer "B.SilkS")
      (effects (font (size 0.7 0.7) (thickness 0.15)) (justify left bottom mirror))
    )
    (fp_text value "TP_0.75mm_SMD" (at 0 -1.2 90) (layer "B.Fab")
      (effects (font (size 0.7 0.7) (thickness 0.15)) (justify left bottom mirror))
    )
    (fp_text user "Author: Antmicro" (at -0.4 -3.901 90) (layer "B.Fab") hide
      (effects (font (size 0.7 0.7) (thickness 0.15)) (justify left bottom mirror))
    )
    (fp_text user "${REFERENCE}" (at -0.4 -2.7 90) (layer "B.Fab") hide
      (effects (font (size 0.7 0.7) (thickness 0.15)) (justify left bottom mirror))
    )
    (fp_text user "License: Apache-2.0" (at -0.4 -5.101 90) (layer "B.Fab") hide
      (effects (font (size 0.7 0.7) (thickness 0.15)) (justify left bottom mirror))
    )
    (pad "1" smd circle (at 0 0 270) (size 0.75 0.75) (layers "B.Cu" "B.Mask")
      (net 101 "USB2_EN") (pinfunction "1") (pintype "passive"))
  )

  (footprint "sa800u-baseboard-hw-footprints:TP_SMD_0.75mm" (layer "B.Cu")
    (tedit 5E4A9375)
    (at 110 147.6 90)
    (property "Author" "Antmicro")
    (property "License" "Apache-2.0")
    (property "MPN" "")
    (property "Manufacturer" "")
    (property "Sheetfile" "usb-c-interface.kicad_sch")
    (property "Sheetname" "USB-C Interface ")
    (attr smd)
    (fp_text reference "TP108" (at -0.33 -0.3 270) (layer "B.SilkS")
      (effects (font (size 0.7 0.7) (thickness 0.15)) (justify left bottom mirror))
    )
    (fp_text value "TP_0.75mm_SMD" (at 0 -1.2 270) (layer "B.Fab")
      (effects (font (size 0.7 0.7) (thickness 0.15)) (justify left bottom mirror))
    )
    (fp_text user "License: Apache-2.0" (at -0.4 -5.101 270) (layer "B.Fab") hide
      (effects (font (size 0.7 0.7) (thickness 0.15)) (justify left bottom mirror))
    )
    (fp_text user "Author: Antmicro" (at -0.4 -3.901 270) (layer "B.Fab") hide
      (effects (font (size 0.7 0.7) (thickness 0.15)) (justify left bottom mirror))
    )
    (fp_text user "${REFERENCE}" (at -0.4 -2.7 270) (layer "B.Fab") hide
      (effects (font (size 0.7 0.7) (thickness 0.15)) (justify left bottom mirror))
    )
    (pad "1" smd circle (at 0 0 90) (size 0.75 0.75) (layers "B.Cu" "B.Mask")
      (net 292 "/USB-C Interface /USB2_FAULT_5V") (pinfunction "1") (pintype "passive"))
  )

  (footprint "sa800u-baseboard-hw-footprints:TP_SMD_0.75mm" (layer "B.Cu")
    (tedit 5E4A9375)
    (at 111.2 147.6 90)
    (property "Author" "Antmicro")
    (property "License" "Apache-2.0")
    (property "MPN" "")
    (property "Manufacturer" "")
    (property "Sheetfile" "usb-c-interface.kicad_sch")
    (property "Sheetname" "USB-C Interface ")
    (attr smd)
    (fp_text reference "TP109" (at -0.32 -0.6 270) (layer "B.SilkS")
      (effects (font (size 0.7 0.7) (thickness 0.15)) (justify left bottom mirror))
    )
    (fp_text value "TP_0.75mm_SMD" (at 0 -1.2 270) (layer "B.Fab")
      (effects (font (size 0.7 0.7) (thickness 0.15)) (justify left bottom mirror))
    )
    (fp_text user "Author: Antmicro" (at -0.4 -3.901 270) (layer "B.Fab") hide
      (effects (font (size 0.7 0.7) (thickness 0.15)) (justify left bottom mirror))
    )
    (fp_text user "License: Apache-2.0" (at -0.4 -5.101 270) (layer "B.Fab") hide
      (effects (font (size 0.7 0.7) (thickness 0.15)) (justify left bottom mirror))
    )
    (fp_text user "${REFERENCE}" (at -0.4 -2.7 270) (layer "B.Fab") hide
      (effects (font (size 0.7 0.7) (thickness 0.15)) (justify left bottom mirror))
    )
    (pad "1" smd circle (at 0 0 90) (size 0.75 0.75) (layers "B.Cu" "B.Mask")
      (net 291 "/USB-C Interface /USB2_SINK_5V") (pinfunction "1") (pintype "passive"))
  )

  (footprint "sa800u-baseboard-hw-footprints:TP_SMD_0.75mm" (layer "B.Cu")
    (tedit 5E4A9375)
    (at 112 142.5492)
    (property "Author" "Antmicro")
    (property "License" "Apache-2.0")
    (property "MPN" "")
    (property "Manufacturer" "")
    (property "Sheetfile" "usb-c-interface.kicad_sch")
    (property "Sheetname" "USB-C Interface ")
    (attr smd)
    (fp_text reference "TP110" (at 3.72 0.4308 180) (layer "B.SilkS")
      (effects (font (size 0.7 0.7) (thickness 0.15)) (justify left bottom mirror))
    )
    (fp_text value "TP_0.75mm_SMD" (at 0 -1.2 180) (layer "B.Fab")
      (effects (font (size 0.7 0.7) (thickness 0.15)) (justify left bottom mirror))
    )
    (fp_text user "License: Apache-2.0" (at -0.4 -5.101 180) (layer "B.Fab") hide
      (effects (font (size 0.7 0.7) (thickness 0.15)) (justify left bottom mirror))
    )
    (fp_text user "${REFERENCE}" (at -0.4 -2.7 180) (layer "B.Fab") hide
      (effects (font (size 0.7 0.7) (thickness 0.15)) (justify left bottom mirror))
    )
    (fp_text user "Author: Antmicro" (at -0.4 -3.901 180) (layer "B.Fab") hide
      (effects (font (size 0.7 0.7) (thickness 0.15)) (justify left bottom mirror))
    )
    (pad "1" smd circle (at 0 0) (size 0.75 0.75) (layers "B.Cu" "B.Mask")
      (net 290 "/USB-C Interface /USB2_CC_SELECT") (pinfunction "1") (pintype "passive"))
  )

  (footprint "sa800u-baseboard-hw-footprints:TP_SMD_0.75mm" (layer "B.Cu")
    (tedit 5E4A9375)
    (at 123.8 140.5492)
    (property "Author" "Antmicro")
    (property "License" "Apache-2.0")
    (property "MPN" "")
    (property "Manufacturer" "")
    (property "Sheetfile" "usb-c-interface.kicad_sch")
    (property "Sheetname" "USB-C Interface ")
    (attr smd)
    (fp_text reference "TP111" (at 1.21 -0.4392 180) (layer "B.SilkS")
      (effects (font (size 0.7 0.7) (thickness 0.15)) (justify left bottom mirror))
    )
    (fp_text value "TP_0.75mm_SMD" (at 0 -1.2 180) (layer "B.Fab")
      (effects (font (size 0.7 0.7) (thickness 0.15)) (justify left bottom mirror))
    )
    (fp_text user "License: Apache-2.0" (at -0.4 -5.101 180) (layer "B.Fab") hide
      (effects (font (size 0.7 0.7) (thickness 0.15)) (justify left bottom mirror))
    )
    (fp_text user "Author: Antmicro" (at -0.4 -3.901 180) (layer "B.Fab") hide
      (effects (font (size 0.7 0.7) (thickness 0.15)) (justify left bottom mirror))
    )
    (fp_text user "${REFERENCE}" (at -0.4 -2.7 180) (layer "B.Fab") hide
      (effects (font (size 0.7 0.7) (thickness 0.15)) (justify left bottom mirror))
    )
    (pad "1" smd circle (at 0 0) (size 0.75 0.75) (layers "B.Cu" "B.Mask")
      (net 228 "/USB-C Interface /5V0_DBG") (pinfunction "1") (pintype "passive"))
  )

  (footprint "sa800u-baseboard-hw-footprints:R_0402_1005Metric" (layer "B.Cu")
    (tedit 5FD9C158)
    (at 61.9 113.8 180)
    (descr "Resistor SMD 0402")
    (tags "resistor SMD 0402")
    (property "Author" "Antmicro")
    (property "License" "Apache-2.0")
    (property "MPN" "CR0402-FX-2492GLF")
    (property "Manufacturer" "Bourns")
    (property "Sheetfile" "poe.kicad_sch")
    (property "Sheetname" "PoE")
    (property "Tolerance" "1%")
    (property "Val" "24k9")
    (attr smd)
    (fp_text reference "R143" (at -3.76 -0.3) (layer "B.SilkS")
      (effects (font (size 0.7 0.7) (thickness 0.15)) (justify left bottom mirror))
    )
    (fp_text value "R_24k9_0402" (at 0 -1.4) (layer "B.Fab")
      (effects (font (size 0.7 0.7) (thickness 0.15)) (justify left bottom mirror))
    )
    (fp_text user "License: Apache-2.0" (at -0.95 -5.169) (layer "B.Fab") hide
      (effects (font (size 0.7 0.7) (thickness 0.15)) (justify left bottom mirror))
    )
    (fp_text user "${REFERENCE}" (at -0.95 -3.168) (layer "B.Fab") hide
      (effects (font (size 0.7 0.7) (thickness 0.15)) (justify left bottom mirror))
    )
    (fp_text user "Author: Antmicro" (at -0.95 -4.169) (layer "B.Fab") hide
      (effects (font (size 0.7 0.7) (thickness 0.15)) (justify left bottom mirror))
    )
    (fp_rect (start -0.93 0.47) (end 0.93 -0.47) (layer "B.CrtYd") (width 0.05) (fill none))
    (fp_rect (start -0.5 0.25) (end 0.5 -0.25) (layer "B.Fab") (width 0.15) (fill none))
    (pad "1" smd roundrect (at -0.485 0 180) (size 0.59 0.64) (layers "B.Cu" "B.Paste" "B.Mask") (roundrect_rratio 0.25)
      (net 73 "/PoE/VDD_POE") (pintype "passive"))
    (pad "2" smd roundrect (at 0.485 0 180) (size 0.59 0.64) (layers "B.Cu" "B.Paste" "B.Mask") (roundrect_rratio 0.25)
      (net 145 "/PoE/DEN") (pintype "passive"))
  )

  (footprint "sa800u-baseboard-hw-footprints:SOIC-8-1EP_3.9x4.9x1.75mm_P1.27mm" (layer "B.Cu")
    (tedit 5FD9C0CC)
    (at 60.7 109.5 90)
    (tags "Integrated Circuit")
    (property "Arrow Part Number" "TPS2378DDA")
    (property "Arrow Price/Stock" "https://www.arrow.com/en/products/tps2378dda/texas-instruments")
    (property "Author" "Antmicro")
    (property "Description" "IEEE 802.3at PoE High-Power PD Interface with AUX Control")
    (property "License" "Apache-2.0")
    (property "MPN" "TPS2378DDA")
    (property "Manufacturer" "Texas Instruments")
    (property "Mouser Part Number" "595-TPS2378DDA")
    (property "Mouser Price/Stock" "https://www.mouser.co.uk/ProductDetail/Texas-Instruments/TPS2378DDA?qs=5771e39Rz9HhOSwUvwIrNw%3D%3D")
    (property "Sheetfile" "poe.kicad_sch")
    (property "Sheetname" "PoE")
    (attr smd)
    (fp_text reference "IC2" (at 0.86 3.65 270) (layer "B.SilkS")
      (effects (font (size 0.7 0.7) (thickness 0.15)) (justify left bottom mirror))
    )
    (fp_text value "TPS2378DDA" (at 0 -3.65 270) (layer "B.Fab")
      (effects (font (size 0.7 0.7) (thickness 0.15)) (justify left bottom mirror))
    )
    (fp_text user "License: Apache-2.0" (at -3.476 -5.099 270) (layer "B.Fab") hide
      (effects (font (size 0.7 0.7) (thickness 0.15)) (justify left bottom mirror))
    )
    (fp_text user "Author: Antmicro" (at -3.476 -6.099 270) (layer "B.Fab") hide
      (effects (font (size 0.7 0.7) (thickness 0.15)) (justify left bottom mirror))
    )
    (fp_text user "${REFERENCE}" (at -3.476 -7.099 270) (layer "B.Fab") hide
      (effects (font (size 0.7 0.7) (thickness 0.15)) (justify left bottom mirror))
    )
    (fp_line (start 1.95 2.55) (end -1.95 2.55) (layer "B.SilkS") (width 0.15))
    (fp_line (start 1.95 -2.55) (end -1.95 -2.55) (layer "B.SilkS") (width 0.15))
    (fp_circle (center -2.5 2.45) (end -2.45 2.4) (layer "B.SilkS") (width 0.15) (fill solid))
    (fp_rect (start -3.55 2.7) (end 3.55 -2.7) (layer "B.CrtYd") (width 0.05) (fill none))
    (fp_line (start -0.683 2.452) (end 1.949 2.452) (layer "B.Fab") (width 0.15))
    (fp_line (start -1.95 1.18) (end -0.683 2.452) (layer "B.Fab") (width 0.15))
    (fp_line (start -1.95 -2.45) (end -1.95 1.18) (layer "B.Fab") (width 0.15))
    (fp_line (start 1.949 -2.45) (end -1.95 -2.45) (layer "B.Fab") (width 0.15))
    (fp_line (start 1.949 2.452) (end 1.949 -2.45) (layer "B.Fab") (width 0.15))
    (pad "1" smd roundrect (at -2.714 1.905) (size 0.65 1.525) (layers "B.Cu" "B.Paste" "B.Mask") (roundrect_rratio 0.25)
      (net 73 "/PoE/VDD_POE") (pinfunction "VDD") (pintype "power_in"))
    (pad "2" smd roundrect (at -2.714 0.635) (size 0.65 1.525) (layers "B.Cu" "B.Paste" "B.Mask") (roundrect_rratio 0.25)
      (net 145 "/PoE/DEN") (pinfunction "DEN") (pintype "passive"))
    (pad "3" smd roundrect (at -2.714 -0.632) (size 0.65 1.525) (layers "B.Cu" "B.Paste" "B.Mask") (roundrect_rratio 0.25)
      (net 146 "/PoE/CLS") (pinfunction "CLS") (pintype "passive"))
    (pad "4" smd roundrect (at -2.714 -1.902) (size 0.65 1.525) (layers "B.Cu" "B.Paste" "B.Mask") (roundrect_rratio 0.25)
      (net 135 "/PoE/VSS_POE") (pinfunction "VSS") (pintype "power_in"))
    (pad "5" smd roundrect (at 2.712 -1.902) (size 0.65 1.525) (layers "B.Cu" "B.Paste" "B.Mask") (roundrect_rratio 0.25)
      (net 7 "GNDD") (pinfunction "RTN") (pintype "passive"))
    (pad "6" smd roundrect (at 2.712 -0.632) (size 0.65 1.525) (layers "B.Cu" "B.Paste" "B.Mask") (roundrect_rratio 0.25)
      (net 147 "/PoE/CDB") (pinfunction "CDB") (pintype "passive"))
    (pad "7" smd roundrect (at 2.712 0.635) (size 0.65 1.525) (layers "B.Cu" "B.Paste" "B.Mask") (roundrect_rratio 0.25)
      (net 384 "Net-(IC2-Pad7)") (pinfunction "T2P") (pintype "passive"))
    (pad "8" smd roundrect (at 2.712 1.905) (size 0.65 1.525) (layers "B.Cu" "B.Paste" "B.Mask") (roundrect_rratio 0.25)
      (net 174 "/PoE/APD") (pinfunction "APD") (pintype "passive"))
    (pad "9" smd roundrect (at 0 0 90) (size 2.29 3.1) (layers "B.Cu" "B.Paste" "B.Mask") (roundrect_rratio 0.05)
      (net 135 "/PoE/VSS_POE") (pinfunction "EP") (pintype "power_in"))
  )

  (footprint "sa800u-baseboard-hw-footprints:TP_SMD_0.75mm" (layer "B.Cu")
    (tedit 5E4A9375)
    (at 126.5 130.6 180)
    (property "Author" "Antmicro")
    (property "License" "Apache-2.0")
    (property "MPN" "")
    (property "Manufacturer" "")
    (property "Sheetfile" "usb-c-interface.kicad_sch")
    (property "Sheetname" "USB-C Interface ")
    (attr smd)
    (fp_text reference "TP100" (at -3.74 -0.32) (layer "B.SilkS")
      (effects (font (size 0.7 0.7) (thickness 0.15)) (justify left bottom mirror))
    )
    (fp_text value "TP_0.75mm_SMD" (at 0 -1.2) (layer "B.Fab")
      (effects (font (size 0.7 0.7) (thickness 0.15)) (justify left bottom mirror))
    )
    (fp_text user "Author: Antmicro" (at -0.4 -3.901) (layer "B.Fab") hide
      (effects (font (size 0.7 0.7) (thickness 0.15)) (justify left bottom mirror))
    )
    (fp_text user "${REFERENCE}" (at -0.4 -2.7) (layer "B.Fab") hide
      (effects (font (size 0.7 0.7) (thickness 0.15)) (justify left bottom mirror))
    )
    (fp_text user "License: Apache-2.0" (at -0.4 -5.101) (layer "B.Fab") hide
      (effects (font (size 0.7 0.7) (thickness 0.15)) (justify left bottom mirror))
    )
    (pad "1" smd circle (at 0 0 180) (size 0.75 0.75) (layers "B.Cu" "B.Mask")
      (net 129 "DBG_RXD") (pinfunction "1") (pintype "passive"))
  )

  (footprint "sa800u-baseboard-hw-footprints:SOT-23-3" (layer "B.Cu")
    (tedit 5D5D4314)
    (at 79.8 147.1 180)
    (property "Author" "Antmicro")
    (property "License" "Apache-2.0")
    (property "MPN" "BSS84")
    (property "Manufacturer" "ON Semiconductor")
    (property "Sheetfile" "psu.kicad_sch")
    (property "Sheetname" "PSU")
    (attr smd)
    (fp_text reference "Q8" (at -0.86 1.8) (layer "B.SilkS")
      (effects (font (size 0.7 0.7) (thickness 0.15)) (justify left bottom mirror))
    )
    (fp_text value "BSS84" (at -1.9 -2.7) (layer "B.Fab")
      (effects (font (size 0.7 0.7) (thickness 0.15)) (justify left bottom mirror))
    )
    (fp_text user "${REFERENCE}" (at -1.837 -4) (layer "B.Fab") hide
      (effects (font (size 0.7 0.7) (thickness 0.15)) (justify left bottom mirror))
    )
    (fp_text user "License: Apache-2.0" (at -1.8 -6.8) (layer "B.Fab") hide
      (effects (font (size 0.7 0.7) (thickness 0.15)) (justify left bottom mirror))
    )
    (fp_text user "Author: Antmicro" (at -1.837 -5.3) (layer "B.Fab") hide
      (effects (font (size 0.7 0.7) (thickness 0.15)) (justify left bottom mirror))
    )
    (fp_line (start 0.7 0.4) (end 0.7 1.5) (layer "B.SilkS") (width 0.15))
    (fp_line (start -0.7 -1.5) (end -0.7 -1.35) (layer "B.SilkS") (width 0.15))
    (fp_line (start 0.7 1.5) (end -0.7 1.5) (layer "B.SilkS") (width 0.15))
    (fp_line (start -1.45 1.35) (end -0.85 1.35) (layer "B.SilkS") (width 0.15))
    (fp_line (start -0.85 1.35) (end -0.7 1.5) (layer "B.SilkS") (width 0.15))
    (fp_line (start 0.7 -0.4) (end 0.7 -1.5) (layer "B.SilkS") (width 0.15))
    (fp_line (start 0.7 -1.5) (end -0.7 -1.5) (layer "B.SilkS") (width 0.15))
    (fp_line (start 0.825 0.45) (end 1.75 0.45) (layer "B.CrtYd") (width 0.05))
    (fp_line (start -0.9 1.4) (end -1.75 1.4) (layer "B.CrtYd") (width 0.05))
    (fp_line (start -1.75 0.5) (end -1.75 1.4) (layer "B.CrtYd") (width 0.05))
    (fp_line (start -0.85 0.5) (end -1.75 0.5) (layer "B.CrtYd") (width 0.05))
    (fp_line (start -0.9 1.6) (end -0.9 1.4) (layer "B.CrtYd") (width 0.05))
    (fp_line (start -1.75 -0.5) (end -0.85 -0.5) (layer "B.CrtYd") (width 0.05))
    (fp_line (start -0.85 -1.65) (end -0.85 -1.4) (layer "B.CrtYd") (width 0.05))
    (fp_line (start 0.825 1.6) (end 0.825 0.45) (layer "B.CrtYd") (width 0.05))
    (fp_line (start 1.75 0.45) (end 1.75 -0.45) (layer "B.CrtYd") (width 0.05))
    (fp_line (start 0.85 -0.45) (end 0.85 -1.65) (layer "B.CrtYd") (width 0.05))
    (fp_line (start -1.75 -1.4) (end -1.75 -0.5) (layer "B.CrtYd") (width 0.05))
    (fp_line (start -0.85 -0.5) (end -0.85 0.5) (layer "B.CrtYd") (width 0.05))
    (fp_line (start 1.75 -0.45) (end 0.85 -0.45) (layer "B.CrtYd") (width 0.05))
    (fp_line (start 0.85 -1.65) (end -0.85 -1.65) (layer "B.CrtYd") (width 0.05))
    (fp_line (start -0.9 1.6) (end 0.825 1.6) (layer "B.CrtYd") (width 0.05))
    (fp_line (start -0.85 -1.4) (end -1.75 -1.4) (layer "B.CrtYd") (width 0.05))
    (fp_line (start -0.437 1.526) (end -0.712 1.325) (layer "B.Fab") (width 0.15))
    (fp_line (start -0.437 1.526) (end 0.688 1.526) (layer "B.Fab") (width 0.15))
    (fp_line (start -0.712 1.325) (end -0.712 -1.523) (layer "B.Fab") (width 0.15))
    (fp_line (start -0.712 -1.519) (end 0.688 -1.519) (layer "B.Fab") (width 0.15))
    (fp_line (start 0.688 -1.519) (end 0.688 1.52) (layer "B.Fab") (width 0.15))
    (pad "1" smd roundrect (at -1.1 0.951 180) (size 1 0.6) (layers "B.Cu" "B.Paste" "B.Mask") (roundrect_rratio 0.15)
      (net 339 "/PSU/AUX_VALID") (pinfunction "G") (pintype "bidirectional"))
    (pad "2" smd roundrect (at -1.1 -0.949 180) (size 1 0.6) (layers "B.Cu" "B.Paste" "B.Mask") (roundrect_rratio 0.15)
      (net 1 "GND") (pinfunction "D") (pintype "bidirectional"))
    (pad "3" smd roundrect (at 1.1 0.0005 180) (size 1 0.6) (layers "B.Cu" "B.Paste" "B.Mask") (roundrect_rratio 0.15)
      (net 388 "Net-(Q8-Pad3)") (pinfunction "S") (pintype "bidirectional"))
  )

  (footprint "sa800u-baseboard-hw-footprints:R_0402_1005Metric" (layer "B.Cu")
    (tedit 5FD9C158)
    (at 81.25 150 -90)
    (descr "Resistor SMD 0402")
    (tags "resistor SMD 0402")
    (property "Author" "Antmicro")
    (property "License" "Apache-2.0")
    (property "MPN" "CR0402-FX-1002GLF")
    (property "Manufacturer" "Bourns")
    (property "Sheetfile" "psu.kicad_sch")
    (property "Sheetname" "PSU")
    (property "Tolerance" "1%")
    (property "Val" "10k")
    (attr smd)
    (fp_text reference "R111" (at -1.05 0.64 90) (layer "B.SilkS")
      (effects (font (size 0.7 0.7) (thickness 0.15)) (justify left bottom mirror))
    )
    (fp_text value "R_10k_0402" (at 0 -1.4 90) (layer "B.Fab")
      (effects (font (size 0.7 0.7) (thickness 0.15)) (justify left bottom mirror))
    )
    (fp_text user "${REFERENCE}" (at -0.95 -3.168 90) (layer "B.Fab") hide
      (effects (font (size 0.7 0.7) (thickness 0.15)) (justify left bottom mirror))
    )
    (fp_text user "License: Apache-2.0" (at -0.95 -5.169 90) (layer "B.Fab") hide
      (effects (font (size 0.7 0.7) (thickness 0.15)) (justify left bottom mirror))
    )
    (fp_text user "Author: Antmicro" (at -0.95 -4.169 90) (layer "B.Fab") hide
      (effects (font (size 0.7 0.7) (thickness 0.15)) (justify left bottom mirror))
    )
    (fp_rect (start -0.93 0.47) (end 0.93 -0.47) (layer "B.CrtYd") (width 0.05) (fill none))
    (fp_rect (start -0.5 0.25) (end 0.5 -0.25) (layer "B.Fab") (width 0.15) (fill none))
    (pad "1" smd roundrect (at -0.485 0 270) (size 0.59 0.64) (layers "B.Cu" "B.Paste" "B.Mask") (roundrect_rratio 0.25)
      (net 388 "Net-(Q8-Pad3)") (pintype "passive"))
    (pad "2" smd roundrect (at 0.485 0 270) (size 0.59 0.64) (layers "B.Cu" "B.Paste" "B.Mask") (roundrect_rratio 0.25)
      (net 375 "Net-(D24-Pad2)") (pintype "passive"))
  )

  (footprint "sa800u-baseboard-hw-footprints:R_0402_1005Metric" (layer "B.Cu")
    (tedit 5FD9C158)
    (at 93.4 150.25 -90)
    (descr "Resistor SMD 0402")
    (tags "resistor SMD 0402")
    (property "Author" "Antmicro")
    (property "License" "Apache-2.0")
    (property "MPN" "CR0402-FX-1002GLF")
    (property "Manufacturer" "Bourns")
    (property "Sheetfile" "psu.kicad_sch")
    (property "Sheetname" "PSU")
    (property "Tolerance" "1%")
    (property "Val" "10k")
    (attr smd)
    (fp_text reference "R115" (at -1.25 -1.32 90) (layer "B.SilkS")
      (effects (font (size 0.7 0.7) (thickness 0.15)) (justify left bottom mirror))
    )
    (fp_text value "R_10k_0402" (at 0 -1.4 90) (layer "B.Fab")
      (effects (font (size 0.7 0.7) (thickness 0.15)) (justify left bottom mirror))
    )
    (fp_text user "${REFERENCE}" (at -0.95 -3.168 90) (layer "B.Fab") hide
      (effects (font (size 0.7 0.7) (thickness 0.15)) (justify left bottom mirror))
    )
    (fp_text user "Author: Antmicro" (at -0.95 -4.169 90) (layer "B.Fab") hide
      (effects (font (size 0.7 0.7) (thickness 0.15)) (justify left bottom mirror))
    )
    (fp_text user "License: Apache-2.0" (at -0.95 -5.169 90) (layer "B.Fab") hide
      (effects (font (size 0.7 0.7) (thickness 0.15)) (justify left bottom mirror))
    )
    (fp_rect (start -0.93 0.47) (end 0.93 -0.47) (layer "B.CrtYd") (width 0.05) (fill none))
    (fp_rect (start -0.5 0.25) (end 0.5 -0.25) (layer "B.Fab") (width 0.15) (fill none))
    (pad "1" smd roundrect (at -0.485 0 270) (size 0.59 0.64) (layers "B.Cu" "B.Paste" "B.Mask") (roundrect_rratio 0.25)
      (net 389 "Net-(Q10-Pad3)") (pintype "passive"))
    (pad "2" smd roundrect (at 0.485 0 270) (size 0.59 0.64) (layers "B.Cu" "B.Paste" "B.Mask") (roundrect_rratio 0.25)
      (net 376 "Net-(D25-Pad2)") (pintype "passive"))
  )

  (footprint "sa800u-baseboard-hw-footprints:SOT-23-3" (layer "B.Cu")
    (tedit 5D5D4314)
    (at 84.2 123 90)
    (property "Author" "Antmicro")
    (property "License" "Apache-2.0")
    (property "MPN" "BSS84")
    (property "Manufacturer" "ON Semiconductor")
    (property "Sheetfile" "psu.kicad_sch")
    (property "Sheetname" "PSU")
    (attr smd)
    (fp_text reference "Q14" (at 0.98 2.65) (layer "B.SilkS")
      (effects (font (size 0.7 0.7) (thickness 0.15)) (justify left bottom mirror))
    )
    (fp_text value "BSS84" (at -1.9 -2.7 270) (layer "B.Fab")
      (effects (font (size 0.7 0.7) (thickness 0.15)) (justify left bottom mirror))
    )
    (fp_text user "License: Apache-2.0" (at -1.8 -6.8 270) (layer "B.Fab") hide
      (effects (font (size 0.7 0.7) (thickness 0.15)) (justify left bottom mirror))
    )
    (fp_text user "${REFERENCE}" (at -1.837 -4 270) (layer "B.Fab") hide
      (effects (font (size 0.7 0.7) (thickness 0.15)) (justify left bottom mirror))
    )
    (fp_text user "Author: Antmicro" (at -1.837 -5.3 270) (layer "B.Fab") hide
      (effects (font (size 0.7 0.7) (thickness 0.15)) (justify left bottom mirror))
    )
    (fp_line (start -0.85 1.35) (end -0.7 1.5) (layer "B.SilkS") (width 0.15))
    (fp_line (start 0.7 -0.4) (end 0.7 -1.5) (layer "B.SilkS") (width 0.15))
    (fp_line (start 0.7 -1.5) (end -0.7 -1.5) (layer "B.SilkS") (width 0.15))
    (fp_line (start 0.7 0.4) (end 0.7 1.5) (layer "B.SilkS") (width 0.15))
    (fp_line (start -0.7 -1.5) (end -0.7 -1.35) (layer "B.SilkS") (width 0.15))
    (fp_line (start 0.7 1.5) (end -0.7 1.5) (layer "B.SilkS") (width 0.15))
    (fp_line (start -1.45 1.35) (end -0.85 1.35) (layer "B.SilkS") (width 0.15))
    (fp_line (start -0.85 -1.4) (end -1.75 -1.4) (layer "B.CrtYd") (width 0.05))
    (fp_line (start -0.85 0.5) (end -1.75 0.5) (layer "B.CrtYd") (width 0.05))
    (fp_line (start -0.85 -1.65) (end -0.85 -1.4) (layer "B.CrtYd") (width 0.05))
    (fp_line (start -0.9 1.6) (end -0.9 1.4) (layer "B.CrtYd") (width 0.05))
    (fp_line (start -0.9 1.4) (end -1.75 1.4) (layer "B.CrtYd") (width 0.05))
    (fp_line (start -0.85 -0.5) (end -0.85 0.5) (layer "B.CrtYd") (width 0.05))
    (fp_line (start 0.85 -1.65) (end -0.85 -1.65) (layer "B.CrtYd") (width 0.05))
    (fp_line (start -1.75 -0.5) (end -0.85 -0.5) (layer "B.CrtYd") (width 0.05))
    (fp_line (start 0.825 1.6) (end 0.825 0.45) (layer "B.CrtYd") (width 0.05))
    (fp_line (start 1.75 -0.45) (end 0.85 -0.45) (layer "B.CrtYd") (width 0.05))
    (fp_line (start 1.75 0.45) (end 1.75 -0.45) (layer "B.CrtYd") (width 0.05))
    (fp_line (start -0.9 1.6) (end 0.825 1.6) (layer "B.CrtYd") (width 0.05))
    (fp_line (start 0.85 -0.45) (end 0.85 -1.65) (layer "B.CrtYd") (width 0.05))
    (fp_line (start -1.75 0.5) (end -1.75 1.4) (layer "B.CrtYd") (width 0.05))
    (fp_line (start -1.75 -1.4) (end -1.75 -0.5) (layer "B.CrtYd") (width 0.05))
    (fp_line (start 0.825 0.45) (end 1.75 0.45) (layer "B.CrtYd") (width 0.05))
    (fp_line (start 0.688 -1.519) (end 0.688 1.52) (layer "B.Fab") (width 0.15))
    (fp_line (start -0.437 1.526) (end 0.688 1.526) (layer "B.Fab") (width 0.15))
    (fp_line (start -0.712 -1.519) (end 0.688 -1.519) (layer "B.Fab") (width 0.15))
    (fp_line (start -0.712 1.325) (end -0.712 -1.523) (layer "B.Fab") (width 0.15))
    (fp_line (start -0.437 1.526) (end -0.712 1.325) (layer "B.Fab") (width 0.15))
    (pad "1" smd roundrect (at -1.1 0.951 90) (size 1 0.6) (layers "B.Cu" "B.Paste" "B.Mask") (roundrect_rratio 0.15)
      (net 156 "/PSU/BYPASS_EN") (pinfunction "G") (pintype "bidirectional"))
    (pad "2" smd roundrect (at -1.1 -0.949 90) (size 1 0.6) (layers "B.Cu" "B.Paste" "B.Mask") (roundrect_rratio 0.15)
      (net 1 "GND") (pinfunction "D") (pintype "bidirectional"))
    (pad "3" smd roundrect (at 1.1 0.0005 90) (size 1 0.6) (layers "B.Cu" "B.Paste" "B.Mask") (roundrect_rratio 0.15)
      (net 348 "Net-(Q14-Pad3)") (pinfunction "S") (pintype "bidirectional"))
  )

  (footprint "sa800u-baseboard-hw-footprints:Nexperia_DFN-10_2.5x1mm_P0.5mm" (layer "B.Cu")
    (tedit 6215DC23)
    (at 95.5 142.9 -90)
    (property "Author" "Antmicro")
    (property "License" "Apache-2.0")
    (property "MPN" "PUSB3F96X")
    (property "Manufacturer" "Nexperia")
    (property "Sheetfile" "usb-c-interface.kicad_sch")
    (property "Sheetname" "USB-C Interface ")
    (attr smd)
    (fp_text reference "D7" (at -1.5 -0.72 180) (layer "B.SilkS")
      (effects (font (size 0.7 0.7) (thickness 0.15)) (justify left bottom mirror))
    )
    (fp_text value "PUSB3F96X_PASS" (at -0.016 -1.705 90) (layer "B.Fab")
      (effects (font (size 0.7 0.7) (thickness 0.15)) (justify left bottom mirror))
    )
    (fp_text user "License: Apache-2.0" (at -1.367 -6.105 90) (layer "B.Fab") hide
      (effects (font (size 0.7 0.7) (thickness 0.15)) (justify left bottom mirror))
    )
    (fp_text user "Author: Antmicro" (at -1.367 -4.905 90) (layer "B.Fab") hide
      (effects (font (size 0.7 0.7) (thickness 0.15)) (justify left bottom mirror))
    )
    (fp_text user "${REFERENCE}" (at -1.367 -3.704 90) (layer "B.Fab") hide
      (effects (font (size 0.7 0.7) (thickness 0.15)) (justify left bottom mirror))
    )
    (fp_line (start -1.266 0.396) (end -1.266 -0.405) (layer "B.SilkS") (width 0.15))
    (fp_line (start 1.233 -0.405) (end 1.233 0.396) (layer "B.SilkS") (width 0.15))
    (fp_circle (center -1.317 -0.704) (end -1.266 -0.704) (layer "B.SilkS") (width 0.15) (fill solid))
    (fp_rect (start -1.4 0.7) (end 1.4 -0.7) (layer "B.CrtYd") (width 0.05) (fill none))
    (pad "1" smd rect (at -1.016 -0.392 270) (size 0.2 0.475) (layers "B.Cu" "B.Paste" "B.Mask")
      (net 368 "unconnected-(D7-Pad1)") (pinfunction "CH1") (pintype "passive+no_connect"))
    (pad "2" smd rect (at -0.517 -0.392 270) (size 0.2 0.475) (layers "B.Cu" "B.Paste" "B.Mask")
      (net 331 "/USB-C Interface /USB1_SBU_P") (pinfunction "CH2") (pintype "passive"))
    (pad "3" smd rect (at -0.016 -0.392 270) (size 0.2 0.475) (layers "B.Cu" "B.Paste" "B.Mask")
      (net 1 "GND") (pinfunction "GND") (pintype "passive"))
    (pad "4" smd rect (at 0.482 -0.392 270) (size 0.2 0.475) (layers "B.Cu" "B.Paste" "B.Mask")
      (net 330 "/USB-C Interface /USB1_SBU_N") (pinfunction "CH3") (pintype "passive"))
    (pad "5" smd rect (at 0.982 -0.392 270) (size 0.2 0.475) (layers "B.Cu" "B.Paste" "B.Mask")
      (net 369 "unconnected-(D7-Pad5)") (pinfunction "CH4") (pintype "passive+no_connect"))
    (pad "6" smd rect (at 0.982 0.383 90) (size 0.2 0.475) (layers "B.Cu" "B.Paste" "B.Mask")
      (net 369 "unconnected-(D7-Pad5)") (pinfunction "CH4") (pintype "passive+no_connect"))
    (pad "7" smd rect (at 0.482 0.383 90) (size 0.2 0.475) (layers "B.Cu" "B.Paste" "B.Mask")
      (net 330 "/USB-C Interface /USB1_SBU_N") (pinfunction "CH3") (pintype "passive"))
    (pad "8" smd rect (at -0.016 0.383 90) (size 0.2 0.475) (layers "B.Cu" "B.Paste" "B.Mask")
      (net 1 "GND") (pinfunction "GND") (pintype "passive"))
    (pad "9" smd rect (at -0.517 0.383 90) (size 0.2 0.475) (layers "B.Cu" "B.Paste" "B.Mask")
      (net 331 "/USB-C Interface /USB1_SBU_P") (pinfunction "CH2") (pintype "passive"))
    (pad "10" smd rect (at -1.016 0.383 90) (size 0.2 0.475) (layers "B.Cu" "B.Paste" "B.Mask")
      (net 368 "unconnected-(D7-Pad1)") (pinfunction "CH1") (pintype "passive+no_connect"))
  )

  (footprint "sa800u-baseboard-hw-footprints:L_Murata_025020_0605Metric" (layer "B.Cu")
    (tedit 61AA2C4F)
    (at 95 93.7 90)
    (property "Author" "Antmicro")
    (property "License" "Apache-2.0")
    (property "MPN" "NFP0QHB242HS2D")
    (property "Manufacturer" "Murata")
    (property "Sheetfile" "camera-interface.kicad_sch")
    (property "Sheetname" "Camera Interface")
    (attr smd)
    (fp_text reference "L18" (at -0.44 0.33 270) (layer "B.SilkS")
      (effects (font (size 0.7 0.7) (thickness 0.15)) (justify left bottom mirror))
    )
    (fp_text value "NFP0QHB242HS2D" (at 0 -1.55 270) (layer "B.Fab")
      (effects (font (size 0.7 0.7) (thickness 0.15)) (justify left bottom mirror))
    )
    (fp_text user "Author: Antmicro" (at -1.027 -4.605 270) (layer "B.Fab") hide
      (effects (font (size 0.7 0.7) (thickness 0.15)) (justify left bottom mirror))
    )
    (fp_text user "${REFERENCE}" (at -1.027 -3.406 270) (layer "B.Fab") hide
      (effects (font (size 0.7 0.7) (thickness 0.15)) (justify left bottom mirror))
    )
    (fp_text user "License: Apache-2.0" (at -1.027 -5.805 270) (layer "B.Fab") hide
      (effects (font (size 0.7 0.7) (thickness 0.15)) (justify left bottom mirror))
    )
    (fp_line (start 0.276 0.45) (end -0.276 0.45) (layer "B.SilkS") (width 0.15))
    (fp_line (start -0.276 -0.45) (end 0.276 -0.45) (layer "B.SilkS") (width 0.15))
    (fp_circle (center -0.5 0.5) (end -0.449 0.5) (layer "B.SilkS") (width 0.15) (fill solid))
    (fp_rect (start -0.5 0.6) (end 0.5 -0.6) (layer "B.CrtYd") (width 0.05) (fill none))
    (fp_line (start 0.275 0.351) (end -0.277 0.351) (layer "B.Fab") (width 0.15))
    (fp_line (start -0.277 0.351) (end -0.277 -0.349) (layer "B.Fab") (width 0.15))
    (fp_line (start -0.277 -0.349) (end 0.275 -0.349) (layer "B.Fab") (width 0.15))
    (fp_line (start 0.275 -0.349) (end 0.275 0.351) (layer "B.Fab") (width 0.15))
    (pad "1" smd rect (at -0.25 0.24 90) (size 0.3 0.23) (layers "B.Cu" "B.Paste" "B.Mask")
      (net 21 "CSI1_LN1_P") (pinfunction "1") (pintype "passive"))
    (pad "2" smd rect (at 0.248 0.24 90) (size 0.3 0.23) (layers "B.Cu" "B.Paste" "B.Mask")
      (net 272 "/Camera Interface/CSI1_LN1_FFC_P") (pinfunction "2") (pintype "passive"))
    (pad "3" smd rect (at 0.248 -0.239 90) (size 0.3 0.23) (layers "B.Cu" "B.Paste" "B.Mask")
      (net 273 "/Camera Interface/CSI1_LN1_FFC_N") (pinfunction "3") (pintype "passive"))
    (pad "4" smd rect (at -0.25 -0.239 90) (size 0.3 0.23) (layers "B.Cu" "B.Paste" "B.Mask")
      (net 22 "CSI1_LN1_N") (pinfunction "4") (pintype "passive"))
  )

  (footprint "sa800u-baseboard-hw-footprints:SOT-23-3" (layer "B.Cu")
    (tedit 5D5D4314)
    (at 72.2 118.6 90)
    (property "Author" "Antmicro")
    (property "License" "Apache-2.0")
    (property "MPN" "BSS84PH6327XTSA2")
    (property "Manufacturer" "Infineon Technologies")
    (property "Sheetfile" "psu.kicad_sch")
    (property "Sheetname" "PSU")
    (attr smd)
    (fp_text reference "Q15" (at 0.86 2.42) (layer "B.SilkS")
      (effects (font (size 0.7 0.7) (thickness 0.15)) (justify left bottom mirror))
    )
    (fp_text value "BSS84PH6327XTSA2" (at -1.9 -2.7 270) (layer "B.Fab")
      (effects (font (size 0.7 0.7) (thickness 0.15)) (justify left bottom mirror))
    )
    (fp_text user "${REFERENCE}" (at -1.837 -4 270) (layer "B.Fab") hide
      (effects (font (size 0.7 0.7) (thickness 0.15)) (justify left bottom mirror))
    )
    (fp_text user "License: Apache-2.0" (at -1.8 -6.8 270) (layer "B.Fab") hide
      (effects (font (size 0.7 0.7) (thickness 0.15)) (justify left bottom mirror))
    )
    (fp_text user "Author: Antmicro" (at -1.837 -5.3 270) (layer "B.Fab") hide
      (effects (font (size 0.7 0.7) (thickness 0.15)) (justify left bottom mirror))
    )
    (fp_line (start 0.7 1.5) (end -0.7 1.5) (layer "B.SilkS") (width 0.15))
    (fp_line (start -0.7 -1.5) (end -0.7 -1.35) (layer "B.SilkS") (width 0.15))
    (fp_line (start 0.7 -0.4) (end 0.7 -1.5) (layer "B.SilkS") (width 0.15))
    (fp_line (start -0.85 1.35) (end -0.7 1.5) (layer "B.SilkS") (width 0.15))
    (fp_line (start 0.7 -1.5) (end -0.7 -1.5) (layer "B.SilkS") (width 0.15))
    (fp_line (start -1.45 1.35) (end -0.85 1.35) (layer "B.SilkS") (width 0.15))
    (fp_line (start 0.7 0.4) (end 0.7 1.5) (layer "B.SilkS") (width 0.15))
    (fp_line (start -0.9 1.6) (end -0.9 1.4) (layer "B.CrtYd") (width 0.05))
    (fp_line (start 0.825 0.45) (end 1.75 0.45) (layer "B.CrtYd") (width 0.05))
    (fp_line (start -0.85 -0.5) (end -0.85 0.5) (layer "B.CrtYd") (width 0.05))
    (fp_line (start -1.75 0.5) (end -1.75 1.4) (layer "B.CrtYd") (width 0.05))
    (fp_line (start -0.85 0.5) (end -1.75 0.5) (layer "B.CrtYd") (width 0.05))
    (fp_line (start -0.85 -1.65) (end -0.85 -1.4) (layer "B.CrtYd") (width 0.05))
    (fp_line (start 0.85 -1.65) (end -0.85 -1.65) (layer "B.CrtYd") (width 0.05))
    (fp_line (start 1.75 0.45) (end 1.75 -0.45) (layer "B.CrtYd") (width 0.05))
    (fp_line (start -0.9 1.6) (end 0.825 1.6) (layer "B.CrtYd") (width 0.05))
    (fp_line (start -1.75 -1.4) (end -1.75 -0.5) (layer "B.CrtYd") (width 0.05))
    (fp_line (start -0.9 1.4) (end -1.75 1.4) (layer "B.CrtYd") (width 0.05))
    (fp_line (start 0.85 -0.45) (end 0.85 -1.65) (layer "B.CrtYd") (width 0.05))
    (fp_line (start -0.85 -1.4) (end -1.75 -1.4) (layer "B.CrtYd") (width 0.05))
    (fp_line (start -1.75 -0.5) (end -0.85 -0.5) (layer "B.CrtYd") (width 0.05))
    (fp_line (start 1.75 -0.45) (end 0.85 -0.45) (layer "B.CrtYd") (width 0.05))
    (fp_line (start 0.825 1.6) (end 0.825 0.45) (layer "B.CrtYd") (width 0.05))
    (fp_line (start -0.437 1.526) (end -0.712 1.325) (layer "B.Fab") (width 0.15))
    (fp_line (start -0.712 1.325) (end -0.712 -1.523) (layer "B.Fab") (width 0.15))
    (fp_line (start -0.437 1.526) (end 0.688 1.526) (layer "B.Fab") (width 0.15))
    (fp_line (start -0.712 -1.519) (end 0.688 -1.519) (layer "B.Fab") (width 0.15))
    (fp_line (start 0.688 -1.519) (end 0.688 1.52) (layer "B.Fab") (width 0.15))
    (pad "1" smd roundrect (at -1.1 0.951 90) (size 1 0.6) (layers "B.Cu" "B.Paste" "B.Mask") (roundrect_rratio 0.15)
      (net 390 "Net-(Q15-Pad1)") (pinfunction "G") (pintype "bidirectional"))
    (pad "2" smd roundrect (at -1.1 -0.949 90) (size 1 0.6) (layers "B.Cu" "B.Paste" "B.Mask") (roundrect_rratio 0.15)
      (net 156 "/PSU/BYPASS_EN") (pinfunction "D") (pintype "bidirectional"))
    (pad "3" smd roundrect (at 1.1 0.0005 90) (size 1 0.6) (layers "B.Cu" "B.Paste" "B.Mask") (roundrect_rratio 0.15)
      (net 74 "VDD") (pinfunction "S") (pintype "bidirectional"))
  )

  (footprint "sa800u-baseboard-hw-footprints:C_0402_1005Metric" (layer "B.Cu")
    (tedit 616D63CF)
    (at 133.888164 125.012952 90)
    (descr "Capacitor SMD 0402")
    (tags "capacitor SMD 0402")
    (property "Author" "Antmicro")
    (property "Dielectric" "X5R")
    (property "License" "Apache-2.0")
    (property "MPN" "GRM155R61H104KE14D")
    (property "Manufacturer" "Murata")
    (property "Sheetfile" "hdmi-converter.kicad_sch")
    (property "Sheetname" "HDMI converter")
    (property "Val" "100n")
    (property "Voltage" "50V")
    (attr smd)
    (fp_text reference "C20" (at 1.112952 -0.588164 270) (layer "B.SilkS")
      (effects (font (size 0.7 0.7) (thickness 0.15)) (justify left bottom mirror))
    )
    (fp_text value "C_100n_0402" (at 0 -1.4 270) (layer "B.Fab")
      (effects (font (size 0.7 0.7) (thickness 0.15)) (justify left bottom mirror))
    )
    (fp_text user "${REFERENCE}" (at -0.932 -3.168 270) (layer "B.Fab") hide
      (effects (font (size 0.7 0.7) (thickness 0.15)) (justify left bottom mirror))
    )
    (fp_text user "License: Apache-2.0" (at -0.932 -5.17 270) (layer "B.Fab") hide
      (effects (font (size 0.7 0.7) (thickness 0.15)) (justify left bottom mirror))
    )
    (fp_text user "Author: Antmicro" (at -0.932 -4.17 270) (layer "B.Fab") hide
      (effects (font (size 0.7 0.7) (thickness 0.15)) (justify left bottom mirror))
    )
    (fp_rect (start -0.94 0.47) (end 0.94 -0.47) (layer "B.CrtYd") (width 0.05) (fill none))
    (fp_rect (start -0.499 0.249) (end 0.499 -0.249) (layer "B.Fab") (width 0.15) (fill none))
    (pad "1" smd roundrect (at -0.484 0 90) (size 0.59 0.64) (layers "B.Cu" "B.Paste" "B.Mask") (roundrect_rratio 0.25)
      (net 131 "3V3_SYS") (pintype "passive"))
    (pad "2" smd roundrect (at 0.484 0 90) (size 0.59 0.64) (layers "B.Cu" "B.Paste" "B.Mask") (roundrect_rratio 0.25)
      (net 1 "GND") (pintype "passive"))
  )

  (footprint "sa800u-baseboard-hw-footprints:C_0805_2012Metric" (layer "B.Cu")
    (tedit 5FD9C126)
    (at 77.2 101.9 90)
    (descr "Capacitor SMD 0805")
    (tags "capacitor SMD 0805")
    (property "Author" "Antmicro")
    (property "Dielectric" "")
    (property "License" "Apache-2.0")
    (property "MPN" "GRM21BR60J107ME15L")
    (property "Manufacturer" "Murata")
    (property "Sheetfile" "poe.kicad_sch")
    (property "Sheetname" "PoE")
    (property "Val" "100u")
    (property "Voltage" "")
    (attr smd)
    (fp_text reference "C148" (at 4.48 0.35 270) (layer "B.SilkS")
      (effects (font (size 0.7 0.7) (thickness 0.15)) (justify left bottom mirror))
    )
    (fp_text value "C_100u_0805" (at 0 -1.947 270) (layer "B.Fab")
      (effects (font (size 0.7 0.7) (thickness 0.15)) (justify left bottom mirror))
    )
    (fp_text user "License: Apache-2.0" (at -1.9 -4.947 270) (layer "B.Fab") hide
      (effects (font (size 0.7 0.7) (thickness 0.15)) (justify left bottom mirror))
    )
    (fp_text user "Author: Antmicro" (at -1.9 -5.947 270) (layer "B.Fab") hide
      (effects (font (size 0.7 0.7) (thickness 0.15)) (justify left bottom mirror))
    )
    (fp_text user "${REFERENCE}" (at -1.9 -3.947 270) (layer "B.Fab") hide
      (effects (font (size 0.7 0.7) (thickness 0.15)) (justify left bottom mirror))
    )
    (fp_line (start -0.3 -0.8) (end 0.3 -0.8) (layer "B.SilkS") (width 0.15))
    (fp_line (start -0.3 0.8) (end 0.3 0.8) (layer "B.SilkS") (width 0.15))
    (fp_rect (start -1.9 0.93) (end 1.9 -0.93) (layer "B.CrtYd") (width 0.05) (fill none))
    (fp_rect (start -0.95 0.675) (end 0.95 -0.675) (layer "B.Fab") (width 0.15) (fill none))
    (pad "1" smd rect (at -1.05 0 90) (size 1.2 1.2) (layers "B.Cu" "B.Paste" "B.Mask")
      (net 136 "5V_POE") (pintype "passive"))
    (pad "2" smd rect (at 1.05 0 90) (size 1.2 1.2) (layers "B.Cu" "B.Paste" "B.Mask")
      (net 1 "GND") (pintype "passive"))
  )

  (footprint "sa800u-baseboard-hw-footprints:C_0603_1608Metric" (layer "B.Cu")
    (tedit 5D5E94D2)
    (at 76.6 145.3 180)
    (descr "Capacitor SMD 0603")
    (tags "capacitor 0603")
    (property "Author" "Antmicro")
    (property "Dielectric" "")
    (property "License" "Apache-2.0")
    (property "MPN" "C1608X5R1E106M080AC")
    (property "Manufacturer" "TDK")
    (property "Sheetfile" "psu.kicad_sch")
    (property "Sheetname" "PSU")
    (property "Val" "10u/25V")
    (property "Voltage" "")
    (attr smd)
    (fp_text reference "C121" (at -1.43 -2.86) (layer "B.SilkS")
      (effects (font (size 0.7 0.7) (thickness 0.15)) (justify left bottom mirror))
    )
    (fp_text value "C_10u_25V_0603" (at 0 -1.6) (layer "B.Fab")
      (effects (font (size 0.7 0.7) (thickness 0.15)) (justify left bottom mirror))
    )
    (fp_text user "License: Apache-2.0" (at -1.682 -5.895) (layer "B.Fab") hide
      (effects (font (size 0.7 0.7) (thickness 0.15)) (justify left bottom mirror))
    )
    (fp_text user "${REFERENCE}" (at -1.682 -3.895) (layer "B.Fab") hide
      (effects (font (size 0.7 0.7) (thickness 0.15)) (justify left bottom mirror))
    )
    (fp_text user "Author: Antmicro" (at -1.682 -4.894) (layer "B.Fab") hide
      (effects (font (size 0.7 0.7) (thickness 0.15)) (justify left bottom mirror))
    )
    (fp_line (start -0.3 0.3) (end 0.3 0.3) (layer "B.SilkS") (width 0.15))
    (fp_line (start -0.3 -0.3) (end 0.3 -0.3) (layer "B.SilkS") (width 0.15))
    (fp_rect (start -1.24 0.7) (end 1.24 -0.7) (layer "B.CrtYd") (width 0.05) (fill none))
    (fp_rect (start -0.8 0.4) (end 0.8 -0.4) (layer "B.Fab") (width 0.15) (fill none))
    (pad "1" smd roundrect (at -0.7 0 180) (size 0.6 0.8) (layers "B.Cu" "B.Paste" "B.Mask") (roundrect_rratio 0.2)
      (net 152 "/PSU/AUX_VDD") (pintype "passive"))
    (pad "2" smd roundrect (at 0.7 0 180) (size 0.6 0.8) (layers "B.Cu" "B.Paste" "B.Mask") (roundrect_rratio 0.2)
      (net 1 "GND") (pintype "passive"))
  )

  (footprint "sa800u-baseboard-hw-footprints:C_0603_1608Metric" (layer "B.Cu")
    (tedit 5D5E94D2)
    (at 76.6 146.8 180)
    (descr "Capacitor SMD 0603")
    (tags "capacitor 0603")
    (property "Author" "Antmicro")
    (property "Dielectric" "")
    (property "License" "Apache-2.0")
    (property "MPN" "C1608X5R1E106M080AC")
    (property "Manufacturer" "TDK")
    (property "Sheetfile" "psu.kicad_sch")
    (property "Sheetname" "PSU")
    (property "Val" "10u/25V")
    (property "Voltage" "")
    (attr smd)
    (fp_text reference "C122" (at -1.42 -2.32) (layer "B.SilkS")
      (effects (font (size 0.7 0.7) (thickness 0.15)) (justify left bottom mirror))
    )
    (fp_text value "C_10u_25V_0603" (at 0 -1.6) (layer "B.Fab")
      (effects (font (size 0.7 0.7) (thickness 0.15)) (justify left bottom mirror))
    )
    (fp_text user "${REFERENCE}" (at -1.682 -3.895) (layer "B.Fab") hide
      (effects (font (size 0.7 0.7) (thickness 0.15)) (justify left bottom mirror))
    )
    (fp_text user "Author: Antmicro" (at -1.682 -4.894) (layer "B.Fab") hide
      (effects (font (size 0.7 0.7) (thickness 0.15)) (justify left bottom mirror))
    )
    (fp_text user "License: Apache-2.0" (at -1.682 -5.895) (layer "B.Fab") hide
      (effects (font (size 0.7 0.7) (thickness 0.15)) (justify left bottom mirror))
    )
    (fp_line (start -0.3 0.3) (end 0.3 0.3) (layer "B.SilkS") (width 0.15))
    (fp_line (start -0.3 -0.3) (end 0.3 -0.3) (layer "B.SilkS") (width 0.15))
    (fp_rect (start -1.24 0.7) (end 1.24 -0.7) (layer "B.CrtYd") (width 0.05) (fill none))
    (fp_rect (start -0.8 0.4) (end 0.8 -0.4) (layer "B.Fab") (width 0.15) (fill none))
    (pad "1" smd roundrect (at -0.7 0 180) (size 0.6 0.8) (layers "B.Cu" "B.Paste" "B.Mask") (roundrect_rratio 0.2)
      (net 152 "/PSU/AUX_VDD") (pintype "passive"))
    (pad "2" smd roundrect (at 0.7 0 180) (size 0.6 0.8) (layers "B.Cu" "B.Paste" "B.Mask") (roundrect_rratio 0.2)
      (net 1 "GND") (pintype "passive"))
  )

  (footprint "sa800u-baseboard-hw-footprints:C_0603_1608Metric" (layer "B.Cu")
    (tedit 5D5E94D2)
    (at 82.65 127.59 90)
    (descr "Capacitor SMD 0603")
    (tags "capacitor 0603")
    (property "Author" "Antmicro")
    (property "Dielectric" "")
    (property "License" "Apache-2.0")
    (property "MPN" "C1608X5R1E106M080AC")
    (property "Manufacturer" "TDK")
    (property "Sheetfile" "psu.kicad_sch")
    (property "Sheetname" "PSU")
    (property "Val" "10u/25V")
    (property "Voltage" "")
    (attr smd)
    (fp_text reference "C126" (at -1.09 0.38 270) (layer "B.SilkS")
      (effects (font (size 0.7 0.7) (thickness 0.15)) (justify left bottom mirror))
    )
    (fp_text value "C_10u_25V_0603" (at 0 -1.6 270) (layer "B.Fab")
      (effects (font (size 0.7 0.7) (thickness 0.15)) (justify left bottom mirror))
    )
    (fp_text user "${REFERENCE}" (at -1.682 -3.895 270) (layer "B.Fab") hide
      (effects (font (size 0.7 0.7) (thickness 0.15)) (justify left bottom mirror))
    )
    (fp_text user "License: Apache-2.0" (at -1.682 -5.895 270) (layer "B.Fab") hide
      (effects (font (size 0.7 0.7) (thickness 0.15)) (justify left bottom mirror))
    )
    (fp_text user "Author: Antmicro" (at -1.682 -4.894 270) (layer "B.Fab") hide
      (effects (font (size 0.7 0.7) (thickness 0.15)) (justify left bottom mirror))
    )
    (fp_line (start -0.3 -0.3) (end 0.3 -0.3) (layer "B.SilkS") (width 0.15))
    (fp_line (start -0.3 0.3) (end 0.3 0.3) (layer "B.SilkS") (width 0.15))
    (fp_rect (start -1.24 0.7) (end 1.24 -0.7) (layer "B.CrtYd") (width 0.05) (fill none))
    (fp_rect (start -0.8 0.4) (end 0.8 -0.4) (layer "B.Fab") (width 0.15) (fill none))
    (pad "1" smd roundrect (at -0.7 0 90) (size 0.6 0.8) (layers "B.Cu" "B.Paste" "B.Mask") (roundrect_rratio 0.2)
      (net 74 "VDD") (pintype "passive"))
    (pad "2" smd roundrect (at 0.7 0 90) (size 0.6 0.8) (layers "B.Cu" "B.Paste" "B.Mask") (roundrect_rratio 0.2)
      (net 1 "GND") (pintype "passive"))
  )

  (footprint "sa800u-baseboard-hw-footprints:C_0805_2012Metric" (layer "B.Cu")
    (tedit 5FD9C126)
    (at 75.3 101.9 90)
    (descr "Capacitor SMD 0805")
    (tags "capacitor SMD 0805")
    (property "Author" "Antmicro")
    (property "Dielectric" "")
    (property "License" "Apache-2.0")
    (property "MPN" "GRM21BR60J107ME15L")
    (property "Manufacturer" "Murata")
    (property "Sheetfile" "poe.kicad_sch")
    (property "Sheetname" "PoE")
    (property "Val" "100u")
    (property "Voltage" "")
    (attr smd)
    (fp_text reference "C147" (at 4.48 0.35 270) (layer "B.SilkS")
      (effects (font (size 0.7 0.7) (thickness 0.15)) (justify left bottom mirror))
    )
    (fp_text value "C_100u_0805" (at 0 -1.947 270) (layer "B.Fab")
      (effects (font (size 0.7 0.7) (thickness 0.15)) (justify left bottom mirror))
    )
    (fp_text user "Author: Antmicro" (at -1.9 -5.947 270) (layer "B.Fab") hide
      (effects (font (size 0.7 0.7) (thickness 0.15)) (justify left bottom mirror))
    )
    (fp_text user "${REFERENCE}" (at -1.9 -3.947 270) (layer "B.Fab") hide
      (effects (font (size 0.7 0.7) (thickness 0.15)) (justify left bottom mirror))
    )
    (fp_text user "License: Apache-2.0" (at -1.9 -4.947 270) (layer "B.Fab") hide
      (effects (font (size 0.7 0.7) (thickness 0.15)) (justify left bottom mirror))
    )
    (fp_line (start -0.3 -0.8) (end 0.3 -0.8) (layer "B.SilkS") (width 0.15))
    (fp_line (start -0.3 0.8) (end 0.3 0.8) (layer "B.SilkS") (width 0.15))
    (fp_rect (start -1.9 0.93) (end 1.9 -0.93) (layer "B.CrtYd") (width 0.05) (fill none))
    (fp_rect (start -0.95 0.675) (end 0.95 -0.675) (layer "B.Fab") (width 0.15) (fill none))
    (pad "1" smd rect (at -1.05 0 90) (size 1.2 1.2) (layers "B.Cu" "B.Paste" "B.Mask")
      (net 136 "5V_POE") (pintype "passive"))
    (pad "2" smd rect (at 1.05 0 90) (size 1.2 1.2) (layers "B.Cu" "B.Paste" "B.Mask")
      (net 1 "GND") (pintype "passive"))
  )

  (footprint "sa800u-baseboard-hw-footprints:C_0603_1608Metric" (layer "B.Cu")
    (tedit 5D5E94D2)
    (at 84.15 127.6 90)
    (descr "Capacitor SMD 0603")
    (tags "capacitor 0603")
    (property "Author" "Antmicro")
    (property "Dielectric" "")
    (property "License" "Apache-2.0")
    (property "MPN" "C1608X5R1E106M080AC")
    (property "Manufacturer" "TDK")
    (property "Sheetfile" "psu.kicad_sch")
    (property "Sheetname" "PSU")
    (property "Val" "10u/25V")
    (property "Voltage" "")
    (attr smd)
    (fp_text reference "C127" (at -1.09 0.38 270) (layer "B.SilkS")
      (effects (font (size 0.7 0.7) (thickness 0.15)) (justify left bottom mirror))
    )
    (fp_text value "C_10u_25V_0603" (at 0 -1.6 270) (layer "B.Fab")
      (effects (font (size 0.7 0.7) (thickness 0.15)) (justify left bottom mirror))
    )
    (fp_text user "Author: Antmicro" (at -1.682 -4.894 270) (layer "B.Fab") hide
      (effects (font (size 0.7 0.7) (thickness 0.15)) (justify left bottom mirror))
    )
    (fp_text user "License: Apache-2.0" (at -1.682 -5.895 270) (layer "B.Fab") hide
      (effects (font (size 0.7 0.7) (thickness 0.15)) (justify left bottom mirror))
    )
    (fp_text user "${REFERENCE}" (at -1.682 -3.895 270) (layer "B.Fab") hide
      (effects (font (size 0.7 0.7) (thickness 0.15)) (justify left bottom mirror))
    )
    (fp_line (start -0.3 0.3) (end 0.3 0.3) (layer "B.SilkS") (width 0.15))
    (fp_line (start -0.3 -0.3) (end 0.3 -0.3) (layer "B.SilkS") (width 0.15))
    (fp_rect (start -1.24 0.7) (end 1.24 -0.7) (layer "B.CrtYd") (width 0.05) (fill none))
    (fp_rect (start -0.8 0.4) (end 0.8 -0.4) (layer "B.Fab") (width 0.15) (fill none))
    (pad "1" smd roundrect (at -0.7 0 90) (size 0.6 0.8) (layers "B.Cu" "B.Paste" "B.Mask") (roundrect_rratio 0.2)
      (net 74 "VDD") (pintype "passive"))
    (pad "2" smd roundrect (at 0.7 0 90) (size 0.6 0.8) (layers "B.Cu" "B.Paste" "B.Mask") (roundrect_rratio 0.2)
      (net 1 "GND") (pintype "passive"))
  )

  (footprint "sa800u-baseboard-hw-footprints:R_0402_1005Metric" (layer "B.Cu")
    (tedit 5FD9C158)
    (at 122.84 93.8 -90)
    (descr "Resistor SMD 0402")
    (tags "resistor SMD 0402")
    (property "Author" "Antmicro")
    (property "License" "Apache-2.0")
    (property "MPN" "CR0402-FX-33R0GLF")
    (property "Manufacturer" "Bourns")
    (property "Sheetfile" "other-interfaces.kicad_sch")
    (property "Sheetname" "Other Interfaces")
    (property "Tolerance" "1%")
    (property "Val" "33R")
    (attr smd)
    (fp_text reference "R102" (at 0.86 -0.47 90) (layer "B.SilkS")
      (effects (font (size 0.7 0.7) (thickness 0.15)) (justify left bottom mirror))
    )
    (fp_text value "R_33R_0402" (at 0 -1.4 90) (layer "B.Fab")
      (effects (font (size 0.7 0.7) (thickness 0.15)) (justify left bottom mirror))
    )
    (fp_text user "License: Apache-2.0" (at -0.95 -5.169 90) (layer "B.Fab") hide
      (effects (font (size 0.7 0.7) (thickness 0.15)) (justify left bottom mirror))
    )
    (fp_text user "Author: Antmicro" (at -0.95 -4.169 90) (layer "B.Fab") hide
      (effects (font (size 0.7 0.7) (thickness 0.15)) (justify left bottom mirror))
    )
    (fp_text user "${REFERENCE}" (at -0.95 -3.168 90) (layer "B.Fab") hide
      (effects (font (size 0.7 0.7) (thickness 0.15)) (justify left bottom mirror))
    )
    (fp_rect (start -0.93 0.47) (end 0.93 -0.47) (layer "B.CrtYd") (width 0.05) (fill none))
    (fp_rect (start -0.5 0.25) (end 0.5 -0.25) (layer "B.Fab") (width 0.15) (fill none))
    (pad "1" smd roundrect (at -0.485 0 270) (size 0.59 0.64) (layers "B.Cu" "B.Paste" "B.Mask") (roundrect_rratio 0.25)
      (net 117 "SD_DATA1") (pintype "passive"))
    (pad "2" smd roundrect (at 0.485 0 270) (size 0.59 0.64) (layers "B.Cu" "B.Paste" "B.Mask") (roundrect_rratio 0.25)
      (net 251 "/Other Interfaces/SD_DATA1_R") (pintype "passive"))
  )

  (footprint "sa800u-baseboard-hw-footprints:R_0402_1005Metric" (layer "B.Cu")
    (tedit 5FD9C158)
    (at 119.9 93.8 -90)
    (descr "Resistor SMD 0402")
    (tags "resistor SMD 0402")
    (property "Author" "Antmicro")
    (property "License" "Apache-2.0")
    (property "MPN" "CR0402-FX-33R0GLF")
    (property "Manufacturer" "Bourns")
    (property "Sheetfile" "other-interfaces.kicad_sch")
    (property "Sheetname" "Other Interfaces")
    (property "Tolerance" "1%")
    (property "Val" "33R")
    (attr smd)
    (fp_text reference "R100" (at 0.87 -0.38 90) (layer "B.SilkS")
      (effects (font (size 0.7 0.7) (thickness 0.15)) (justify left bottom mirror))
    )
    (fp_text value "R_33R_0402" (at 0 -1.4 90) (layer "B.Fab")
      (effects (font (size 0.7 0.7) (thickness 0.15)) (justify left bottom mirror))
    )
    (fp_text user "Author: Antmicro" (at -0.95 -4.169 90) (layer "B.Fab") hide
      (effects (font (size 0.7 0.7) (thickness 0.15)) (justify left bottom mirror))
    )
    (fp_text user "${REFERENCE}" (at -0.95 -3.168 90) (layer "B.Fab") hide
      (effects (font (size 0.7 0.7) (thickness 0.15)) (justify left bottom mirror))
    )
    (fp_text user "License: Apache-2.0" (at -0.95 -5.169 90) (layer "B.Fab") hide
      (effects (font (size 0.7 0.7) (thickness 0.15)) (justify left bottom mirror))
    )
    (fp_rect (start -0.93 0.47) (end 0.93 -0.47) (layer "B.CrtYd") (width 0.05) (fill none))
    (fp_rect (start -0.5 0.25) (end 0.5 -0.25) (layer "B.Fab") (width 0.15) (fill none))
    (pad "1" smd roundrect (at -0.485 0 270) (size 0.59 0.64) (layers "B.Cu" "B.Paste" "B.Mask") (roundrect_rratio 0.25)
      (net 116 "SD_CLK") (pintype "passive"))
    (pad "2" smd roundrect (at 0.485 0 270) (size 0.59 0.64) (layers "B.Cu" "B.Paste" "B.Mask") (roundrect_rratio 0.25)
      (net 250 "/Other Interfaces/SD_CLK_R") (pintype "passive"))
  )

  (footprint "sa800u-baseboard-hw-footprints:R_0402_1005Metric" (layer "B.Cu")
    (tedit 5FD9C158)
    (at 120.9 93.8 -90)
    (descr "Resistor SMD 0402")
    (tags "resistor SMD 0402")
    (property "Author" "Antmicro")
    (property "License" "Apache-2.0")
    (property "MPN" "CR0402-FX-33R0GLF")
    (property "Manufacturer" "Bourns")
    (property "Sheetfile" "other-interfaces.kicad_sch")
    (property "Sheetname" "Other Interfaces")
    (property "Tolerance" "1%")
    (property "Val" "33R")
    (attr smd)
    (fp_text reference "R101" (at 0.87 -0.38 90) (layer "B.SilkS")
      (effects (font (size 0.7 0.7) (thickness 0.15)) (justify left bottom mirror))
    )
    (fp_text value "R_33R_0402" (at 0 -1.4 90) (layer "B.Fab")
      (effects (font (size 0.7 0.7) (thickness 0.15)) (justify left bottom mirror))
    )
    (fp_text user "${REFERENCE}" (at -0.95 -3.168 90) (layer "B.Fab") hide
      (effects (font (size 0.7 0.7) (thickness 0.15)) (justify left bottom mirror))
    )
    (fp_text user "License: Apache-2.0" (at -0.95 -5.169 90) (layer "B.Fab") hide
      (effects (font (size 0.7 0.7) (thickness 0.15)) (justify left bottom mirror))
    )
    (fp_text user "Author: Antmicro" (at -0.95 -4.169 90) (layer "B.Fab") hide
      (effects (font (size 0.7 0.7) (thickness 0.15)) (justify left bottom mirror))
    )
    (fp_rect (start -0.93 0.47) (end 0.93 -0.47) (layer "B.CrtYd") (width 0.05) (fill none))
    (fp_rect (start -0.5 0.25) (end 0.5 -0.25) (layer "B.Fab") (width 0.15) (fill none))
    (pad "1" smd roundrect (at -0.485 0 270) (size 0.59 0.64) (layers "B.Cu" "B.Paste" "B.Mask") (roundrect_rratio 0.25)
      (net 118 "SD_DATA0") (pintype "passive"))
    (pad "2" smd roundrect (at 0.485 0 270) (size 0.59 0.64) (layers "B.Cu" "B.Paste" "B.Mask") (roundrect_rratio 0.25)
      (net 252 "/Other Interfaces/SD_DATA0_R") (pintype "passive"))
  )

  (footprint "sa800u-baseboard-hw-footprints:SC70-3" (layer "B.Cu")
    (tedit 615FF353)
    (at 146.8 138.2 -90)
    (property "Author" "Antmicro")
    (property "License" "Apache-2.0")
    (property "MPN" "BSS138PW")
    (property "Manufacturer" "Nexperia")
    (property "Sheetfile" "som.kicad_sch")
    (property "Sheetname" "SoM")
    (attr smd)
    (fp_text reference "Q5" (at 0 1.6 90) (layer "B.SilkS")
      (effects (font (size 0.7 0.7) (thickness 0.15)) (justify left bottom mirror))
    )
    (fp_text value "BSS138PW" (at 0 -2.3 90) (layer "B.Fab")
      (effects (font (size 0.7 0.7) (thickness 0.15)) (justify left bottom mirror))
    )
    (fp_text user "License: Apache-2.0" (at -1.45 -6.782 90) (layer "B.Fab") hide
      (effects (font (size 0.7 0.7) (thickness 0.15)) (justify left bottom mirror))
    )
    (fp_text user "${REFERENCE}" (at -1.45 -4.783 90) (layer "B.Fab") hide
      (effects (font (size 0.7 0.7) (thickness 0.15)) (justify left bottom mirror))
    )
    (fp_text user "Author: Antmicro" (at -1.45 -5.782 90) (layer "B.Fab") hide
      (effects (font (size 0.7 0.7) (thickness 0.15)) (justify left bottom mirror))
    )
    (fp_line (start 0.627 -0.6) (end 0.627 -1.001) (layer "B.SilkS") (width 0.15))
    (fp_line (start 0.627 0.6) (end 0.627 0.999) (layer "B.SilkS") (width 0.15))
    (fp_line (start -0.3 -1) (end 0.627 -1.001) (layer "B.SilkS") (width 0.15))
    (fp_line (start -0.3 1) (end 0.627 0.999) (layer "B.SilkS") (width 0.15))
    (fp_line (start -0.9 -1.3) (end -0.9 -1) (layer "B.CrtYd") (width 0.05))
    (fp_line (start -1.4 -1) (end -1.4 1) (layer "B.CrtYd") (width 0.05))
    (fp_line (start 0.9 1.3) (end 0.9 0.4) (layer "B.CrtYd") (width 0.05))
    (fp_line (start -0.9 -1) (end -1.4 -1) (layer "B.CrtYd") (width 0.05))
    (fp_line (start 1.4 0.4) (end 1.4 -0.4) (layer "B.CrtYd") (width 0.05))
    (fp_line (start 0.9 -1.3) (end -0.9 -1.3) (layer "B.CrtYd") (width 0.05))
    (fp_line (start -0.9 1.3) (end 0.9 1.3) (layer "B.CrtYd") (width 0.05))
    (fp_line (start 0.9 0.4) (end 1.4 0.4) (layer "B.CrtYd") (width 0.05))
    (fp_line (start -0.9 1) (end -1.4 1) (layer "B.CrtYd") (width 0.05))
    (fp_line (start 1.4 -0.4) (end 0.9 -0.4) (layer "B.CrtYd") (width 0.05))
    (fp_line (start 0.9 -0.4) (end 0.9 -1.3) (layer "B.CrtYd") (width 0.05))
    (fp_line (start -0.9 1.3) (end -0.9 1) (layer "B.CrtYd") (width 0.05))
    (fp_rect (start -0.623 0.999) (end 0.627 -1.001) (layer "B.Fab") (width 0.15) (fill none))
    (pad "1" smd rect (at -1.051 0.65 180) (size 0.6 0.6) (layers "B.Cu" "B.Paste" "B.Mask")
      (net 349 "/SoM/BOOT") (pinfunction "G") (pintype "bidirectional"))
    (pad "2" smd rect (at -1.051 -0.65 180) (size 0.6 0.6) (layers "B.Cu" "B.Paste" "B.Mask")
      (net 1 "GND") (pinfunction "S") (pintype "bidirectional"))
    (pad "3" smd rect (at 1.05 0 180) (size 0.6 0.6) (layers "B.Cu" "B.Paste" "B.Mask")
      (net 385 "Net-(Q5-Pad3)") (pinfunction "D") (pintype "bidirectional"))
  )

  (footprint "sa800u-baseboard-hw-footprints:SC70-3" (layer "B.Cu")
    (tedit 615FF353)
    (at 150.35 142.75 90)
    (property "Author" "Antmicro")
    (property "License" "Apache-2.0")
    (property "MPN" "BSS138PW")
    (property "Manufacturer" "Nexperia")
    (property "Sheetfile" "som.kicad_sch")
    (property "Sheetname" "SoM")
    (attr smd)
    (fp_text reference "Q6" (at 0.7 -1.31 270) (layer "B.SilkS")
      (effects (font (size 0.7 0.7) (thickness 0.15)) (justify left bottom mirror))
    )
    (fp_text value "BSS138PW" (at 0 -2.3 270) (layer "B.Fab")
      (effects (font (size 0.7 0.7) (thickness 0.15)) (justify left bottom mirror))
    )
    (fp_text user "Author: Antmicro" (at -1.45 -5.782 270) (layer "B.Fab") hide
      (effects (font (size 0.7 0.7) (thickness 0.15)) (justify left bottom mirror))
    )
    (fp_text user "${REFERENCE}" (at -1.45 -4.783 270) (layer "B.Fab") hide
      (effects (font (size 0.7 0.7) (thickness 0.15)) (justify left bottom mirror))
    )
    (fp_text user "License: Apache-2.0" (at -1.45 -6.782 270) (layer "B.Fab") hide
      (effects (font (size 0.7 0.7) (thickness 0.15)) (justify left bottom mirror))
    )
    (fp_line (start -0.3 -1) (end 0.627 -1.001) (layer "B.SilkS") (width 0.15))
    (fp_line (start 0.627 -0.6) (end 0.627 -1.001) (layer "B.SilkS") (width 0.15))
    (fp_line (start 0.627 0.6) (end 0.627 0.999) (layer "B.SilkS") (width 0.15))
    (fp_line (start -0.3 1) (end 0.627 0.999) (layer "B.SilkS") (width 0.15))
    (fp_line (start -0.9 1) (end -1.4 1) (layer "B.CrtYd") (width 0.05))
    (fp_line (start 0.9 0.4) (end 1.4 0.4) (layer "B.CrtYd") (width 0.05))
    (fp_line (start 0.9 -0.4) (end 0.9 -1.3) (layer "B.CrtYd") (width 0.05))
    (fp_line (start -1.4 -1) (end -1.4 1) (layer "B.CrtYd") (width 0.05))
    (fp_line (start -0.9 1.3) (end 0.9 1.3) (layer "B.CrtYd") (width 0.05))
    (fp_line (start 1.4 0.4) (end 1.4 -0.4) (layer "B.CrtYd") (width 0.05))
    (fp_line (start 0.9 -1.3) (end -0.9 -1.3) (layer "B.CrtYd") (width 0.05))
    (fp_line (start 0.9 1.3) (end 0.9 0.4) (layer "B.CrtYd") (width 0.05))
    (fp_line (start -0.9 -1.3) (end -0.9 -1) (layer "B.CrtYd") (width 0.05))
    (fp_line (start -0.9 1.3) (end -0.9 1) (layer "B.CrtYd") (width 0.05))
    (fp_line (start -0.9 -1) (end -1.4 -1) (layer "B.CrtYd") (width 0.05))
    (fp_line (start 1.4 -0.4) (end 0.9 -0.4) (layer "B.CrtYd") (width 0.05))
    (fp_rect (start -0.623 0.999) (end 0.627 -1.001) (layer "B.Fab") (width 0.15) (fill none))
    (pad "1" smd rect (at -1.051 0.65) (size 0.6 0.6) (layers "B.Cu" "B.Paste" "B.Mask")
      (net 132 "VREG_S4A_1V8") (pinfunction "G") (pintype "bidirectional"))
    (pad "2" smd rect (at -1.051 -0.65) (size 0.6 0.6) (layers "B.Cu" "B.Paste" "B.Mask")
      (net 1 "GND") (pinfunction "S") (pintype "bidirectional"))
    (pad "3" smd rect (at 1.05 0) (size 0.6 0.6) (layers "B.Cu" "B.Paste" "B.Mask")
      (net 386 "Net-(Q6-Pad3)") (pinfunction "D") (pintype "bidirectional"))
  )

  (footprint "sa800u-baseboard-hw-footprints:SC70-3" (layer "B.Cu")
    (tedit 615FF353)
    (at 146.8 135.23 -90)
    (property "Author" "Antmicro")
    (property "License" "Apache-2.0")
    (property "MPN" "BSS138PW")
    (property "Manufacturer" "Nexperia")
    (property "Sheetfile" "som.kicad_sch")
    (property "Sheetname" "SoM")
    (attr smd)
    (fp_text reference "Q7" (at 0 1.6 90) (layer "B.SilkS")
      (effects (font (size 0.7 0.7) (thickness 0.15)) (justify left bottom mirror))
    )
    (fp_text value "BSS138PW" (at 0 -2.3 90) (layer "B.Fab")
      (effects (font (size 0.7 0.7) (thickness 0.15)) (justify left bottom mirror))
    )
    (fp_text user "License: Apache-2.0" (at -1.45 -6.782 90) (layer "B.Fab") hide
      (effects (font (size 0.7 0.7) (thickness 0.15)) (justify left bottom mirror))
    )
    (fp_text user "${REFERENCE}" (at -1.45 -4.783 90) (layer "B.Fab") hide
      (effects (font (size 0.7 0.7) (thickness 0.15)) (justify left bottom mirror))
    )
    (fp_text user "Author: Antmicro" (at -1.45 -5.782 90) (layer "B.Fab") hide
      (effects (font (size 0.7 0.7) (thickness 0.15)) (justify left bottom mirror))
    )
    (fp_line (start -0.3 -1) (end 0.627 -1.001) (layer "B.SilkS") (width 0.15))
    (fp_line (start 0.627 -0.6) (end 0.627 -1.001) (layer "B.SilkS") (width 0.15))
    (fp_line (start -0.3 1) (end 0.627 0.999) (layer "B.SilkS") (width 0.15))
    (fp_line (start 0.627 0.6) (end 0.627 0.999) (layer "B.SilkS") (width 0.15))
    (fp_line (start 0.9 -1.3) (end -0.9 -1.3) (layer "B.CrtYd") (width 0.05))
    (fp_line (start 0.9 1.3) (end 0.9 0.4) (layer "B.CrtYd") (width 0.05))
    (fp_line (start -1.4 -1) (end -1.4 1) (layer "B.CrtYd") (width 0.05))
    (fp_line (start -0.9 -1.3) (end -0.9 -1) (layer "B.CrtYd") (width 0.05))
    (fp_line (start 1.4 -0.4) (end 0.9 -0.4) (layer "B.CrtYd") (width 0.05))
    (fp_line (start 1.4 0.4) (end 1.4 -0.4) (layer "B.CrtYd") (width 0.05))
    (fp_line (start 0.9 -0.4) (end 0.9 -1.3) (layer "B.CrtYd") (width 0.05))
    (fp_line (start 0.9 0.4) (end 1.4 0.4) (layer "B.CrtYd") (width 0.05))
    (fp_line (start -0.9 1.3) (end 0.9 1.3) (layer "B.CrtYd") (width 0.05))
    (fp_line (start -0.9 1.3) (end -0.9 1) (layer "B.CrtYd") (width 0.05))
    (fp_line (start -0.9 -1) (end -1.4 -1) (layer "B.CrtYd") (width 0.05))
    (fp_line (start -0.9 1) (end -1.4 1) (layer "B.CrtYd") (width 0.05))
    (fp_rect (start -0.623 0.999) (end 0.627 -1.001) (layer "B.Fab") (width 0.15) (fill none))
    (pad "1" smd rect (at -1.051 0.65 180) (size 0.6 0.6) (layers "B.Cu" "B.Paste" "B.Mask")
      (net 350 "/SoM/USER_LED") (pinfunction "G") (pintype "bidirectional"))
    (pad "2" smd rect (at -1.051 -0.65 180) (size 0.6 0.6) (layers "B.Cu" "B.Paste" "B.Mask")
      (net 1 "GND") (pinfunction "S") (pintype "bidirectional"))
    (pad "3" smd rect (at 1.05 0 180) (size 0.6 0.6) (layers "B.Cu" "B.Paste" "B.Mask")
      (net 387 "Net-(Q7-Pad3)") (pinfunction "D") (pintype "bidirectional"))
  )

  (footprint "sa800u-baseboard-hw-footprints:C_0402_1005Metric" (layer "B.Cu")
    (tedit 616D63CF)
    (at 144.6 121.4 -90)
    (descr "Capacitor SMD 0402")
    (tags "capacitor SMD 0402")
    (property "Author" "Antmicro")
    (property "DNP" "DNP")
    (property "Dielectric" "")
    (property "License" "Apache-2.0")
    (property "MPN" "CC0402MRX5R5BB106")
    (property "Manufacturer" "Yaego")
    (property "Sheetfile" "hdmi-converter.kicad_sch")
    (property "Sheetname" "HDMI converter")
    (property "Val" "10u")
    (property "Voltage" "")
    (attr exclude_from_pos_files)
    (fp_text reference "C24" (at -3.08 -0.46 90) (layer "B.SilkS")
      (effects (font (size 0.7 0.7) (thickness 0.15)) (justify left bottom mirror))
    )
    (fp_text value "C_10u_0402" (at 0 -1.4 90) (layer "B.Fab")
      (effects (font (size 0.7 0.7) (thickness 0.15)) (justify left bottom mirror))
    )
    (fp_text user "${REFERENCE}" (at -0.932 -3.168 90) (layer "B.Fab") hide
      (effects (font (size 0.7 0.7) (thickness 0.15)) (justify left bottom mirror))
    )
    (fp_text user "Author: Antmicro" (at -0.932 -4.17 90) (layer "B.Fab") hide
      (effects (font (size 0.7 0.7) (thickness 0.15)) (justify left bottom mirror))
    )
    (fp_text user "License: Apache-2.0" (at -0.932 -5.17 90) (layer "B.Fab") hide
      (effects (font (size 0.7 0.7) (thickness 0.15)) (justify left bottom mirror))
    )
    (fp_rect (start -0.94 0.47) (end 0.94 -0.47) (layer "B.CrtYd") (width 0.05) (fill none))
    (fp_rect (start -0.499 0.249) (end 0.499 -0.249) (layer "B.Fab") (width 0.15) (fill none))
    (pad "1" smd roundrect (at -0.484 0 270) (size 0.59 0.64) (layers "B.Cu" "B.Paste" "B.Mask") (roundrect_rratio 0.25)
      (net 189 "/HDMI converter/LT9611_VCC12_RX") (pintype "passive"))
    (pad "2" smd roundrect (at 0.484 0 270) (size 0.59 0.64) (layers "B.Cu" "B.Paste" "B.Mask") (roundrect_rratio 0.25)
      (net 1 "GND") (pintype "passive"))
  )

  (footprint "sa800u-baseboard-hw-footprints:R_0402_1005Metric" (layer "B.Cu")
    (tedit 5FD9C158)
    (at 133.485 133.5)
    (descr "Resistor SMD 0402")
    (tags "resistor SMD 0402")
    (property "Author" "Antmicro")
    (property "License" "Apache-2.0")
    (property "MPN" "CR0402-FX-1002GLF")
    (property "Manufacturer" "Bourns")
    (property "Sheetfile" "hdmi-converter.kicad_sch")
    (property "Sheetname" "HDMI converter")
    (property "Tolerance" "1%")
    (property "Val" "10k")
    (attr smd)
    (fp_text reference "R50" (at 0.955 -0.59 180) (layer "B.SilkS")
      (effects (font (size 0.7 0.7) (thickness 0.15)) (justify left bottom mirror))
    )
    (fp_text value "R_10k_0402" (at 0 -1.4 180) (layer "B.Fab")
      (effects (font (size 0.7 0.7) (thickness 0.15)) (justify left bottom mirror))
    )
    (fp_text user "Author: Antmicro" (at -0.95 -4.169 180) (layer "B.Fab") hide
      (effects (font (size 0.7 0.7) (thickness 0.15)) (justify left bottom mirror))
    )
    (fp_text user "${REFERENCE}" (at -0.95 -3.168 180) (layer "B.Fab") hide
      (effects (font (size 0.7 0.7) (thickness 0.15)) (justify left bottom mirror))
    )
    (fp_text user "License: Apache-2.0" (at -0.95 -5.169 180) (layer "B.Fab") hide
      (effects (font (size 0.7 0.7) (thickness 0.15)) (justify left bottom mirror))
    )
    (fp_rect (start -0.93 0.47) (end 0.93 -0.47) (layer "B.CrtYd") (width 0.05) (fill none))
    (fp_rect (start -0.5 0.25) (end 0.5 -0.25) (layer "B.Fab") (width 0.15) (fill none))
    (pad "1" smd roundrect (at -0.485 0) (size 0.59 0.64) (layers "B.Cu" "B.Paste" "B.Mask") (roundrect_rratio 0.25)
      (net 131 "3V3_SYS") (pintype "passive"))
    (pad "2" smd roundrect (at 0.485 0) (size 0.59 0.64) (layers "B.Cu" "B.Paste" "B.Mask") (roundrect_rratio 0.25)
      (net 155 "Net-(Q4-Pad1)") (pintype "passive"))
  )

  (footprint "sa800u-baseboard-hw-footprints:C_0402_1005Metric" (layer "B.Cu")
    (tedit 616D63CF)
    (at 142.55 121.4 -90)
    (descr "Capacitor SMD 0402")
    (tags "capacitor SMD 0402")
    (property "Author" "Antmicro")
    (property "Dielectric" "X5R")
    (property "License" "Apache-2.0")
    (property "MPN" "GRM155R61H104KE14D")
    (property "Manufacturer" "Murata")
    (property "Sheetfile" "hdmi-converter.kicad_sch")
    (property "Sheetname" "HDMI converter")
    (property "Val" "100n")
    (property "Voltage" "50V")
    (attr smd)
    (fp_text reference "C27" (at -3.08 -0.46 90) (layer "B.SilkS")
      (effects (font (size 0.7 0.7) (thickness 0.15)) (justify left bottom mirror))
    )
    (fp_text value "C_100n_0402" (at 0 -1.4 90) (layer "B.Fab")
      (effects (font (size 0.7 0.7) (thickness 0.15)) (justify left bottom mirror))
    )
    (fp_text user "Author: Antmicro" (at -0.932 -4.17 90) (layer "B.Fab") hide
      (effects (font (size 0.7 0.7) (thickness 0.15)) (justify left bottom mirror))
    )
    (fp_text user "License: Apache-2.0" (at -0.932 -5.17 90) (layer "B.Fab") hide
      (effects (font (size 0.7 0.7) (thickness 0.15)) (justify left bottom mirror))
    )
    (fp_text user "${REFERENCE}" (at -0.932 -3.168 90) (layer "B.Fab") hide
      (effects (font (size 0.7 0.7) (thickness 0.15)) (justify left bottom mirror))
    )
    (fp_rect (start -0.94 0.47) (end 0.94 -0.47) (layer "B.CrtYd") (width 0.05) (fill none))
    (fp_rect (start -0.499 0.249) (end 0.499 -0.249) (layer "B.Fab") (width 0.15) (fill none))
    (pad "1" smd roundrect (at -0.484 0 270) (size 0.59 0.64) (layers "B.Cu" "B.Paste" "B.Mask") (roundrect_rratio 0.25)
      (net 189 "/HDMI converter/LT9611_VCC12_RX") (pintype "passive"))
    (pad "2" smd roundrect (at 0.484 0 270) (size 0.59 0.64) (layers "B.Cu" "B.Paste" "B.Mask") (roundrect_rratio 0.25)
      (net 1 "GND") (pintype "passive"))
  )

  (footprint "sa800u-baseboard-hw-footprints:SC70-3" (layer "B.Cu")
    (tedit 615FF353)
    (at 134.6 135.4 -90)
    (property "Author" "Antmicro")
    (property "License" "Apache-2.0")
    (property "MPN" "BSS138PW")
    (property "Manufacturer" "Nexperia")
    (property "Sheetfile" "hdmi-converter.kicad_sch")
    (property "Sheetname" "HDMI converter")
    (attr smd)
    (fp_text reference "Q4" (at 0.71 0.59 90) (layer "B.SilkS")
      (effects (font (size 0.7 0.7) (thickness 0.15)) (justify left bottom mirror))
    )
    (fp_text value "BSS138PW" (at 0 -2.3 90) (layer "B.Fab")
      (effects (font (size 0.7 0.7) (thickness 0.15)) (justify left bottom mirror))
    )
    (fp_text user "${REFERENCE}" (at -1.45 -4.783 90) (layer "B.Fab") hide
      (effects (font (size 0.7 0.7) (thickness 0.15)) (justify left bottom mirror))
    )
    (fp_text user "Author: Antmicro" (at -1.45 -5.782 90) (layer "B.Fab") hide
      (effects (font (size 0.7 0.7) (thickness 0.15)) (justify left bottom mirror))
    )
    (fp_text user "License: Apache-2.0" (at -1.45 -6.782 90) (layer "B.Fab") hide
      (effects (font (size 0.7 0.7) (thickness 0.15)) (justify left bottom mirror))
    )
    (fp_line (start -0.3 1) (end 0.627 0.999) (layer "B.SilkS") (width 0.15))
    (fp_line (start -0.3 -1) (end 0.627 -1.001) (layer "B.SilkS") (width 0.15))
    (fp_line (start 0.627 -0.6) (end 0.627 -1.001) (layer "B.SilkS") (width 0.15))
    (fp_line (start 0.627 0.6) (end 0.627 0.999) (layer "B.SilkS") (width 0.15))
    (fp_line (start 0.9 0.4) (end 1.4 0.4) (layer "B.CrtYd") (width 0.05))
    (fp_line (start 1.4 0.4) (end 1.4 -0.4) (layer "B.CrtYd") (width 0.05))
    (fp_line (start -0.9 1.3) (end -0.9 1) (layer "B.CrtYd") (width 0.05))
    (fp_line (start -0.9 -1) (end -1.4 -1) (layer "B.CrtYd") (width 0.05))
    (fp_line (start 0.9 -1.3) (end -0.9 -1.3) (layer "B.CrtYd") (width 0.05))
    (fp_line (start -0.9 1) (end -1.4 1) (layer "B.CrtYd") (width 0.05))
    (fp_line (start 1.4 -0.4) (end 0.9 -0.4) (layer "B.CrtYd") (width 0.05))
    (fp_line (start -1.4 -1) (end -1.4 1) (layer "B.CrtYd") (width 0.05))
    (fp_line (start -0.9 -1.3) (end -0.9 -1) (layer "B.CrtYd") (width 0.05))
    (fp_line (start -0.9 1.3) (end 0.9 1.3) (layer "B.CrtYd") (width 0.05))
    (fp_line (start 0.9 -0.4) (end 0.9 -1.3) (layer "B.CrtYd") (width 0.05))
    (fp_line (start 0.9 1.3) (end 0.9 0.4) (layer "B.CrtYd") (width 0.05))
    (fp_rect (start -0.623 0.999) (end 0.627 -1.001) (layer "B.Fab") (width 0.15) (fill none))
    (pad "1" smd rect (at -1.051 0.65 180) (size 0.6 0.6) (layers "B.Cu" "B.Paste" "B.Mask")
      (net 155 "Net-(Q4-Pad1)") (pinfunction "G") (pintype "bidirectional"))
    (pad "2" smd rect (at -1.051 -0.65 180) (size 0.6 0.6) (layers "B.Cu" "B.Paste" "B.Mask")
      (net 1 "GND") (pinfunction "S") (pintype "bidirectional"))
    (pad "3" smd rect (at 1.05 0 180) (size 0.6 0.6) (layers "B.Cu" "B.Paste" "B.Mask")
      (net 209 "/HDMI converter/VCOM") (pinfunction "D") (pintype "bidirectional"))
  )

  (footprint "sa800u-baseboard-hw-footprints:C_0402_1005Metric" (layer "B.Cu")
    (tedit 616D63CF)
    (at 134.600003 123.066848 180)
    (descr "Capacitor SMD 0402")
    (tags "capacitor SMD 0402")
    (property "Author" "Antmicro")
    (property "Dielectric" "")
    (property "License" "Apache-2.0")
    (property "MPN" "C1005X6S1A105K050BC")
    (property "Manufacturer" "TDK")
    (property "Sheetfile" "hdmi-converter.kicad_sch")
    (property "Sheetname" "HDMI converter")
    (property "Val" "1u")
    (property "Voltage" "")
    (attr smd)
    (fp_text reference "C25" (at 0.820003 -0.453151) (layer "B.SilkS")
      (effects (font (size 0.7 0.7) (thickness 0.15)) (justify left bottom mirror))
    )
    (fp_text value "C_1u_0402" (at 0 -1.4) (layer "B.Fab")
      (effects (font (size 0.7 0.7) (thickness 0.15)) (justify left bottom mirror))
    )
    (fp_text user "Author: Antmicro" (at -0.932 -4.17) (layer "B.Fab") hide
      (effects (font (size 0.7 0.7) (thickness 0.15)) (justify left bottom mirror))
    )
    (fp_text user "${REFERENCE}" (at -0.932 -3.168) (layer "B.Fab") hide
      (effects (font (size 0.7 0.7) (thickness 0.15)) (justify left bottom mirror))
    )
    (fp_text user "License: Apache-2.0" (at -0.932 -5.17) (layer "B.Fab") hide
      (effects (font (size 0.7 0.7) (thickness 0.15)) (justify left bottom mirror))
    )
    (fp_rect (start -0.94 0.47) (end 0.94 -0.47) (layer "B.CrtYd") (width 0.05) (fill none))
    (fp_rect (start -0.499 0.249) (end 0.499 -0.249) (layer "B.Fab") (width 0.15) (fill none))
    (pad "1" smd roundrect (at -0.484 0 180) (size 0.59 0.64) (layers "B.Cu" "B.Paste" "B.Mask") (roundrect_rratio 0.25)
      (net 188 "/HDMI converter/LT9611_VDD12") (pintype "passive"))
    (pad "2" smd roundrect (at 0.484 0 180) (size 0.59 0.64) (layers "B.Cu" "B.Paste" "B.Mask") (roundrect_rratio 0.25)
      (net 1 "GND") (pintype "passive"))
  )

  (footprint "sa800u-baseboard-hw-footprints:C_0402_1005Metric" (layer "B.Cu")
    (tedit 616D63CF)
    (at 144.5 124.6 180)
    (descr "Capacitor SMD 0402")
    (tags "capacitor SMD 0402")
    (property "Author" "Antmicro")
    (property "Dielectric" "X5R")
    (property "License" "Apache-2.0")
    (property "MPN" "GRM155R61H104KE14D")
    (property "Manufacturer" "Murata")
    (property "Sheetfile" "hdmi-converter.kicad_sch")
    (property "Sheetname" "HDMI converter")
    (property "Val" "100n")
    (property "Voltage" "50V")
    (attr smd)
    (fp_text reference "C40" (at -2.94 -0.35) (layer "B.SilkS")
      (effects (font (size 0.7 0.7) (thickness 0.15)) (justify left bottom mirror))
    )
    (fp_text value "C_100n_0402" (at 0 -1.4) (layer "B.Fab")
      (effects (font (size 0.7 0.7) (thickness 0.15)) (justify left bottom mirror))
    )
    (fp_text user "License: Apache-2.0" (at -0.932 -5.17) (layer "B.Fab") hide
      (effects (font (size 0.7 0.7) (thickness 0.15)) (justify left bottom mirror))
    )
    (fp_text user "Author: Antmicro" (at -0.932 -4.17) (layer "B.Fab") hide
      (effects (font (size 0.7 0.7) (thickness 0.15)) (justify left bottom mirror))
    )
    (fp_text user "${REFERENCE}" (at -0.932 -3.168) (layer "B.Fab") hide
      (effects (font (size 0.7 0.7) (thickness 0.15)) (justify left bottom mirror))
    )
    (fp_rect (start -0.94 0.47) (end 0.94 -0.47) (layer "B.CrtYd") (width 0.05) (fill none))
    (fp_rect (start -0.499 0.249) (end 0.499 -0.249) (layer "B.Fab") (width 0.15) (fill none))
    (pad "1" smd roundrect (at -0.484 0 180) (size 0.59 0.64) (layers "B.Cu" "B.Paste" "B.Mask") (roundrect_rratio 0.25)
      (net 185 "/HDMI converter/LT9611_VCC33_RX") (pintype "passive"))
    (pad "2" smd roundrect (at 0.484 0 180) (size 0.59 0.64) (layers "B.Cu" "B.Paste" "B.Mask") (roundrect_rratio 0.25)
      (net 1 "GND") (pintype "passive"))
  )

  (footprint "sa800u-baseboard-hw-footprints:C_0402_1005Metric" (layer "B.Cu")
    (tedit 616D63CF)
    (at 143.55 121.4 -90)
    (descr "Capacitor SMD 0402")
    (tags "capacitor SMD 0402")
    (property "Author" "Antmicro")
    (property "Dielectric" "X5R")
    (property "License" "Apache-2.0")
    (property "MPN" "GRM155R61H104KE14D")
    (property "Manufacturer" "Murata")
    (property "Sheetfile" "hdmi-converter.kicad_sch")
    (property "Sheetname" "HDMI converter")
    (property "Val" "100n")
    (property "Voltage" "50V")
    (attr smd)
    (fp_text reference "C41" (at -3.08 -0.46 90) (layer "B.SilkS")
      (effects (font (size 0.7 0.7) (thickness 0.15)) (justify left bottom mirror))
    )
    (fp_text value "C_100n_0402" (at 0 -1.4 90) (layer "B.Fab")
      (effects (font (size 0.7 0.7) (thickness 0.15)) (justify left bottom mirror))
    )
    (fp_text user "${REFERENCE}" (at -0.932 -3.168 90) (layer "B.Fab") hide
      (effects (font (size 0.7 0.7) (thickness 0.15)) (justify left bottom mirror))
    )
    (fp_text user "Author: Antmicro" (at -0.932 -4.17 90) (layer "B.Fab") hide
      (effects (font (size 0.7 0.7) (thickness 0.15)) (justify left bottom mirror))
    )
    (fp_text user "License: Apache-2.0" (at -0.932 -5.17 90) (layer "B.Fab") hide
      (effects (font (size 0.7 0.7) (thickness 0.15)) (justify left bottom mirror))
    )
    (fp_rect (start -0.94 0.47) (end 0.94 -0.47) (layer "B.CrtYd") (width 0.05) (fill none))
    (fp_rect (start -0.499 0.249) (end 0.499 -0.249) (layer "B.Fab") (width 0.15) (fill none))
    (pad "1" smd roundrect (at -0.484 0 270) (size 0.59 0.64) (layers "B.Cu" "B.Paste" "B.Mask") (roundrect_rratio 0.25)
      (net 185 "/HDMI converter/LT9611_VCC33_RX") (pintype "passive"))
    (pad "2" smd roundrect (at 0.484 0 270) (size 0.59 0.64) (layers "B.Cu" "B.Paste" "B.Mask") (roundrect_rratio 0.25)
      (net 1 "GND") (pintype "passive"))
  )

  (footprint "sa800u-baseboard-hw-footprints:C_0603_1608Metric" (layer "B.Cu")
    (tedit 5D5E94D2)
    (at 129.56 126.46 180)
    (descr "Capacitor SMD 0603")
    (tags "capacitor 0603")
    (property "Author" "Antmicro")
    (property "Dielectric" "")
    (property "License" "Apache-2.0")
    (property "MPN" "GRM188R60J226MEA0D")
    (property "Manufacturer" "Murata")
    (property "Sheetfile" "psu.kicad_sch")
    (property "Sheetname" "PSU")
    (property "Val" "22u")
    (property "Voltage" "")
    (attr smd)
    (fp_text reference "C137" (at -1.44 -2.34) (layer "B.SilkS")
      (effects (font (size 0.7 0.7) (thickness 0.15)) (justify left bottom mirror))
    )
    (fp_text value "C_22u_0603" (at 0 -1.6) (layer "B.Fab")
      (effects (font (size 0.7 0.7) (thickness 0.15)) (justify left bottom mirror))
    )
    (fp_text user "License: Apache-2.0" (at -1.682 -5.895) (layer "B.Fab") hide
      (effects (font (size 0.7 0.7) (thickness 0.15)) (justify left bottom mirror))
    )
    (fp_text user "${REFERENCE}" (at -1.682 -3.895) (layer "B.Fab") hide
      (effects (font (size 0.7 0.7) (thickness 0.15)) (justify left bottom mirror))
    )
    (fp_text user "Author: Antmicro" (at -1.682 -4.894) (layer "B.Fab") hide
      (effects (font (size 0.7 0.7) (thickness 0.15)) (justify left bottom mirror))
    )
    (fp_line (start -0.3 -0.3) (end 0.3 -0.3) (layer "B.SilkS") (width 0.15))
    (fp_line (start -0.3 0.3) (end 0.3 0.3) (layer "B.SilkS") (width 0.15))
    (fp_rect (start -1.24 0.7) (end 1.24 -0.7) (layer "B.CrtYd") (width 0.05) (fill none))
    (fp_rect (start -0.8 0.4) (end 0.8 -0.4) (layer "B.Fab") (width 0.15) (fill none))
    (pad "1" smd roundrect (at -0.7 0 180) (size 0.6 0.8) (layers "B.Cu" "B.Paste" "B.Mask") (roundrect_rratio 0.2)
      (net 138 "1V2_SYS") (pintype "passive"))
    (pad "2" smd roundrect (at 0.7 0 180) (size 0.6 0.8) (layers "B.Cu" "B.Paste" "B.Mask") (roundrect_rratio 0.2)
      (net 1 "GND") (pintype "passive"))
  )

  (footprint "sa800u-baseboard-hw-footprints:C_0402_1005Metric" (layer "B.Cu")
    (tedit 616D63CF)
    (at 134.600003 122.066849 180)
    (descr "Capacitor SMD 0402")
    (tags "capacitor SMD 0402")
    (property "Author" "Antmicro")
    (property "DNP" "DNP")
    (property "Dielectric" "")
    (property "License" "Apache-2.0")
    (property "MPN" "CC0402MRX5R5BB106")
    (property "Manufacturer" "Yaego")
    (property "Sheetfile" "hdmi-converter.kicad_sch")
    (property "Sheetname" "HDMI converter")
    (property "Val" "10u")
    (property "Voltage" "")
    (attr exclude_from_pos_files)
    (fp_text reference "C22" (at 0.820003 -0.453151) (layer "B.SilkS")
      (effects (font (size 0.7 0.7) (thickness 0.15)) (justify left bottom mirror))
    )
    (fp_text value "C_10u_0402" (at 0 -1.4) (layer "B.Fab")
      (effects (font (size 0.7 0.7) (thickness 0.15)) (justify left bottom mirror))
    )
    (fp_text user "Author: Antmicro" (at -0.932 -4.17) (layer "B.Fab") hide
      (effects (font (size 0.7 0.7) (thickness 0.15)) (justify left bottom mirror))
    )
    (fp_text user "License: Apache-2.0" (at -0.932 -5.17) (layer "B.Fab") hide
      (effects (font (size 0.7 0.7) (thickness 0.15)) (justify left bottom mirror))
    )
    (fp_text user "${REFERENCE}" (at -0.932 -3.168) (layer "B.Fab") hide
      (effects (font (size 0.7 0.7) (thickness 0.15)) (justify left bottom mirror))
    )
    (fp_rect (start -0.94 0.47) (end 0.94 -0.47) (layer "B.CrtYd") (width 0.05) (fill none))
    (fp_rect (start -0.499 0.249) (end 0.499 -0.249) (layer "B.Fab") (width 0.15) (fill none))
    (pad "1" smd roundrect (at -0.484 0 180) (size 0.59 0.64) (layers "B.Cu" "B.Paste" "B.Mask") (roundrect_rratio 0.25)
      (net 188 "/HDMI converter/LT9611_VDD12") (pintype "passive"))
    (pad "2" smd roundrect (at 0.484 0 180) (size 0.59 0.64) (layers "B.Cu" "B.Paste" "B.Mask") (roundrect_rratio 0.25)
      (net 1 "GND") (pintype "passive"))
  )

  (footprint "sa800u-baseboard-hw-footprints:R_0603_1608Metric" (layer "B.Cu")
    (tedit 5D5D3E92)
    (at 68.7 118.55 90)
    (descr "Resistor SMD 0603")
    (tags "resistor SMD 0603")
    (property "Author" "Antmicro")
    (property "DNP" "DNP")
    (property "License" "Apache-2.0")
    (property "MPN" "CR0603-FX-1002ELF")
    (property "Manufacturer" "Bourns")
    (property "Sheetfile" "poe.kicad_sch")
    (property "Sheetname" "PoE")
    (property "Tolerance" "1%")
    (property "Val" "10k")
    (attr exclude_from_pos_files)
    (fp_text reference "R150" (at 1.4 -0.54 270) (layer "B.SilkS")
      (effects (font (size 0.7 0.7) (thickness 0.15)) (justify left bottom mirror))
    )
    (fp_text value "R_10k_0603" (at 0 -1.6 270) (layer "B.Fab")
      (effects (font (size 0.7 0.7) (thickness 0.15)) (justify left bottom mirror))
    )
    (fp_text user "License: Apache-2.0" (at -1.25 -5.9 270) (layer "B.Fab") hide
      (effects (font (size 0.7 0.7) (thickness 0.15)) (justify left bottom mirror))
    )
    (fp_text user "Author: Antmicro" (at -1.25 -4.9 270) (layer "B.Fab") hide
      (effects (font (size 0.7 0.7) (thickness 0.15)) (justify left bottom mirror))
    )
    (fp_text user "${REFERENCE}" (at -1.25 -3.898 270) (layer "B.Fab") hide
      (effects (font (size 0.7 0.7) (thickness 0.15)) (justify left bottom mirror))
    )
    (fp_line (start -0.3 -0.3) (end 0.3 -0.3) (layer "B.SilkS") (width 0.15))
    (fp_line (start -0.3 0.3) (end 0.3 0.3) (layer "B.SilkS") (width 0.15))
    (fp_rect (start -1.25 0.7) (end 1.25 -0.7) (layer "B.CrtYd") (width 0.05) (fill none))
    (fp_rect (start -0.8 0.4) (end 0.8 -0.4) (layer "B.Fab") (width 0.15) (fill none))
    (pad "1" smd roundrect (at -0.7 0 90) (size 0.6 0.8) (layers "B.Cu" "B.Paste" "B.Mask") (roundrect_rratio 0.2)
      (net 380 "Net-(D32-Pad1)") (pintype "passive"))
    (pad "2" smd roundrect (at 0.7 0 90) (size 0.6 0.8) (layers "B.Cu" "B.Paste" "B.Mask") (roundrect_rratio 0.2)
      (net 7 "GNDD") (pintype "passive"))
  )

  (footprint "sa800u-baseboard-hw-footprints:C_0402_1005Metric" (layer "B.Cu")
    (tedit 616D63CF)
    (at 144.5 125.6 180)
    (descr "Capacitor SMD 0402")
    (tags "capacitor SMD 0402")
    (property "Author" "Antmicro")
    (property "Dielectric" "X5R")
    (property "License" "Apache-2.0")
    (property "MPN" "GRM155R61H104KE14D")
    (property "Manufacturer" "Murata")
    (property "Sheetfile" "hdmi-converter.kicad_sch")
    (property "Sheetname" "HDMI converter")
    (property "Val" "100n")
    (property "Voltage" "50V")
    (attr smd)
    (fp_text reference "C33" (at -2.94 -0.35) (layer "B.SilkS")
      (effects (font (size 0.7 0.7) (thickness 0.15)) (justify left bottom mirror))
    )
    (fp_text value "C_100n_0402" (at 0 -1.4) (layer "B.Fab")
      (effects (font (size 0.7 0.7) (thickness 0.15)) (justify left bottom mirror))
    )
    (fp_text user "${REFERENCE}" (at -0.932 -3.168) (layer "B.Fab") hide
      (effects (font (size 0.7 0.7) (thickness 0.15)) (justify left bottom mirror))
    )
    (fp_text user "License: Apache-2.0" (at -0.932 -5.17) (layer "B.Fab") hide
      (effects (font (size 0.7 0.7) (thickness 0.15)) (justify left bottom mirror))
    )
    (fp_text user "Author: Antmicro" (at -0.932 -4.17) (layer "B.Fab") hide
      (effects (font (size 0.7 0.7) (thickness 0.15)) (justify left bottom mirror))
    )
    (fp_rect (start -0.94 0.47) (end 0.94 -0.47) (layer "B.CrtYd") (width 0.05) (fill none))
    (fp_rect (start -0.499 0.249) (end 0.499 -0.249) (layer "B.Fab") (width 0.15) (fill none))
    (pad "1" smd roundrect (at -0.484 0 180) (size 0.59 0.64) (layers "B.Cu" "B.Paste" "B.Mask") (roundrect_rratio 0.25)
      (net 188 "/HDMI converter/LT9611_VDD12") (pintype "passive"))
    (pad "2" smd roundrect (at 0.484 0 180) (size 0.59 0.64) (layers "B.Cu" "B.Paste" "B.Mask") (roundrect_rratio 0.25)
      (net 1 "GND") (pintype "passive"))
  )

  (footprint "sa800u-baseboard-hw-footprints:C_0402_1005Metric" (layer "B.Cu")
    (tedit 616D63CF)
    (at 144.5 126.6 180)
    (descr "Capacitor SMD 0402")
    (tags "capacitor SMD 0402")
    (property "Author" "Antmicro")
    (property "Dielectric" "X5R")
    (property "License" "Apache-2.0")
    (property "MPN" "GRM155R61H104KE14D")
    (property "Manufacturer" "Murata")
    (property "Sheetfile" "hdmi-converter.kicad_sch")
    (property "Sheetname" "HDMI converter")
    (property "Val" "100n")
    (property "Voltage" "50V")
    (attr smd)
    (fp_text reference "C35" (at -2.94 -0.35) (layer "B.SilkS")
      (effects (font (size 0.7 0.7) (thickness 0.15)) (justify left bottom mirror))
    )
    (fp_text value "C_100n_0402" (at 0 -1.4) (layer "B.Fab")
      (effects (font (size 0.7 0.7) (thickness 0.15)) (justify left bottom mirror))
    )
    (fp_text user "${REFERENCE}" (at -0.932 -3.168) (layer "B.Fab") hide
      (effects (font (size 0.7 0.7) (thickness 0.15)) (justify left bottom mirror))
    )
    (fp_text user "License: Apache-2.0" (at -0.932 -5.17) (layer "B.Fab") hide
      (effects (font (size 0.7 0.7) (thickness 0.15)) (justify left bottom mirror))
    )
    (fp_text user "Author: Antmicro" (at -0.932 -4.17) (layer "B.Fab") hide
      (effects (font (size 0.7 0.7) (thickness 0.15)) (justify left bottom mirror))
    )
    (fp_rect (start -0.94 0.47) (end 0.94 -0.47) (layer "B.CrtYd") (width 0.05) (fill none))
    (fp_rect (start -0.499 0.249) (end 0.499 -0.249) (layer "B.Fab") (width 0.15) (fill none))
    (pad "1" smd roundrect (at -0.484 0 180) (size 0.59 0.64) (layers "B.Cu" "B.Paste" "B.Mask") (roundrect_rratio 0.25)
      (net 188 "/HDMI converter/LT9611_VDD12") (pintype "passive"))
    (pad "2" smd roundrect (at 0.484 0 180) (size 0.59 0.64) (layers "B.Cu" "B.Paste" "B.Mask") (roundrect_rratio 0.25)
      (net 1 "GND") (pintype "passive"))
  )

  (footprint "sa800u-baseboard-hw-footprints:Bus_M.2_Socket_Key_M_Amphenol_MDT580M01001" locked (layer "B.Cu")
    (tedit 5E81ED22)
    (at 146.192 100.36 90)
    (property "Author" "Antmicro")
    (property "License" "Apache-2.0")
    (property "MPN" "MDT580M01001")
    (property "Manufacturer" "Amphenol")
    (property "Sheetfile" "m2.kicad_sch")
    (property "Sheetname" "M2")
    (attr smd)
    (fp_text reference "U15" (at -0.3 5.978 90) (layer "B.SilkS")
      (effects (font (size 0.7 0.7) (thickness 0.15)) (justify right bottom mirror))
    )
    (fp_text value "Bus_M.2_MDT580M01001" (at 0 -5.9 90) (layer "B.Fab")
      (effects (font (size 0.7 0.7) (thickness 0.15)) (justify right bottom mirror))
    )
    (fp_text user "Author: Antmicro" (at -13 -8.499 90) (layer "B.Fab") hide
      (effects (font (size 0.7 0.7) (thickness 0.15)) (justify right bottom mirror))
    )
    (fp_text user "${REFERENCE}" (at -13 -9.698 90) (layer "B.Fab") hide
      (effects (font (size 0.7 0.7) (thickness 0.15)) (justify right bottom mirror))
    )
    (fp_text user "License: Apache-2.0" (at -13 -10.899 90) (layer "B.Fab") hide
      (effects (font (size 0.7 0.7) (thickness 0.15)) (justify right bottom mirror))
    )
    (fp_line (start -10.071 -0.624) (end 9.499 -0.624) (layer "B.SilkS") (width 0.15))
    (fp_line (start -10.071 -4.626) (end -11.151 -4.626) (layer "B.SilkS") (width 0.15))
    (fp_line (start 10.848 -4.626) (end 9.768 -4.626) (layer "B.SilkS") (width 0.15))
    (fp_line (start -10.071 -4.626) (end -10.071 -2.205) (layer "B.SilkS") (width 0.15))
    (fp_line (start 9.768 -4.626) (end 9.768 -2.346) (layer "B.SilkS") (width 0.15))
    (fp_circle (center -9.7 4.7) (end -9.65 4.7) (layer "B.SilkS") (width 0.15) (fill solid))
    (fp_rect (start -11.5 5) (end 11.5 -4.9) (layer "B.CrtYd") (width 0.05) (fill none))
    (fp_line (start -10.985 4.13) (end -10.859 4.255) (layer "B.Fab") (width 0.15))
    (fp_rect (start -11 -4.275) (end 10.999 4.276) (layer "B.Fab") (width 0.15) (fill none))
    (pad "" np_thru_hole circle locked (at -10 -1.425 90) (size 1.1 1.1) (drill 1.1) (layers F&B.Cu *.Mask))
    (pad "" np_thru_hole circle locked (at 9.999 -1.425 90) (size 1.6 1.6) (drill 1.6) (layers F&B.Cu *.Mask))
    (pad "1" smd rect locked (at -9.25 3.848 90) (size 0.3 1.55) (layers "B.Cu" "B.Paste" "B.Mask")
      (net 1 "GND") (pinfunction "GND") (pintype "passive"))
    (pad "2" smd rect locked (at -9 -3.7 90) (size 0.3 1.55) (layers "B.Cu" "B.Paste" "B.Mask")
      (net 131 "3V3_SYS") (pinfunction "3V3") (pintype "passive"))
    (pad "3" smd rect locked (at -8.75 3.848 90) (size 0.3 1.55) (layers "B.Cu" "B.Paste" "B.Mask")
      (net 1 "GND") (pinfunction "GND") (pintype "passive"))
    (pad "4" smd rect locked (at -8.5 -3.7 90) (size 0.3 1.55) (layers "B.Cu" "B.Paste" "B.Mask")
      (net 131 "3V3_SYS") (pinfunction "3V3") (pintype "passive"))
    (pad "5" smd rect locked (at -8.25 3.848 90) (size 0.3 1.55) (layers "B.Cu" "B.Paste" "B.Mask")
      (net 656 "unconnected-(U15-Pad5)") (pinfunction "PER3_N") (pintype "passive+no_connect"))
    (pad "6" smd rect locked (at -8 -3.7 90) (size 0.3 1.55) (layers "B.Cu" "B.Paste" "B.Mask")
      (net 655 "unconnected-(U15-Pad6)") (pinfunction "NC") (pintype "no_connect"))
    (pad "7" smd rect locked (at -7.75 3.848 90) (size 0.3 1.55) (layers "B.Cu" "B.Paste" "B.Mask")
      (net 654 "unconnected-(U15-Pad7)") (pinfunction "PER3_P") (pintype "passive+no_connect"))
    (pad "8" smd rect locked (at -7.5 -3.7 90) (size 0.3 1.55) (layers "B.Cu" "B.Paste" "B.Mask")
      (net 653 "unconnected-(U15-Pad8)") (pinfunction "NC") (pintype "no_connect"))
    (pad "9" smd rect locked (at -7.25 3.848 90) (size 0.3 1.55) (layers "B.Cu" "B.Paste" "B.Mask")
      (net 1 "GND") (pinfunction "GND") (pintype "passive"))
    (pad "10" smd rect locked (at -7 -3.7 90) (size 0.3 1.55) (layers "B.Cu" "B.Paste" "B.Mask")
      (net 374 "Net-(D21-Pad2)") (pinfunction "LED") (pintype "passive"))
    (pad "11" smd rect locked (at -6.75 3.848 90) (size 0.3 1.55) (layers "B.Cu" "B.Paste" "B.Mask")
      (net 652 "unconnected-(U15-Pad11)") (pinfunction "PET3_N") (pintype "passive+no_connect"))
    (pad "12" smd rect locked (at -6.5 -3.7 90) (size 0.3 1.55) (layers "B.Cu" "B.Paste" "B.Mask")
      (net 131 "3V3_SYS") (pinfunction "3V3") (pintype "passive"))
    (pad "13" smd rect locked (at -6.25 3.848 90) (size 0.3 1.55) (layers "B.Cu" "B.Paste" "B.Mask")
      (net 651 "unconnected-(U15-Pad13)") (pinfunction "PET3_P") (pintype "passive+no_connect"))
    (pad "14" smd rect locked (at -6 -3.7 90) (size 0.3 1.55) (layers "B.Cu" "B.Paste" "B.Mask")
      (net 131 "3V3_SYS") (pinfunction "3V3") (pintype "passive"))
    (pad "15" smd rect locked (at -5.75 3.848 90) (size 0.3 1.55) (layers "B.Cu" "B.Paste" "B.Mask")
      (net 1 "GND") (pinfunction "GND") (pintype "passive"))
    (pad "16" smd rect locked (at -5.5 -3.7 90) (size 0.3 1.55) (layers "B.Cu" "B.Paste" "B.Mask")
      (net 131 "3V3_SYS") (pinfunction "3V3") (pintype "passive"))
    (pad "17" smd rect locked (at -5.25 3.848 90) (size 0.3 1.55) (layers "B.Cu" "B.Paste" "B.Mask")
      (net 650 "unconnected-(U15-Pad17)") (pinfunction "PER2_N") (pintype "passive+no_connect"))
    (pad "18" smd rect locked (at -5 -3.7 90) (size 0.3 1.55) (layers "B.Cu" "B.Paste" "B.Mask")
      (net 131 "3V3_SYS") (pinfunction "3V3") (pintype "passive"))
    (pad "19" smd rect locked (at -4.75 3.848 90) (size 0.3 1.55) (layers "B.Cu" "B.Paste" "B.Mask")
      (net 649 "unconnected-(U15-Pad19)") (pinfunction "PER2_P") (pintype "passive+no_connect"))
    (pad "20" smd rect locked (at -4.5 -3.7 90) (size 0.3 1.55) (layers "B.Cu" "B.Paste" "B.Mask")
      (net 648 "unconnected-(U15-Pad20)") (pinfunction "NC") (pintype "no_connect"))
    (pad "21" smd rect locked (at -4.25 3.848 90) (size 0.3 1.55) (layers "B.Cu" "B.Paste" "B.Mask")
      (net 1 "GND") (pinfunction "GND") (pintype "passive"))
    (pad "22" smd rect locked (at -4 -3.7 90) (size 0.3 1.55) (layers "B.Cu" "B.Paste" "B.Mask")
      (net 647 "unconnected-(U15-Pad22)") (pinfunction "NC") (pintype "no_connect"))
    (pad "23" smd rect locked (at -3.75 3.848 90) (size 0.3 1.55) (layers "B.Cu" "B.Paste" "B.Mask")
      (net 646 "unconnected-(U15-Pad23)") (pinfunction "PET2_N") (pintype "passive+no_connect"))
    (pad "24" smd rect locked (at -3.5 -3.7 90) (size 0.3 1.55) (layers "B.Cu" "B.Paste" "B.Mask")
      (net 645 "unconnected-(U15-Pad24)") (pinfunction "NC") (pintype "no_connect"))
    (pad "25" smd rect locked (at -3.25 3.848 90) (size 0.3 1.55) (layers "B.Cu" "B.Paste" "B.Mask")
      (net 644 "unconnected-(U15-Pad25)") (pinfunction "PET2_P") (pintype "passive+no_connect"))
    (pad "26" smd rect locked (at -3 -3.7 90) (size 0.3 1.55) (layers "B.Cu" "B.Paste" "B.Mask")
      (net 643 "unconnected-(U15-Pad26)") (pinfunction "NC") (pintype "no_connect"))
    (pad "27" smd rect locked (at -2.75 3.848 90) (size 0.3 1.55) (layers "B.Cu" "B.Paste" "B.Mask")
      (net 1 "GND") (pinfunction "GND") (pintype "passive"))
    (pad "28" smd rect locked (at -2.5 -3.7 90) (size 0.3 1.55) (layers "B.Cu" "B.Paste" "B.Mask")
      (net 642 "unconnected-(U15-Pad28)") (pinfunction "NC") (pintype "no_connect"))
    (pad "29" smd rect locked (at -2.25 3.848 90) (size 0.3 1.55) (layers "B.Cu" "B.Paste" "B.Mask")
      (net 641 "unconnected-(U15-Pad29)") (pinfunction "PER1_N") (pintype "passive+no_connect"))
    (pad "30" smd rect locked (at -2 -3.7 90) (size 0.3 1.55) (layers "B.Cu" "B.Paste" "B.Mask")
      (net 640 "unconnected-(U15-Pad30)") (pinfunction "NC") (pintype "no_connect"))
    (pad "31" smd rect locked (at -1.75 3.848 90) (size 0.3 1.55) (layers "B.Cu" "B.Paste" "B.Mask")
      (net 639 "unconnected-(U15-Pad31)") (pinfunction "PER1_P") (pintype "passive+no_connect"))
    (pad "32" smd rect locked (at -1.5 -3.7 90) (size 0.3 1.55) (layers "B.Cu" "B.Paste" "B.Mask")
      (net 638 "unconnected-(U15-Pad32)") (pinfunction "NC") (pintype "no_connect"))
    (pad "33" smd rect locked (at -1.25 3.848 90) (size 0.3 1.55) (layers "B.Cu" "B.Paste" "B.Mask")
      (net 1 "GND") (pinfunction "GND") (pintype "passive"))
    (pad "34" smd rect locked (at -1 -3.7 90) (size 0.3 1.55) (layers "B.Cu" "B.Paste" "B.Mask")
      (net 637 "unconnected-(U15-Pad34)") (pinfunction "NC") (pintype "no_connect"))
    (pad "35" smd rect locked (at -0.75 3.848 90) (size 0.3 1.55) (layers "B.Cu" "B.Paste" "B.Mask")
      (net 636 "unconnected-(U15-Pad35)") (pinfunction "PET1_N") (pintype "passive+no_connect"))
    (pad "36" smd rect locked (at -0.5 -3.7 90) (size 0.3 1.55) (layers "B.Cu" "B.Paste" "B.Mask")
      (net 635 "unconnected-(U15-Pad36)") (pinfunction "NC") (pintype "no_connect"))
    (pad "37" smd rect locked (at -0.25 3.848 90) (size 0.3 1.55) (layers "B.Cu" "B.Paste" "B.Mask")
      (net 634 "unconnected-(U15-Pad37)") (pinfunction "PET1_P") (pintype "passive+no_connect"))
    (pad "38" smd rect locked (at 0 -3.7 90) (size 0.3 1.55) (layers "B.Cu" "B.Paste" "B.Mask")
      (net 633 "unconnected-(U15-Pad38)") (pinfunction "NC") (pintype "no_connect"))
    (pad "39" smd rect locked (at 0.246 3.848 90) (size 0.3 1.55) (layers "B.Cu" "B.Paste" "B.Mask")
      (net 1 "GND") (pinfunction "GND") (pintype "passive"))
    (pad "40" smd rect locked (at 0.496 -3.7 90) (size 0.3 1.55) (layers "B.Cu" "B.Paste" "B.Mask")
      (net 416 "Net-(TP43-Pad1)") (pinfunction "SMB_CLK") (pintype "passive"))
    (pad "41" smd rect locked (at 0.747 3.848 90) (size 0.3 1.55) (layers "B.Cu" "B.Paste" "B.Mask")
      (net 125 "PCIE0_RX_N") (pinfunction "PER0_N") (pintype "passive"))
    (pad "42" smd rect locked (at 0.996 -3.7 90) (size 0.3 1.55) (layers "B.Cu" "B.Paste" "B.Mask")
      (net 415 "Net-(TP42-Pad1)") (pinfunction "SMB_DATA") (pintype "passive"))
    (pad "43" smd rect locked (at 1.249 3.848 90) (size 0.3 1.55) (layers "B.Cu" "B.Paste" "B.Mask")
      (net 123 "PCIE0_RX_P") (pinfunction "PER0_P") (pintype "passive"))
    (pad "44" smd rect locked (at 1.499 -3.7 90) (size 0.3 1.55) (layers "B.Cu" "B.Paste" "B.Mask")
      (net 121 "M2_ALERT") (pinfunction "ALERT") (pintype "passive"))
    (pad "45" smd rect locked (at 1.749 3.848 90) (size 0.3 1.55) (layers "B.Cu" "B.Paste" "B.Mask")
      (net 1 "GND") (pinfunction "GND") (pintype "passive"))
    (pad "46" smd rect locked (at 1.999 -3.7 90) (size 0.3 1.55) (layers "B.Cu" "B.Paste" "B.Mask")
      (net 632 "unconnected-(U15-Pad46)") (pinfunction "NC") (pintype "no_connect"))
    (pad "47" smd rect locked (at 2.249 3.848 90) (size 0.3 1.55) (layers "B.Cu" "B.Paste" "B.Mask")
      (net 111 "/M2/C_PCIE0_TX0_N") (pinfunction "PET0_N") (pintype "passive"))
    (pad "48" smd rect locked (at 2.499 -3.7 90) (size 0.3 1.55) (layers "B.Cu" "B.Paste" "B.Mask")
      (net 631 "unconnected-(U15-Pad48)") (pinfunction "NC") (pintype "no_connect"))
    (pad "49" smd rect locked (at 2.749 3.848 90) (size 0.3 1.55) (layers "B.Cu" "B.Paste" "B.Mask")
      (net 109 "/M2/C_PCIE0_TX0_P") (pinfunction "PET0_P") (pintype "passive"))
    (pad "50" smd rect locked (at 2.999 -3.7 90) (size 0.3 1.55) (layers "B.Cu" "B.Paste" "B.Mask")
      (net 124 "PCIE0_RST_N") (pinfunction "PERST#") (pintype "passive"))
    (pad "51" smd rect locked (at 3.249 3.848 90) (size 0.3 1.55) (layers "B.Cu" "B.Paste" "B.Mask")
      (net 1 "GND") (pinfunction "GND") (pintype "passive"))
    (pad "52" smd rect locked (at 3.499 -3.7 90) (size 0.3 1.55) (layers "B.Cu" "B.Paste" "B.Mask")
      (net 120 "PCIE0_CLKREQ_N") (pinfunction "CLKREQ#") (pintype "passive"))
    (pad "53" smd rect locked (at 3.749 3.848 90) (size 0.3 1.55) (layers "B.Cu" "B.Paste" "B.Mask")
      (net 126 "PCIE0_REFCLK_N") (pinfunction "REFCLK_N") (pintype "passive"))
    (pad "54" smd rect locked (at 3.999 -3.7 90) (size 0.3 1.55) (layers "B.Cu" "B.Paste" "B.Mask")
      (net 119 "PCIE0_WAKE_N") (pinfunction "PEWAKE#") (pintype "passive"))
    (pad "55" smd rect locked (at 4.248 3.848 90) (size 0.3 1.55) (layers "B.Cu" "B.Paste" "B.Mask")
      (net 122 "PCIE0_REFCLK_P") (pinfunction "REFCLK_P") (pintype "passive"))
    (pad "56" smd rect locked (at 4.498 -3.7 90) (size 0.3 1.55) (layers "B.Cu" "B.Paste" "B.Mask")
      (net 630 "unconnected-(U15-Pad56)") (pinfunction "NC") (pintype "no_connect"))
    (pad "57" smd rect locked (at 4.748 3.848 90) (size 0.3 1.55) (layers "B.Cu" "B.Paste" "B.Mask")
      (net 1 "GND") (pinfunction "GND") (pintype "passive"))
    (pad "58" smd rect locked (at 4.998 -3.7 90) (size 0.3 1.55) (layers "B.Cu" "B.Paste" "B.Mask")
      (net 629 "unconnected-(U15-Pad58)") (pinfunction "NC") (pintype "no_connect"))
    (pad "67" smd rect locked (at 7.249 3.848 90) (size 0.3 1.55) (layers "B.Cu" "B.Paste" "B.Mask")
      (net 628 "unconnected-(U15-Pad67)") (pinfunction "NC") (pintype "no_connect"))
    (pad "68" smd rect locked (at 7.498 -3.7 90) (size 0.3 1.55) (layers "B.Cu" "B.Paste" "B.Mask")
      (net 627 "unconnected-(U15-Pad68)") (pinfunction "SUSCLK") (pintype "passive+no_connect"))
    (pad "69" smd rect locked (at 7.748 3.848 90) (size 0.3 1.55) (layers "B.Cu" "B.Paste" "B.Mask")
      (net 626 "unconnected-(U15-Pad69)") (pinfunction "NC") (pintype "no_connect"))
    (pad "70" smd rect locked (at 7.998 -3.7 90) (size 0.3 1.55) (layers "B.Cu" "B.Paste" "B.Mask")
      (net 131 "3V3_SYS") (pinfunction "3V3") (pintype "passive"))
    (pad "71" smd rect locked (at 8.249 3.848 90) (size 0.3 1.55) (layers "B.Cu" "B.Paste" "B.Mask")
      (net 1 "GND") (pinfunction "GND") (pintype "passive"))
    (pad "72" smd rect locked (at 8.499 -3.7 90) (size 0.3 1.55) (layers "B.Cu" "B.Paste" "B.Mask")
      (net 131 "3V3_SYS") (pinfunction "3V3") (pintype "passive"))
    (pad "73" smd rect locked (at 8.749 3.848 90) (size 0.3 1.55) (layers "B.Cu" "B.Paste" "B.Mask")
      (net 1 "GND") (pinfunction "GND") (pintype "passive"))
    (pad "74" smd rect locked (at 8.999 -3.7 90) (size 0.3 1.55) (layers "B.Cu" "B.Paste" "B.Mask")
      (net 131 "3V3_SYS") (pinfunction "3V3") (pintype "passive"))
    (pad "75" smd rect locked (at 9.249 3.848 90) (size 0.3 1.55) (layers "B.Cu" "B.Paste" "B.Mask")
      (net 1 "GND") (pinfunction "GND") (pintype "passive"))
    (pad "SH1" smd rect locked (at -10.35 3.073 90) (size 1.2 2.75) (layers "B.Cu" "B.Paste" "B.Mask")
      (net 1 "GND") (pinfunction "SHIELD") (pintype "passive"))
    (pad "SH2" smd rect locked (at 10.348 3.073 90) (size 1.2 2.75) (layers "B.Cu" "B.Paste" "B.Mask")
      (net 1 "GND") (pinfunction "SHIELD") (pintype "passive"))
  )

  (footprint "sa800u-baseboard-hw-footprints:TP_SMD_0.75mm" (layer "B.Cu")
    (tedit 5E4A9375)
    (at 139.6 100)
    (property "Author" "Antmicro")
    (property "License" "Apache-2.0")
    (property "MPN" "")
    (property "Manufacturer" "")
    (property "Sheetfile" "m2.kicad_sch")
    (property "Sheetname" "M2")
    (attr smd)
    (fp_text reference "TP42" (at -0.29 1.04 180) (layer "B.SilkS")
      (effects (font (size 0.7 0.7) (thickness 0.15)) (justify left bottom mirror))
    )
    (fp_text value "TP_0.75mm_SMD" (at 0 -1.2 180) (layer "B.Fab")
      (effects (font (size 0.7 0.7) (thickness 0.15)) (justify left bottom mirror))
    )
    (fp_text user "Author: Antmicro" (at -0.4 -3.901 180) (layer "B.Fab") hide
      (effects (font (size 0.7 0.7) (thickness 0.15)) (justify left bottom mirror))
    )
    (fp_text user "${REFERENCE}" (at -0.4 -2.7 180) (layer "B.Fab") hide
      (effects (font (size 0.7 0.7) (thickness 0.15)) (justify left bottom mirror))
    )
    (fp_text user "License: Apache-2.0" (at -0.4 -5.101 180) (layer "B.Fab") hide
      (effects (font (size 0.7 0.7) (thickness 0.15)) (justify left bottom mirror))
    )
    (pad "1" smd circle (at 0 0) (size 0.75 0.75) (layers "B.Cu" "B.Mask")
      (net 415 "Net-(TP42-Pad1)") (pinfunction "1") (pintype "passive"))
  )

  (footprint "sa800u-baseboard-hw-footprints:TP_SMD_0.75mm" (layer "B.Cu")
    (tedit 5E4A9375)
    (at 139.6 101.4)
    (property "Author" "Antmicro")
    (property "License" "Apache-2.0")
    (property "MPN" "")
    (property "Manufacturer" "")
    (property "Sheetfile" "m2.kicad_sch")
    (property "Sheetname" "M2")
    (attr smd)
    (fp_text reference "TP43" (at -0.29 1.04 180) (layer "B.SilkS")
      (effects (font (size 0.7 0.7) (thickness 0.15)) (justify left bottom mirror))
    )
    (fp_text value "TP_0.75mm_SMD" (at 0 -1.2 180) (layer "B.Fab")
      (effects (font (size 0.7 0.7) (thickness 0.15)) (justify left bottom mirror))
    )
    (fp_text user "${REFERENCE}" (at -0.4 -2.7 180) (layer "B.Fab") hide
      (effects (font (size 0.7 0.7) (thickness 0.15)) (justify left bottom mirror))
    )
    (fp_text user "Author: Antmicro" (at -0.4 -3.901 180) (layer "B.Fab") hide
      (effects (font (size 0.7 0.7) (thickness 0.15)) (justify left bottom mirror))
    )
    (fp_text user "License: Apache-2.0" (at -0.4 -5.101 180) (layer "B.Fab") hide
      (effects (font (size 0.7 0.7) (thickness 0.15)) (justify left bottom mirror))
    )
    (pad "1" smd circle (at 0 0) (size 0.75 0.75) (layers "B.Cu" "B.Mask")
      (net 416 "Net-(TP43-Pad1)") (pinfunction "1") (pintype "passive"))
  )

  (footprint "sa800u-baseboard-hw-footprints:TP_SMD_0.75mm" (layer "B.Cu")
    (tedit 5E4A9375)
    (at 95.6 98.8)
    (property "Author" "Antmicro")
    (property "License" "Apache-2.0")
    (property "MPN" "")
    (property "Manufacturer" "")
    (property "Sheetfile" "ethernet-controller.kicad_sch")
    (property "Sheetname" "Ethernet Controller")
    (attr smd)
    (fp_text reference "TP1" (at 0.59 -0.41 180) (layer "B.SilkS")
      (effects (font (size 0.7 0.7) (thickness 0.15)) (justify left bottom mirror))
    )
    (fp_text value "TP_0.75mm_SMD" (at 0 -1.2 180) (layer "B.Fab")
      (effects (font (size 0.7 0.7) (thickness 0.15)) (justify left bottom mirror))
    )
    (fp_text user "License: Apache-2.0" (at -0.4 -5.101 180) (layer "B.Fab") hide
      (effects (font (size 0.7 0.7) (thickness 0.15)) (justify left bottom mirror))
    )
    (fp_text user "${REFERENCE}" (at -0.4 -2.7 180) (layer "B.Fab") hide
      (effects (font (size 0.7 0.7) (thickness 0.15)) (justify left bottom mirror))
    )
    (fp_text user "Author: Antmicro" (at -0.4 -3.901 180) (layer "B.Fab") hide
      (effects (font (size 0.7 0.7) (thickness 0.15)) (justify left bottom mirror))
    )
    (pad "1" smd circle (at 0 0) (size 0.75 0.75) (layers "B.Cu" "B.Mask")
      (net 177 "/Ethernet Controller/ETH_3V3") (pinfunction "1") (pintype "passive"))
  )

  (footprint "sa800u-baseboard-hw-footprints:TP_SMD_0.75mm" (layer "B.Cu")
    (tedit 5E4A9375)
    (at 103.8 100.4)
    (property "Author" "Antmicro")
    (property "License" "Apache-2.0")
    (property "MPN" "")
    (property "Manufacturer" "")
    (property "Sheetfile" "ethernet-controller.kicad_sch")
    (property "Sheetname" "Ethernet Controller")
    (attr smd)
    (fp_text reference "TP2" (at 2.32 0.49 180) (layer "B.SilkS")
      (effects (font (size 0.7 0.7) (thickness 0.15)) (justify left bottom mirror))
    )
    (fp_text value "TP_0.75mm_SMD" (at 0 -1.2 180) (layer "B.Fab")
      (effects (font (size 0.7 0.7) (thickness 0.15)) (justify left bottom mirror))
    )
    (fp_text user "License: Apache-2.0" (at -0.4 -5.101 180) (layer "B.Fab") hide
      (effects (font (size 0.7 0.7) (thickness 0.15)) (justify left bottom mirror))
    )
    (fp_text user "${REFERENCE}" (at -0.4 -2.7 180) (layer "B.Fab") hide
      (effects (font (size 0.7 0.7) (thickness 0.15)) (justify left bottom mirror))
    )
    (fp_text user "Author: Antmicro" (at -0.4 -3.901 180) (layer "B.Fab") hide
      (effects (font (size 0.7 0.7) (thickness 0.15)) (justify left bottom mirror))
    )
    (pad "1" smd circle (at 0 0) (size 0.75 0.75) (layers "B.Cu" "B.Mask")
      (net 162 "PCIE1_CLKREQ_N") (pinfunction "1") (pintype "passive"))
  )

  (footprint "sa800u-baseboard-hw-footprints:TP_SMD_0.75mm" (layer "B.Cu")
    (tedit 5E4A9375)
    (at 105 103.2)
    (property "Author" "Antmicro")
    (property "License" "Apache-2.0")
    (property "MPN" "")
    (property "Manufacturer" "")
    (property "Sheetfile" "ethernet-controller.kicad_sch")
    (property "Sheetname" "Ethernet Controller")
    (attr smd)
    (fp_text reference "TP3" (at 2.37 0.43 180) (layer "B.SilkS")
      (effects (font (size 0.7 0.7) (thickness 0.15)) (justify left bottom mirror))
    )
    (fp_text value "TP_0.75mm_SMD" (at 0 -1.2 180) (layer "B.Fab")
      (effects (font (size 0.7 0.7) (thickness 0.15)) (justify left bottom mirror))
    )
    (fp_text user "Author: Antmicro" (at -0.4 -3.901 180) (layer "B.Fab") hide
      (effects (font (size 0.7 0.7) (thickness 0.15)) (justify left bottom mirror))
    )
    (fp_text user "${REFERENCE}" (at -0.4 -2.7 180) (layer "B.Fab") hide
      (effects (font (size 0.7 0.7) (thickness 0.15)) (justify left bottom mirror))
    )
    (fp_text user "License: Apache-2.0" (at -0.4 -5.101 180) (layer "B.Fab") hide
      (effects (font (size 0.7 0.7) (thickness 0.15)) (justify left bottom mirror))
    )
    (pad "1" smd circle (at 0 0) (size 0.75 0.75) (layers "B.Cu" "B.Mask")
      (net 286 "/Ethernet Controller/ETH_ISOLATEB") (pinfunction "1") (pintype "passive"))
  )

  (footprint "sa800u-baseboard-hw-footprints:TP_SMD_0.75mm" (layer "B.Cu")
    (tedit 5E4A9375)
    (at 102.6 99.4)
    (property "Author" "Antmicro")
    (property "License" "Apache-2.0")
    (property "MPN" "")
    (property "Manufacturer" "")
    (property "Sheetfile" "ethernet-controller.kicad_sch")
    (property "Sheetname" "Ethernet Controller")
    (attr smd)
    (fp_text reference "TP4" (at 2.36 0.31 180) (layer "B.SilkS")
      (effects (font (size 0.7 0.7) (thickness 0.15)) (justify left bottom mirror))
    )
    (fp_text value "TP_0.75mm_SMD" (at 0 -1.2 180) (layer "B.Fab")
      (effects (font (size 0.7 0.7) (thickness 0.15)) (justify left bottom mirror))
    )
    (fp_text user "Author: Antmicro" (at -0.4 -3.901 180) (layer "B.Fab") hide
      (effects (font (size 0.7 0.7) (thickness 0.15)) (justify left bottom mirror))
    )
    (fp_text user "${REFERENCE}" (at -0.4 -2.7 180) (layer "B.Fab") hide
      (effects (font (size 0.7 0.7) (thickness 0.15)) (justify left bottom mirror))
    )
    (fp_text user "License: Apache-2.0" (at -0.4 -5.101 180) (layer "B.Fab") hide
      (effects (font (size 0.7 0.7) (thickness 0.15)) (justify left bottom mirror))
    )
    (pad "1" smd circle (at 0 0) (size 0.75 0.75) (layers "B.Cu" "B.Mask")
      (net 161 "PCIE1_WAKE_N") (pinfunction "1") (pintype "passive"))
  )

  (footprint "sa800u-baseboard-hw-footprints:TP_SMD_0.75mm" (layer "B.Cu")
    (tedit 5E4A9375)
    (at 104.8 101.6)
    (property "Author" "Antmicro")
    (property "License" "Apache-2.0")
    (property "MPN" "")
    (property "Manufacturer" "")
    (property "Sheetfile" "ethernet-controller.kicad_sch")
    (property "Sheetname" "Ethernet Controller")
    (attr smd)
    (fp_text reference "TP5" (at 2.39 0.39 180) (layer "B.SilkS")
      (effects (font (size 0.7 0.7) (thickness 0.15)) (justify left bottom mirror))
    )
    (fp_text value "TP_0.75mm_SMD" (at 0 -1.2 180) (layer "B.Fab")
      (effects (font (size 0.7 0.7) (thickness 0.15)) (justify left bottom mirror))
    )
    (fp_text user "${REFERENCE}" (at -0.4 -2.7 180) (layer "B.Fab") hide
      (effects (font (size 0.7 0.7) (thickness 0.15)) (justify left bottom mirror))
    )
    (fp_text user "License: Apache-2.0" (at -0.4 -5.101 180) (layer "B.Fab") hide
      (effects (font (size 0.7 0.7) (thickness 0.15)) (justify left bottom mirror))
    )
    (fp_text user "Author: Antmicro" (at -0.4 -3.901 180) (layer "B.Fab") hide
      (effects (font (size 0.7 0.7) (thickness 0.15)) (justify left bottom mirror))
    )
    (pad "1" smd circle (at 0 0) (size 0.75 0.75) (layers "B.Cu" "B.Mask")
      (net 163 "PCIE1_RST_N") (pinfunction "1") (pintype "passive"))
  )

  (footprint "sa800u-baseboard-hw-footprints:TP_SMD_0.75mm" (layer "B.Cu")
    (tedit 5E4A9375)
    (at 92.8 106.6)
    (property "Author" "Antmicro")
    (property "License" "Apache-2.0")
    (property "MPN" "")
    (property "Manufacturer" "")
    (property "Sheetfile" "ethernet-controller.kicad_sch")
    (property "Sheetname" "Ethernet Controller")
    (attr smd)
    (fp_text reference "TP6" (at -0.3 0.27 180) (layer "B.SilkS")
      (effects (font (size 0.7 0.7) (thickness 0.15)) (justify left bottom mirror))
    )
    (fp_text value "TP_0.75mm_SMD" (at 0 -1.2 180) (layer "B.Fab")
      (effects (font (size 0.7 0.7) (thickness 0.15)) (justify left bottom mirror))
    )
    (fp_text user "${REFERENCE}" (at -0.4 -2.7 180) (layer "B.Fab") hide
      (effects (font (size 0.7 0.7) (thickness 0.15)) (justify left bottom mirror))
    )
    (fp_text user "License: Apache-2.0" (at -0.4 -5.101 180) (layer "B.Fab") hide
      (effects (font (size 0.7 0.7) (thickness 0.15)) (justify left bottom mirror))
    )
    (fp_text user "Author: Antmicro" (at -0.4 -3.901 180) (layer "B.Fab") hide
      (effects (font (size 0.7 0.7) (thickness 0.15)) (justify left bottom mirror))
    )
    (pad "1" smd circle (at 0 0) (size 0.75 0.75) (layers "B.Cu" "B.Mask")
      (net 393 "Net-(R11-Pad1)") (pinfunction "1") (pintype "passive"))
  )

  (footprint "sa800u-baseboard-hw-footprints:TP_SMD_0.75mm" (layer "B.Cu")
    (tedit 5E4A9375)
    (at 100.6 107.8)
    (property "Author" "Antmicro")
    (property "License" "Apache-2.0")
    (property "MPN" "")
    (property "Manufacturer" "")
    (property "Sheetfile" "ethernet-controller.kicad_sch")
    (property "Sheetname" "Ethernet Controller")
    (attr smd)
    (fp_text reference "TP7" (at 2.48 0.56 180) (layer "B.SilkS")
      (effects (font (size 0.7 0.7) (thickness 0.15)) (justify left bottom mirror))
    )
    (fp_text value "TP_0.75mm_SMD" (at 0 -1.2 180) (layer "B.Fab")
      (effects (font (size 0.7 0.7) (thickness 0.15)) (justify left bottom mirror))
    )
    (fp_text user "License: Apache-2.0" (at -0.4 -5.101 180) (layer "B.Fab") hide
      (effects (font (size 0.7 0.7) (thickness 0.15)) (justify left bottom mirror))
    )
    (fp_text user "${REFERENCE}" (at -0.4 -2.7 180) (layer "B.Fab") hide
      (effects (font (size 0.7 0.7) (thickness 0.15)) (justify left bottom mirror))
    )
    (fp_text user "Author: Antmicro" (at -0.4 -3.901 180) (layer "B.Fab") hide
      (effects (font (size 0.7 0.7) (thickness 0.15)) (justify left bottom mirror))
    )
    (pad "1" smd circle (at 0 0) (size 0.75 0.75) (layers "B.Cu" "B.Mask")
      (net 178 "/Ethernet Controller/REG_1V0") (pinfunction "1") (pintype "passive"))
  )

  (footprint "sa800u-baseboard-hw-footprints:TP_SMD_0.75mm" (layer "B.Cu")
    (tedit 5E4A9375)
    (at 94.4 100)
    (property "Author" "Antmicro")
    (property "License" "Apache-2.0")
    (property "MPN" "")
    (property "Manufacturer" "")
    (property "Sheetfile" "ethernet-controller.kicad_sch")
    (property "Sheetname" "Ethernet Controller")
    (attr smd)
    (fp_text reference "TP8" (at 0.53 -0.47 180) (layer "B.SilkS")
      (effects (font (size 0.7 0.7) (thickness 0.15)) (justify left bottom mirror))
    )
    (fp_text value "TP_0.75mm_SMD" (at 0 -1.2 180) (layer "B.Fab")
      (effects (font (size 0.7 0.7) (thickness 0.15)) (justify left bottom mirror))
    )
    (fp_text user "License: Apache-2.0" (at -0.4 -5.101 180) (layer "B.Fab") hide
      (effects (font (size 0.7 0.7) (thickness 0.15)) (justify left bottom mirror))
    )
    (fp_text user "Author: Antmicro" (at -0.4 -3.901 180) (layer "B.Fab") hide
      (effects (font (size 0.7 0.7) (thickness 0.15)) (justify left bottom mirror))
    )
    (fp_text user "${REFERENCE}" (at -0.4 -2.7 180) (layer "B.Fab") hide
      (effects (font (size 0.7 0.7) (thickness 0.15)) (justify left bottom mirror))
    )
    (pad "1" smd circle (at 0 0) (size 0.75 0.75) (layers "B.Cu" "B.Mask")
      (net 181 "/Ethernet Controller/ETH_1V0") (pinfunction "1") (pintype "passive"))
  )

  (footprint "sa800u-baseboard-hw-footprints:TP_SMD_0.75mm" (layer "B.Cu")
    (tedit 5E4A9375)
    (at 140.25 126.5)
    (property "Author" "Antmicro")
    (property "License" "Apache-2.0")
    (property "MPN" "")
    (property "Manufacturer" "")
    (property "Sheetfile" "hdmi-converter.kicad_sch")
    (property "Sheetname" "HDMI converter")
    (attr smd)
    (fp_text reference "TP9" (at 0.93 1.2 180) (layer "B.SilkS")
      (effects (font (size 0.7 0.7) (thickness 0.15)) (justify left bottom mirror))
    )
    (fp_text value "TP_0.75mm_SMD" (at 0 -1.2 180) (layer "B.Fab")
      (effects (font (size 0.7 0.7) (thickness 0.15)) (justify left bottom mirror))
    )
    (fp_text user "Author: Antmicro" (at -0.4 -3.901 180) (layer "B.Fab") hide
      (effects (font (size 0.7 0.7) (thickness 0.15)) (justify left bottom mirror))
    )
    (fp_text user "${REFERENCE}" (at -0.4 -2.7 180) (layer "B.Fab") hide
      (effects (font (size 0.7 0.7) (thickness 0.15)) (justify left bottom mirror))
    )
    (fp_text user "License: Apache-2.0" (at -0.4 -5.101 180) (layer "B.Fab") hide
      (effects (font (size 0.7 0.7) (thickness 0.15)) (justify left bottom mirror))
    )
    (pad "1" smd circle (at 0 0) (size 0.75 0.75) (layers "B.Cu" "B.Mask")
      (net 289 "/HDMI converter/I2C_ADDR") (pinfunction "1") (pintype "passive"))
  )

  (footprint "sa800u-baseboard-hw-footprints:TP_SMD_0.75mm" (layer "B.Cu")
    (tedit 5E4A9375)
    (at 135.9 127.1992)
    (property "Author" "Antmicro")
    (property "License" "Apache-2.0")
    (property "MPN" "")
    (property "Manufacturer" "")
    (property "Sheetfile" "hdmi-converter.kicad_sch")
    (property "Sheetname" "HDMI converter")
    (attr smd)
    (fp_text reference "TP10" (at -0.17 -0.1092 180) (layer "B.SilkS")
      (effects (font (size 0.7 0.7) (thickness 0.15)) (justify left bottom mirror))
    )
    (fp_text value "TP_0.75mm_SMD" (at 0 -1.2 180) (layer "B.Fab")
      (effects (font (size 0.7 0.7) (thickness 0.15)) (justify left bottom mirror))
    )
    (fp_text user "License: Apache-2.0" (at -0.4 -5.101 180) (layer "B.Fab") hide
      (effects (font (size 0.7 0.7) (thickness 0.15)) (justify left bottom mirror))
    )
    (fp_text user "Author: Antmicro" (at -0.4 -3.901 180) (layer "B.Fab") hide
      (effects (font (size 0.7 0.7) (thickness 0.15)) (justify left bottom mirror))
    )
    (fp_text user "${REFERENCE}" (at -0.4 -2.7 180) (layer "B.Fab") hide
      (effects (font (size 0.7 0.7) (thickness 0.15)) (justify left bottom mirror))
    )
    (pad "1" smd circle (at 0 0) (size 0.75 0.75) (layers "B.Cu" "B.Mask")
      (net 184 "/HDMI converter/LT9611_VCC33_IO") (pinfunction "1") (pintype "passive"))
  )

  (footprint "sa800u-baseboard-hw-footprints:TP_SMD_0.75mm" (layer "B.Cu")
    (tedit 5E4A9375)
    (at 146.75 122.25)
    (property "Author" "Antmicro")
    (property "License" "Apache-2.0")
    (property "MPN" "")
    (property "Manufacturer" "")
    (property "Sheetfile" "hdmi-converter.kicad_sch")
    (property "Sheetname" "HDMI converter")
    (attr smd)
    (fp_text reference "TP12" (at 2.3 -0.5 180) (layer "B.SilkS")
      (effects (font (size 0.7 0.7) (thickness 0.15)) (justify left bottom mirror))
    )
    (fp_text value "TP_0.75mm_SMD" (at 0 -1.2 180) (layer "B.Fab")
      (effects (font (size 0.7 0.7) (thickness 0.15)) (justify left bottom mirror))
    )
    (fp_text user "${REFERENCE}" (at -0.4 -2.7 180) (layer "B.Fab") hide
      (effects (font (size 0.7 0.7) (thickness 0.15)) (justify left bottom mirror))
    )
    (fp_text user "License: Apache-2.0" (at -0.4 -5.101 180) (layer "B.Fab") hide
      (effects (font (size 0.7 0.7) (thickness 0.15)) (justify left bottom mirror))
    )
    (fp_text user "Author: Antmicro" (at -0.4 -3.901 180) (layer "B.Fab") hide
      (effects (font (size 0.7 0.7) (thickness 0.15)) (justify left bottom mirror))
    )
    (pad "1" smd circle (at 0 0) (size 0.75 0.75) (layers "B.Cu" "B.Mask")
      (net 185 "/HDMI converter/LT9611_VCC33_RX") (pinfunction "1") (pintype "passive"))
  )

  (footprint "sa800u-baseboard-hw-footprints:TP_SMD_0.75mm" (layer "B.Cu")
    (tedit 5E4A9375)
    (at 141.3 132.7492)
    (property "Author" "Antmicro")
    (property "License" "Apache-2.0")
    (property "MPN" "")
    (property "Manufacturer" "")
    (property "Sheetfile" "hdmi-converter.kicad_sch")
    (property "Sheetname" "HDMI converter")
    (attr smd)
    (fp_text reference "TP11" (at 0.42 0.3208 270) (layer "B.SilkS")
      (effects (font (size 0.7 0.7) (thickness 0.15)) (justify left bottom mirror))
    )
    (fp_text value "TP_0.75mm_SMD" (at 0 -1.2 180) (layer "B.Fab")
      (effects (font (size 0.7 0.7) (thickness 0.15)) (justify left bottom mirror))
    )
    (fp_text user "${REFERENCE}" (at -0.4 -2.7 180) (layer "B.Fab") hide
      (effects (font (size 0.7 0.7) (thickness 0.15)) (justify left bottom mirror))
    )
    (fp_text user "License: Apache-2.0" (at -0.4 -5.101 180) (layer "B.Fab") hide
      (effects (font (size 0.7 0.7) (thickness 0.15)) (justify left bottom mirror))
    )
    (fp_text user "Author: Antmicro" (at -0.4 -3.901 180) (layer "B.Fab") hide
      (effects (font (size 0.7 0.7) (thickness 0.15)) (justify left bottom mirror))
    )
    (pad "1" smd circle (at 0 0) (size 0.75 0.75) (layers "B.Cu" "B.Mask")
      (net 187 "/HDMI converter/LT9611_VCC33_TX") (pinfunction "1") (pintype "passive"))
  )

  (footprint "sa800u-baseboard-hw-footprints:TP_SMD_0.75mm" (layer "B.Cu")
    (tedit 5E4A9375)
    (at 142 123.5)
    (property "Author" "Antmicro")
    (property "License" "Apache-2.0")
    (property "MPN" "")
    (property "Manufacturer" "")
    (property "Sheetfile" "hdmi-converter.kicad_sch")
    (property "Sheetname" "HDMI converter")
    (attr smd)
    (fp_text reference "TP18" (at 0.53 -0.44 180) (layer "B.SilkS")
      (effects (font (size 0.7 0.7) (thickness 0.15)) (justify left bottom mirror))
    )
    (fp_text value "TP_0.75mm_SMD" (at 0 -1.2 180) (layer "B.Fab")
      (effects (font (size 0.7 0.7) (thickness 0.15)) (justify left bottom mirror))
    )
    (fp_text user "License: Apache-2.0" (at -0.4 -5.101 180) (layer "B.Fab") hide
      (effects (font (size 0.7 0.7) (thickness 0.15)) (justify left bottom mirror))
    )
    (fp_text user "Author: Antmicro" (at -0.4 -3.901 180) (layer "B.Fab") hide
      (effects (font (size 0.7 0.7) (thickness 0.15)) (justify left bottom mirror))
    )
    (fp_text user "${REFERENCE}" (at -0.4 -2.7 180) (layer "B.Fab") hide
      (effects (font (size 0.7 0.7) (thickness 0.15)) (justify left bottom mirror))
    )
    (pad "1" smd circle (at 0 0) (size 0.75 0.75) (layers "B.Cu" "B.Mask")
      (net 186 "/HDMI converter/LT9611_RST_N") (pinfunction "1") (pintype "passive"))
  )

  (footprint "sa800u-baseboard-hw-footprints:TP_SMD_0.75mm" (layer "B.Cu")
    (tedit 5E4A9375)
    (at 140.2 123.5)
    (property "Author" "Antmicro")
    (property "License" "Apache-2.0")
    (property "MPN" "")
    (property "Manufacturer" "")
    (property "Sheetfile" "hdmi-converter.kicad_sch")
    (property "Sheetname" "HDMI converter")
    (attr smd)
    (fp_text reference "TP17" (at -0.28 0.4 180) (layer "B.SilkS")
      (effects (font (size 0.7 0.7) (thickness 0.15)) (justify left bottom mirror))
    )
    (fp_text value "TP_0.75mm_SMD" (at 0 -1.2 180) (layer "B.Fab")
      (effects (font (size 0.7 0.7) (thickness 0.15)) (justify left bottom mirror))
    )
    (fp_text user "${REFERENCE}" (at -0.4 -2.7 180) (layer "B.Fab") hide
      (effects (font (size 0.7 0.7) (thickness 0.15)) (justify left bottom mirror))
    )
    (fp_text user "License: Apache-2.0" (at -0.4 -5.101 180) (layer "B.Fab") hide
      (effects (font (size 0.7 0.7) (thickness 0.15)) (justify left bottom mirror))
    )
    (fp_text user "Author: Antmicro" (at -0.4 -3.901 180) (layer "B.Fab") hide
      (effects (font (size 0.7 0.7) (thickness 0.15)) (justify left bottom mirror))
    )
    (pad "1" smd circle (at 0 0) (size 0.75 0.75) (layers "B.Cu" "B.Mask")
      (net 284 "/HDMI converter/LT9611_INTO_GPIO5") (pinfunction "1") (pintype "passive"))
  )

  (footprint "sa800u-baseboard-hw-footprints:TP_SMD_0.75mm" (layer "B.Cu")
    (tedit 5E4A9375)
    (at 136.25 128.75)
    (property "Author" "Antmicro")
    (property "License" "Apache-2.0")
    (property "MPN" "")
    (property "Manufacturer" "")
    (property "Sheetfile" "hdmi-converter.kicad_sch")
    (property "Sheetname" "HDMI converter")
    (attr smd)
    (fp_text reference "TP13" (at -0.25 0.3 180) (layer "B.SilkS")
      (effects (font (size 0.7 0.7) (thickness 0.15)) (justify left bottom mirror))
    )
    (fp_text value "TP_0.75mm_SMD" (at 0 -1.2 180) (layer "B.Fab")
      (effects (font (size 0.7 0.7) (thickness 0.15)) (justify left bottom mirror))
    )
    (fp_text user "${REFERENCE}" (at -0.4 -2.7 180) (layer "B.Fab") hide
      (effects (font (size 0.7 0.7) (thickness 0.15)) (justify left bottom mirror))
    )
    (fp_text user "License: Apache-2.0" (at -0.4 -5.101 180) (layer "B.Fab") hide
      (effects (font (size 0.7 0.7) (thickness 0.15)) (justify left bottom mirror))
    )
    (fp_text user "Author: Antmicro" (at -0.4 -3.901 180) (layer "B.Fab") hide
      (effects (font (size 0.7 0.7) (thickness 0.15)) (justify left bottom mirror))
    )
    (pad "1" smd circle (at 0 0) (size 0.75 0.75) (layers "B.Cu" "B.Mask")
      (net 188 "/HDMI converter/LT9611_VDD12") (pinfunction "1") (pintype "passive"))
  )

  (footprint "sa800u-baseboard-hw-footprints:TP_SMD_0.75mm" (layer "B.Cu")
    (tedit 5E4A9375)
    (at 146 120.9)
    (property "Author" "Antmicro")
    (property "License" "Apache-2.0")
    (property "MPN" "")
    (property "Manufacturer" "")
    (property "Sheetfile" "hdmi-converter.kicad_sch")
    (property "Sheetname" "HDMI converter")
    (attr smd)
    (fp_text reference "TP14" (at 2.24 -0.49 180) (layer "B.SilkS")
      (effects (font (size 0.7 0.7) (thickness 0.15)) (justify left bottom mirror))
    )
    (fp_text value "TP_0.75mm_SMD" (at 0 -1.2 180) (layer "B.Fab")
      (effects (font (size 0.7 0.7) (thickness 0.15)) (justify left bottom mirror))
    )
    (fp_text user "${REFERENCE}" (at -0.4 -2.7 180) (layer "B.Fab") hide
      (effects (font (size 0.7 0.7) (thickness 0.15)) (justify left bottom mirror))
    )
    (fp_text user "Author: Antmicro" (at -0.4 -3.901 180) (layer "B.Fab") hide
      (effects (font (size 0.7 0.7) (thickness 0.15)) (justify left bottom mirror))
    )
    (fp_text user "License: Apache-2.0" (at -0.4 -5.101 180) (layer "B.Fab") hide
      (effects (font (size 0.7 0.7) (thickness 0.15)) (justify left bottom mirror))
    )
    (pad "1" smd circle (at 0 0) (size 0.75 0.75) (layers "B.Cu" "B.Mask")
      (net 189 "/HDMI converter/LT9611_VCC12_RX") (pinfunction "1") (pintype "passive"))
  )

  (footprint "sa800u-baseboard-hw-footprints:TP_SMD_0.75mm" (layer "B.Cu")
    (tedit 5E4A9375)
    (at 142.9 132.7492)
    (property "Author" "Antmicro")
    (property "License" "Apache-2.0")
    (property "MPN" "")
    (property "Manufacturer" "")
    (property "Sheetfile" "hdmi-converter.kicad_sch")
    (property "Sheetname" "HDMI converter")
    (attr smd)
    (fp_text reference "TP15" (at 0.43 0.3408 270) (layer "B.SilkS")
      (effects (font (size 0.7 0.7) (thickness 0.15)) (justify left bottom mirror))
    )
    (fp_text value "TP_0.75mm_SMD" (at 0 -1.2 180) (layer "B.Fab")
      (effects (font (size 0.7 0.7) (thickness 0.15)) (justify left bottom mirror))
    )
    (fp_text user "License: Apache-2.0" (at -0.4 -5.101 180) (layer "B.Fab") hide
      (effects (font (size 0.7 0.7) (thickness 0.15)) (justify left bottom mirror))
    )
    (fp_text user "${REFERENCE}" (at -0.4 -2.7 180) (layer "B.Fab") hide
      (effects (font (size 0.7 0.7) (thickness 0.15)) (justify left bottom mirror))
    )
    (fp_text user "Author: Antmicro" (at -0.4 -3.901 180) (layer "B.Fab") hide
      (effects (font (size 0.7 0.7) (thickness 0.15)) (justify left bottom mirror))
    )
    (pad "1" smd circle (at 0 0) (size 0.75 0.75) (layers "B.Cu" "B.Mask")
      (net 191 "/HDMI converter/LT9611_VCC12_TX") (pinfunction "1") (pintype "passive"))
  )

  (footprint "sa800u-baseboard-hw-footprints:TP_SMD_0.75mm" (layer "B.Cu")
    (tedit 5E4A9375)
    (at 137.2 131.9492)
    (property "Author" "Antmicro")
    (property "License" "Apache-2.0")
    (property "MPN" "")
    (property "Manufacturer" "")
    (property "Sheetfile" "hdmi-converter.kicad_sch")
    (property "Sheetname" "HDMI converter")
    (attr smd)
    (fp_text reference "TP16" (at 0.62 1.2408 180) (layer "B.SilkS")
      (effects (font (size 0.7 0.7) (thickness 0.15)) (justify left bottom mirror))
    )
    (fp_text value "TP_0.75mm_SMD" (at 0 -1.2 180) (layer "B.Fab")
      (effects (font (size 0.7 0.7) (thickness 0.15)) (justify left bottom mirror))
    )
    (fp_text user "License: Apache-2.0" (at -0.4 -5.101 180) (layer "B.Fab") hide
      (effects (font (size 0.7 0.7) (thickness 0.15)) (justify left bottom mirror))
    )
    (fp_text user "Author: Antmicro" (at -0.4 -3.901 180) (layer "B.Fab") hide
      (effects (font (size 0.7 0.7) (thickness 0.15)) (justify left bottom mirror))
    )
    (fp_text user "${REFERENCE}" (at -0.4 -2.7 180) (layer "B.Fab") hide
      (effects (font (size 0.7 0.7) (thickness 0.15)) (justify left bottom mirror))
    )
    (pad "1" smd circle (at 0 0) (size 0.75 0.75) (layers "B.Cu" "B.Mask")
      (net 232 "/HDMI converter/HDMI_SCL") (pinfunction "1") (pintype "passive"))
  )

  (footprint "sa800u-baseboard-hw-footprints:TP_SMD_0.75mm" (layer "B.Cu")
    (tedit 5E4A9375)
    (at 137.2 130.8)
    (property "Author" "Antmicro")
    (property "License" "Apache-2.0")
    (property "MPN" "")
    (property "Manufacturer" "")
    (property "Sheetfile" "hdmi-converter.kicad_sch")
    (property "Sheetname" "HDMI converter")
    (attr smd)
    (fp_text reference "TP19" (at -0.32 1.14 180) (layer "B.SilkS")
      (effects (font (size 0.7 0.7) (thickness 0.15)) (justify left bottom mirror))
    )
    (fp_text value "TP_0.75mm_SMD" (at 0 -1.2 180) (layer "B.Fab")
      (effects (font (size 0.7 0.7) (thickness 0.15)) (justify left bottom mirror))
    )
    (fp_text user "${REFERENCE}" (at -0.4 -2.7 180) (layer "B.Fab") hide
      (effects (font (size 0.7 0.7) (thickness 0.15)) (justify left bottom mirror))
    )
    (fp_text user "License: Apache-2.0" (at -0.4 -5.101 180) (layer "B.Fab") hide
      (effects (font (size 0.7 0.7) (thickness 0.15)) (justify left bottom mirror))
    )
    (fp_text user "Author: Antmicro" (at -0.4 -3.901 180) (layer "B.Fab") hide
      (effects (font (size 0.7 0.7) (thickness 0.15)) (justify left bottom mirror))
    )
    (pad "1" smd circle (at 0 0) (size 0.75 0.75) (layers "B.Cu" "B.Mask")
      (net 235 "/HDMI converter/HDMI_SDA") (pinfunction "1") (pintype "passive"))
  )

  (footprint "sa800u-baseboard-hw-footprints:TP_SMD_0.75mm" (layer "B.Cu")
    (tedit 5E4A9375)
    (at 142 126.5)
    (property "Author" "Antmicro")
    (property "License" "Apache-2.0")
    (property "MPN" "")
    (property "Manufacturer" "")
    (property "Sheetfile" "hdmi-converter.kicad_sch")
    (property "Sheetname" "HDMI converter")
    (attr smd)
    (fp_text reference "TP20" (at 1.09 -0.31 180) (layer "B.SilkS")
      (effects (font (size 0.7 0.7) (thickness 0.15)) (justify left bottom mirror))
    )
    (fp_text value "TP_0.75mm_SMD" (at 0 -1.2 180) (layer "B.Fab")
      (effects (font (size 0.7 0.7) (thickness 0.15)) (justify left bottom mirror))
    )
    (fp_text user "${REFERENCE}" (at -0.4 -2.7 180) (layer "B.Fab") hide
      (effects (font (size 0.7 0.7) (thickness 0.15)) (justify left bottom mirror))
    )
    (fp_text user "Author: Antmicro" (at -0.4 -3.901 180) (layer "B.Fab") hide
      (effects (font (size 0.7 0.7) (thickness 0.15)) (justify left bottom mirror))
    )
    (fp_text user "License: Apache-2.0" (at -0.4 -5.101 180) (layer "B.Fab") hide
      (effects (font (size 0.7 0.7) (thickness 0.15)) (justify left bottom mirror))
    )
    (pad "1" smd circle (at 0 0) (size 0.75 0.75) (layers "B.Cu" "B.Mask")
      (net 285 "/HDMI converter/LT9611_CEC") (pinfunction "1") (pintype "passive"))
  )

  (footprint "sa800u-baseboard-hw-footprints:TP_SMD_0.75mm" (layer "B.Cu")
    (tedit 5E4A9375)
    (at 143.3 141.15)
    (property "Author" "Antmicro")
    (property "License" "Apache-2.0")
    (property "MPN" "")
    (property "Manufacturer" "")
    (property "Sheetfile" "hdmi-converter.kicad_sch")
    (property "Sheetname" "HDMI converter")
    (attr smd)
    (fp_text reference "TP21" (at -0.35 0.35 180) (layer "B.SilkS")
      (effects (font (size 0.7 0.7) (thickness 0.15)) (justify left bottom mirror))
    )
    (fp_text value "TP_0.75mm_SMD" (at 0 -1.2 180) (layer "B.Fab")
      (effects (font (size 0.7 0.7) (thickness 0.15)) (justify left bottom mirror))
    )
    (fp_text user "Author: Antmicro" (at -0.4 -3.901 180) (layer "B.Fab") hide
      (effects (font (size 0.7 0.7) (thickness 0.15)) (justify left bottom mirror))
    )
    (fp_text user "${REFERENCE}" (at -0.4 -2.7 180) (layer "B.Fab") hide
      (effects (font (size 0.7 0.7) (thickness 0.15)) (justify left bottom mirror))
    )
    (fp_text user "License: Apache-2.0" (at -0.4 -5.101 180) (layer "B.Fab") hide
      (effects (font (size 0.7 0.7) (thickness 0.15)) (justify left bottom mirror))
    )
    (pad "1" smd circle (at 0 0) (size 0.75 0.75) (layers "B.Cu" "B.Mask")
      (net 234 "/HDMI converter/HDMI_DETECT") (pinfunction "1") (pintype "passive"))
  )

  (footprint "sa800u-baseboard-hw-footprints:TP_SMD_0.75mm" (layer "B.Cu")
    (tedit 5E4A9375)
    (at 142.05 136.9992)
    (property "Author" "Antmicro")
    (property "License" "Apache-2.0")
    (property "MPN" "")
    (property "Manufacturer" "")
    (property "Sheetfile" "hdmi-converter.kicad_sch")
    (property "Sheetname" "HDMI converter")
    (attr smd)
    (fp_text reference "TP22" (at -0.26 0.3608 180) (layer "B.SilkS")
      (effects (font (size 0.7 0.7) (thickness 0.15)) (justify left bottom mirror))
    )
    (fp_text value "TP_0.75mm_SMD" (at 0 -1.2 180) (layer "B.Fab")
      (effects (font (size 0.7 0.7) (thickness 0.15)) (justify left bottom mirror))
    )
    (fp_text user "Author: Antmicro" (at -0.4 -3.901 180) (layer "B.Fab") hide
      (effects (font (size 0.7 0.7) (thickness 0.15)) (justify left bottom mirror))
    )
    (fp_text user "${REFERENCE}" (at -0.4 -2.7 180) (layer "B.Fab") hide
      (effects (font (size 0.7 0.7) (thickness 0.15)) (justify left bottom mirror))
    )
    (fp_text user "License: Apache-2.0" (at -0.4 -5.101 180) (layer "B.Fab") hide
      (effects (font (size 0.7 0.7) (thickness 0.15)) (justify left bottom mirror))
    )
    (pad "1" smd circle (at 0 0) (size 0.75 0.75) (layers "B.Cu" "B.Mask")
      (net 209 "/HDMI converter/VCOM") (pinfunction "1") (pintype "passive"))
  )

  (footprint "sa800u-baseboard-hw-footprints:TP_SMD_0.75mm" (layer "B.Cu")
    (tedit 5E4A9375)
    (at 132.2 108.8)
    (property "Author" "Antmicro")
    (property "License" "Apache-2.0")
    (property "MPN" "")
    (property "Manufacturer" "")
    (property "Sheetfile" "hdmi-converter.kicad_sch")
    (property "Sheetname" "HDMI converter")
    (attr smd)
    (fp_text reference "TP23" (at 0.44 0.34 270) (layer "B.SilkS")
      (effects (font (size 0.7 0.7) (thickness 0.15)) (justify left bottom mirror))
    )
    (fp_text value "TP_0.75mm_SMD" (at 0 -1.2 180) (layer "B.Fab")
      (effects (font (size 0.7 0.7) (thickness 0.15)) (justify left bottom mirror))
    )
    (fp_text user "License: Apache-2.0" (at -0.4 -5.101 180) (layer "B.Fab") hide
      (effects (font (size 0.7 0.7) (thickness 0.15)) (justify left bottom mirror))
    )
    (fp_text user "Author: Antmicro" (at -0.4 -3.901 180) (layer "B.Fab") hide
      (effects (font (size 0.7 0.7) (thickness 0.15)) (justify left bottom mirror))
    )
    (fp_text user "${REFERENCE}" (at -0.4 -2.7 180) (layer "B.Fab") hide
      (effects (font (size 0.7 0.7) (thickness 0.15)) (justify left bottom mirror))
    )
    (pad "1" smd circle (at 0 0) (size 0.75 0.75) (layers "B.Cu" "B.Mask")
      (net 40 "I2C4_SDA") (pinfunction "1") (pintype "passive"))
  )

  (footprint "sa800u-baseboard-hw-footprints:TP_SMD_0.75mm" (layer "B.Cu")
    (tedit 5E4A9375)
    (at 128.9 106)
    (property "Author" "Antmicro")
    (property "License" "Apache-2.0")
    (property "MPN" "")
    (property "Manufacturer" "")
    (property "Sheetfile" "hdmi-converter.kicad_sch")
    (property "Sheetname" "HDMI converter")
    (attr smd)
    (fp_text reference "TP24" (at -0.26 0.36 180) (layer "B.SilkS")
      (effects (font (size 0.7 0.7) (thickness 0.15)) (justify left bottom mirror))
    )
    (fp_text value "TP_0.75mm_SMD" (at 0 -1.2 180) (layer "B.Fab")
      (effects (font (size 0.7 0.7) (thickness 0.15)) (justify left bottom mirror))
    )
    (fp_text user "Author: Antmicro" (at -0.4 -3.901 180) (layer "B.Fab") hide
      (effects (font (size 0.7 0.7) (thickness 0.15)) (justify left bottom mirror))
    )
    (fp_text user "License: Apache-2.0" (at -0.4 -5.101 180) (layer "B.Fab") hide
      (effects (font (size 0.7 0.7) (thickness 0.15)) (justify left bottom mirror))
    )
    (fp_text user "${REFERENCE}" (at -0.4 -2.7 180) (layer "B.Fab") hide
      (effects (font (size 0.7 0.7) (thickness 0.15)) (justify left bottom mirror))
    )
    (pad "1" smd circle (at 0 0) (size 0.75 0.75) (layers "B.Cu" "B.Mask")
      (net 41 "I2C4_SCL") (pinfunction "1") (pintype "passive"))
  )

  (footprint "sa800u-baseboard-hw-footprints:TP_SMD_0.75mm" (layer "B.Cu")
    (tedit 5E4A9375)
    (at 142 125)
    (property "Author" "Antmicro")
    (property "License" "Apache-2.0")
    (property "MPN" "")
    (property "Manufacturer" "")
    (property "Sheetfile" "hdmi-converter.kicad_sch")
    (property "Sheetname" "HDMI converter")
    (attr smd)
    (fp_text reference "TP25" (at 1.13 -0.32 180) (layer "B.SilkS")
      (effects (font (size 0.7 0.7) (thickness 0.15)) (justify left bottom mirror))
    )
    (fp_text value "TP_0.75mm_SMD" (at 0 -1.2 180) (layer "B.Fab")
      (effects (font (size 0.7 0.7) (thickness 0.15)) (justify left bottom mirror))
    )
    (fp_text user "License: Apache-2.0" (at -0.4 -5.101 180) (layer "B.Fab") hide
      (effects (font (size 0.7 0.7) (thickness 0.15)) (justify left bottom mirror))
    )
    (fp_text user "${REFERENCE}" (at -0.4 -2.7 180) (layer "B.Fab") hide
      (effects (font (size 0.7 0.7) (thickness 0.15)) (justify left bottom mirror))
    )
    (fp_text user "Author: Antmicro" (at -0.4 -3.901 180) (layer "B.Fab") hide
      (effects (font (size 0.7 0.7) (thickness 0.15)) (justify left bottom mirror))
    )
    (pad "1" smd circle (at 0 0) (size 0.75 0.75) (layers "B.Cu" "B.Mask")
      (net 287 "/HDMI converter/LT9611_SCL") (pinfunction "1") (pintype "passive"))
  )

  (footprint "sa800u-baseboard-hw-footprints:TP_SMD_0.75mm" (layer "B.Cu")
    (tedit 5E4A9375)
    (at 140.25 125)
    (property "Author" "Antmicro")
    (property "License" "Apache-2.0")
    (property "MPN" "")
    (property "Manufacturer" "")
    (property "Sheetfile" "hdmi-converter.kicad_sch")
    (property "Sheetname" "HDMI converter")
    (attr smd)
    (fp_text reference "TP26" (at -0.29 0.35 180) (layer "B.SilkS")
      (effects (font (size 0.7 0.7) (thickness 0.15)) (justify left bottom mirror))
    )
    (fp_text value "TP_0.75mm_SMD" (at 0 -1.2 180) (layer "B.Fab")
      (effects (font (size 0.7 0.7) (thickness 0.15)) (justify left bottom mirror))
    )
    (fp_text user "Author: Antmicro" (at -0.4 -3.901 180) (layer "B.Fab") hide
      (effects (font (size 0.7 0.7) (thickness 0.15)) (justify left bottom mirror))
    )
    (fp_text user "License: Apache-2.0" (at -0.4 -5.101 180) (layer "B.Fab") hide
      (effects (font (size 0.7 0.7) (thickness 0.15)) (justify left bottom mirror))
    )
    (fp_text user "${REFERENCE}" (at -0.4 -2.7 180) (layer "B.Fab") hide
      (effects (font (size 0.7 0.7) (thickness 0.15)) (justify left bottom mirror))
    )
    (pad "1" smd circle (at 0 0) (size 0.75 0.75) (layers "B.Cu" "B.Mask")
      (net 288 "/HDMI converter/LT9611_SDA") (pinfunction "1") (pintype "passive"))
  )

  (footprint "sa800u-baseboard-hw-footprints:TP_SMD_0.75mm" (layer "B.Cu")
    (tedit 5E4A9375)
    (at 109.6 94.1)
    (property "Author" "Antmicro")
    (property "License" "Apache-2.0")
    (property "MPN" "")
    (property "Manufacturer" "")
    (property "Sheetfile" "camera-interface.kicad_sch")
    (property "Sheetname" "Camera Interface")
    (attr smd)
    (fp_text reference "TP30" (at 1.11 1.29 180) (layer "B.SilkS")
      (effects (font (size 0.7 0.7) (thickness 0.15)) (justify left bottom mirror))
    )
    (fp_text value "TP_0.75mm_SMD" (at 0 -1.2 180) (layer "B.Fab")
      (effects (font (size 0.7 0.7) (thickness 0.15)) (justify left bottom mirror))
    )
    (fp_text user "Author: Antmicro" (at -0.4 -3.901 180) (layer "B.Fab") hide
      (effects (font (size 0.7 0.7) (thickness 0.15)) (justify left bottom mirror))
    )
    (fp_text user "License: Apache-2.0" (at -0.4 -5.101 180) (layer "B.Fab") hide
      (effects (font (size 0.7 0.7) (thickness 0.15)) (justify left bottom mirror))
    )
    (fp_text user "${REFERENCE}" (at -0.4 -2.7 180) (layer "B.Fab") hide
      (effects (font (size 0.7 0.7) (thickness 0.15)) (justify left bottom mirror))
    )
    (pad "1" smd circle (at 0 0) (size 0.75 0.75) (layers "B.Cu" "B.Mask")
      (net 43 "CCI0_I2C_SDA") (pinfunction "1") (pintype "passive"))
  )

  (footprint "sa800u-baseboard-hw-footprints:TP_SMD_0.75mm" (layer "B.Cu")
    (tedit 5E4A9375)
    (at 117.4 92.7)
    (property "Author" "Antmicro")
    (property "License" "Apache-2.0")
    (property "MPN" "")
    (property "Manufacturer" "")
    (property "Sheetfile" "camera-interface.kicad_sch")
    (property "Sheetname" "Camera Interface")
    (attr smd)
    (fp_text reference "TP34" (at 1.22 -0.42 180) (layer "B.SilkS")
      (effects (font (size 0.7 0.7) (thickness 0.15)) (justify left bottom mirror))
    )
    (fp_text value "TP_0.75mm_SMD" (at 0 -1.2 180) (layer "B.Fab")
      (effects (font (size 0.7 0.7) (thickness 0.15)) (justify left bottom mirror))
    )
    (fp_text user "${REFERENCE}" (at -0.4 -2.7 180) (layer "B.Fab") hide
      (effects (font (size 0.7 0.7) (thickness 0.15)) (justify left bottom mirror))
    )
    (fp_text user "License: Apache-2.0" (at -0.4 -5.101 180) (layer "B.Fab") hide
      (effects (font (size 0.7 0.7) (thickness 0.15)) (justify left bottom mirror))
    )
    (fp_text user "Author: Antmicro" (at -0.4 -3.901 180) (layer "B.Fab") hide
      (effects (font (size 0.7 0.7) (thickness 0.15)) (justify left bottom mirror))
    )
    (pad "1" smd circle (at 0 0) (size 0.75 0.75) (layers "B.Cu" "B.Mask")
      (net 231 "/Camera Interface/3V3_CAM") (pinfunction "1") (pintype "passive"))
  )

  (footprint "sa800u-baseboard-hw-footprints:TP_SMD_0.75mm" (layer "B.Cu")
    (tedit 5E4A9375)
    (at 111.15 92.26)
    (property "Author" "Antmicro")
    (property "License" "Apache-2.0")
    (property "MPN" "")
    (property "Manufacturer" "")
    (property "Sheetfile" "camera-interface.kicad_sch")
    (property "Sheetname" "Camera Interface")
    (attr smd)
    (fp_text reference "TP36" (at 1.67 -0.4592 180) (layer "B.SilkS")
      (effects (font (size 0.7 0.7) (thickness 0.15)) (justify left bottom mirror))
    )
    (fp_text value "TP_0.75mm_SMD" (at 0 -1.2 180) (layer "B.Fab")
      (effects (font (size 0.7 0.7) (thickness 0.15)) (justify left bottom mirror))
    )
    (fp_text user "Author: Antmicro" (at -0.4 -3.901 180) (layer "B.Fab") hide
      (effects (font (size 0.7 0.7) (thickness 0.15)) (justify left bottom mirror))
    )
    (fp_text user "${REFERENCE}" (at -0.4 -2.7 180) (layer "B.Fab") hide
      (effects (font (size 0.7 0.7) (thickness 0.15)) (justify left bottom mirror))
    )
    (fp_text user "License: Apache-2.0" (at -0.4 -5.101 180) (layer "B.Fab") hide
      (effects (font (size 0.7 0.7) (thickness 0.15)) (justify left bottom mirror))
    )
    (pad "1" smd circle (at 0 0) (size 0.75 0.75) (layers "B.Cu" "B.Mask")
      (net 294 "/Camera Interface/CCI0_I2C_SCL_3V3") (pinfunction "1") (pintype "passive"))
  )

  (footprint "sa800u-baseboard-hw-footprints:TP_SMD_0.75mm" (layer "B.Cu")
    (tedit 5E4A9375)
    (at 112.97 92.81)
    (property "Author" "Antmicro")
    (property "License" "Apache-2.0")
    (property "MPN" "")
    (property "Manufacturer" "")
    (property "Sheetfile" "camera-interface.kicad_sch")
    (property "Sheetname" "Camera Interface")
    (attr smd)
    (fp_text reference "TP37" (at 1.47 1.27 180) (layer "B.SilkS")
      (effects (font (size 0.7 0.7) (thickness 0.15)) (justify left bottom mirror))
    )
    (fp_text value "TP_0.75mm_SMD" (at 0 -1.2 180) (layer "B.Fab")
      (effects (font (size 0.7 0.7) (thickness 0.15)) (justify left bottom mirror))
    )
    (fp_text user "Author: Antmicro" (at -0.4 -3.901 180) (layer "B.Fab") hide
      (effects (font (size 0.7 0.7) (thickness 0.15)) (justify left bottom mirror))
    )
    (fp_text user "License: Apache-2.0" (at -0.4 -5.101 180) (layer "B.Fab") hide
      (effects (font (size 0.7 0.7) (thickness 0.15)) (justify left bottom mirror))
    )
    (fp_text user "${REFERENCE}" (at -0.4 -2.7 180) (layer "B.Fab") hide
      (effects (font (size 0.7 0.7) (thickness 0.15)) (justify left bottom mirror))
    )
    (pad "1" smd circle (at 0 0) (size 0.75 0.75) (layers "B.Cu" "B.Mask")
      (net 295 "/Camera Interface/CCI1_I2C_SDA_3V3") (pinfunction "1") (pintype "passive"))
  )

  (footprint "sa800u-baseboard-hw-footprints:TP_SMD_0.75mm" (layer "B.Cu")
    (tedit 5E4A9375)
    (at 109.8 92.0492)
    (property "Author" "Antmicro")
    (property "License" "Apache-2.0")
    (property "MPN" "")
    (property "Manufacturer" "")
    (property "Sheetfile" "camera-interface.kicad_sch")
    (property "Sheetname" "Camera Interface")
    (attr smd)
    (fp_text reference "TP38" (at 0.93 1.2308 180) (layer "B.SilkS")
      (effects (font (size 0.7 0.7) (thickness 0.15)) (justify left bottom mirror))
    )
    (fp_text value "TP_0.75mm_SMD" (at 0 -1.2 180) (layer "B.Fab")
      (effects (font (size 0.7 0.7) (thickness 0.15)) (justify left bottom mirror))
    )
    (fp_text user "License: Apache-2.0" (at -0.4 -5.101 180) (layer "B.Fab") hide
      (effects (font (size 0.7 0.7) (thickness 0.15)) (justify left bottom mirror))
    )
    (fp_text user "Author: Antmicro" (at -0.4 -3.901 180) (layer "B.Fab") hide
      (effects (font (size 0.7 0.7) (thickness 0.15)) (justify left bottom mirror))
    )
    (fp_text user "${REFERENCE}" (at -0.4 -2.7 180) (layer "B.Fab") hide
      (effects (font (size 0.7 0.7) (thickness 0.15)) (justify left bottom mirror))
    )
    (pad "1" smd circle (at 0 0) (size 0.75 0.75) (layers "B.Cu" "B.Mask")
      (net 296 "/Camera Interface/CCI0_I2C_SDA_3V3") (pinfunction "1") (pintype "passive"))
  )

  (footprint "sa800u-baseboard-hw-footprints:TP_SMD_0.75mm" (layer "B.Cu")
    (tedit 5E4A9375)
    (at 82.4 120.4)
    (property "Author" "Antmicro")
    (property "License" "Apache-2.0")
    (property "MPN" "")
    (property "Manufacturer" "")
    (property "Sheetfile" "psu.kicad_sch")
    (property "Sheetname" "PSU")
    (attr smd)
    (fp_text reference "TP59" (at 0.42 -3.01 90) (layer "B.SilkS")
      (effects (font (size 0.7 0.7) (thickness 0.15)) (justify left bottom mirror))
    )
    (fp_text value "TP_0.75mm_SMD" (at 0 -1.2 180) (layer "B.Fab")
      (effects (font (size 0.7 0.7) (thickness 0.15)) (justify left bottom mirror))
    )
    (fp_text user "License: Apache-2.0" (at -0.4 -5.101 180) (layer "B.Fab") hide
      (effects (font (size 0.7 0.7) (thickness 0.15)) (justify left bottom mirror))
    )
    (fp_text user "${REFERENCE}" (at -0.4 -2.7 180) (layer "B.Fab") hide
      (effects (font (size 0.7 0.7) (thickness 0.15)) (justify left bottom mirror))
    )
    (fp_text user "Author: Antmicro" (at -0.4 -3.901 180) (layer "B.Fab") hide
      (effects (font (size 0.7 0.7) (thickness 0.15)) (justify left bottom mirror))
    )
    (pad "1" smd circle (at 0 0) (size 0.75 0.75) (layers "B.Cu" "B.Mask")
      (net 405 "Net-(R123-Pad2)") (pinfunction "1") (pintype "passive"))
  )

  (footprint "sa800u-baseboard-hw-footprints:TP_SMD_0.75mm" (layer "B.Cu")
    (tedit 5E4A9375)
    (at 76 122.3492)
    (property "Author" "Antmicro")
    (property "License" "Apache-2.0")
    (property "MPN" "")
    (property "Manufacturer" "")
    (property "Sheetfile" "psu.kicad_sch")
    (property "Sheetname" "PSU")
    (attr smd)
    (fp_text reference "TP60" (at -0.46 -0.4992 270) (layer "B.SilkS")
      (effects (font (size 0.7 0.7) (thickness 0.15)) (justify left bottom mirror))
    )
    (fp_text value "TP_0.75mm_SMD" (at 0 -1.2 180) (layer "B.Fab")
      (effects (font (size 0.7 0.7) (thickness 0.15)) (justify left bottom mirror))
    )
    (fp_text user "License: Apache-2.0" (at -0.4 -5.101 180) (layer "B.Fab") hide
      (effects (font (size 0.7 0.7) (thickness 0.15)) (justify left bottom mirror))
    )
    (fp_text user "Author: Antmicro" (at -0.4 -3.901 180) (layer "B.Fab") hide
      (effects (font (size 0.7 0.7) (thickness 0.15)) (justify left bottom mirror))
    )
    (fp_text user "${REFERENCE}" (at -0.4 -2.7 180) (layer "B.Fab") hide
      (effects (font (size 0.7 0.7) (thickness 0.15)) (justify left bottom mirror))
    )
    (pad "1" smd circle (at 0 0) (size 0.75 0.75) (layers "B.Cu" "B.Mask")
      (net 406 "Net-(R125-Pad2)") (pinfunction "1") (pintype "passive"))
  )

  (footprint "sa800u-baseboard-hw-footprints:TP_SMD_0.75mm" (layer "B.Cu")
    (tedit 5E4A9375)
    (at 87 117.2)
    (property "Author" "Antmicro")
    (property "License" "Apache-2.0")
    (property "MPN" "")
    (property "Manufacturer" "")
    (property "Sheetfile" "psu.kicad_sch")
    (property "Sheetname" "PSU")
    (attr smd)
    (fp_text reference "TP67" (at 0.43 -3.09 270) (layer "B.SilkS")
      (effects (font (size 0.7 0.7) (thickness 0.15)) (justify left bottom mirror))
    )
    (fp_text value "TP_0.75mm_SMD" (at 0 -1.2 180) (layer "B.Fab")
      (effects (font (size 0.7 0.7) (thickness 0.15)) (justify left bottom mirror))
    )
    (fp_text user "${REFERENCE}" (at -0.4 -2.7 180) (layer "B.Fab") hide
      (effects (font (size 0.7 0.7) (thickness 0.15)) (justify left bottom mirror))
    )
    (fp_text user "Author: Antmicro" (at -0.4 -3.901 180) (layer "B.Fab") hide
      (effects (font (size 0.7 0.7) (thickness 0.15)) (justify left bottom mirror))
    )
    (fp_text user "License: Apache-2.0" (at -0.4 -5.101 180) (layer "B.Fab") hide
      (effects (font (size 0.7 0.7) (thickness 0.15)) (justify left bottom mirror))
    )
    (pad "1" smd circle (at 0 0) (size 0.75 0.75) (layers "B.Cu" "B.Mask")
      (net 156 "/PSU/BYPASS_EN") (pinfunction "1") (pintype "passive"))
  )

  (footprint "sa800u-baseboard-hw-footprints:TP_SMD_0.75mm" (layer "B.Cu")
    (tedit 5E4A9375)
    (at 88.4 117.2)
    (property "Author" "Antmicro")
    (property "License" "Apache-2.0")
    (property "MPN" "")
    (property "Manufacturer" "")
    (property "Sheetfile" "psu.kicad_sch")
    (property "Sheetname" "PSU")
    (attr smd)
    (fp_text reference "TP69" (at 0.19 -3.05 270) (layer "B.SilkS")
      (effects (font (size 0.7 0.7) (thickness 0.15)) (justify left bottom mirror))
    )
    (fp_text value "TP_0.75mm_SMD" (at 0 -1.2 180) (layer "B.Fab")
      (effects (font (size 0.7 0.7) (thickness 0.15)) (justify left bottom mirror))
    )
    (fp_text user "License: Apache-2.0" (at -0.4 -5.101 180) (layer "B.Fab") hide
      (effects (font (size 0.7 0.7) (thickness 0.15)) (justify left bottom mirror))
    )
    (fp_text user "${REFERENCE}" (at -0.4 -2.7 180) (layer "B.Fab") hide
      (effects (font (size 0.7 0.7) (thickness 0.15)) (justify left bottom mirror))
    )
    (fp_text user "Author: Antmicro" (at -0.4 -3.901 180) (layer "B.Fab") hide
      (effects (font (size 0.7 0.7) (thickness 0.15)) (justify left bottom mirror))
    )
    (pad "1" smd circle (at 0 0) (size 0.75 0.75) (layers "B.Cu" "B.Mask")
      (net 164 "/PSU/5V_DC_DC_ENABLE") (pinfunction "1") (pintype "passive"))
  )

  (footprint "sa800u-baseboard-hw-footprints:TP_SMD_0.75mm" (layer "B.Cu")
    (tedit 5E4A9375)
    (at 87.4 98.2)
    (property "Author" "Antmicro")
    (property "License" "Apache-2.0")
    (property "MPN" "")
    (property "Manufacturer" "")
    (property "Sheetfile" "psu.kicad_sch")
    (property "Sheetname" "PSU")
    (attr smd)
    (fp_text reference "TP64" (at 1.24 -0.49 180) (layer "B.SilkS")
      (effects (font (size 0.7 0.7) (thickness 0.15)) (justify left bottom mirror))
    )
    (fp_text value "TP_0.75mm_SMD" (at 0 -1.2 180) (layer "B.Fab")
      (effects (font (size 0.7 0.7) (thickness 0.15)) (justify left bottom mirror))
    )
    (fp_text user "Author: Antmicro" (at -0.4 -3.901 180) (layer "B.Fab") hide
      (effects (font (size 0.7 0.7) (thickness 0.15)) (justify left bottom mirror))
    )
    (fp_text user "License: Apache-2.0" (at -0.4 -5.101 180) (layer "B.Fab") hide
      (effects (font (size 0.7 0.7) (thickness 0.15)) (justify left bottom mirror))
    )
    (fp_text user "${REFERENCE}" (at -0.4 -2.7 180) (layer "B.Fab") hide
      (effects (font (size 0.7 0.7) (thickness 0.15)) (justify left bottom mirror))
    )
    (pad "1" smd circle (at 0 0) (size 0.75 0.75) (layers "B.Cu" "B.Mask")
      (net 409 "Net-(R131-Pad2)") (pinfunction "1") (pintype "passive"))
  )

  (footprint "sa800u-baseboard-hw-footprints:TP_SMD_0.75mm" (layer "B.Cu")
    (tedit 5E4A9375)
    (at 78.4 110.2)
    (property "Author" "Antmicro")
    (property "License" "Apache-2.0")
    (property "MPN" "")
    (property "Manufacturer" "")
    (property "Sheetfile" "psu.kicad_sch")
    (property "Sheetname" "PSU")
    (attr smd)
    (fp_text reference "TP65" (at 1.13 -0.4 180) (layer "B.SilkS")
      (effects (font (size 0.7 0.7) (thickness 0.15)) (justify left bottom mirror))
    )
    (fp_text value "TP_0.75mm_SMD" (at 0 -1.2 180) (layer "B.Fab")
      (effects (font (size 0.7 0.7) (thickness 0.15)) (justify left bottom mirror))
    )
    (fp_text user "Author: Antmicro" (at -0.4 -3.901 180) (layer "B.Fab") hide
      (effects (font (size 0.7 0.7) (thickness 0.15)) (justify left bottom mirror))
    )
    (fp_text user "${REFERENCE}" (at -0.4 -2.7 180) (layer "B.Fab") hide
      (effects (font (size 0.7 0.7) (thickness 0.15)) (justify left bottom mirror))
    )
    (fp_text user "License: Apache-2.0" (at -0.4 -5.101 180) (layer "B.Fab") hide
      (effects (font (size 0.7 0.7) (thickness 0.15)) (justify left bottom mirror))
    )
    (pad "1" smd circle (at 0 0) (size 0.75 0.75) (layers "B.Cu" "B.Mask")
      (net 407 "Net-(R127-Pad2)") (pinfunction "1") (pintype "passive"))
  )

  (footprint "sa800u-baseboard-hw-footprints:TP_SMD_0.75mm" (layer "B.Cu")
    (tedit 5E4A9375)
    (at 123.4 126.2)
    (property "Author" "Antmicro")
    (property "License" "Apache-2.0")
    (property "MPN" "")
    (property "Manufacturer" "")
    (property "Sheetfile" "psu.kicad_sch")
    (property "Sheetname" "PSU")
    (attr smd)
    (fp_text reference "TP66" (at -0.32 0.38 180) (layer "B.SilkS")
      (effects (font (size 0.7 0.7) (thickness 0.15)) (justify left bottom mirror))
    )
    (fp_text value "TP_0.75mm_SMD" (at 0 -1.2 180) (layer "B.Fab")
      (effects (font (size 0.7 0.7) (thickness 0.15)) (justify left bottom mirror))
    )
    (fp_text user "License: Apache-2.0" (at -0.4 -5.101 180) (layer "B.Fab") hide
      (effects (font (size 0.7 0.7) (thickness 0.15)) (justify left bottom mirror))
    )
    (fp_text user "Author: Antmicro" (at -0.4 -3.901 180) (layer "B.Fab") hide
      (effects (font (size 0.7 0.7) (thickness 0.15)) (justify left bottom mirror))
    )
    (fp_text user "${REFERENCE}" (at -0.4 -2.7 180) (layer "B.Fab") hide
      (effects (font (size 0.7 0.7) (thickness 0.15)) (justify left bottom mirror))
    )
    (pad "1" smd circle (at 0 0) (size 0.75 0.75) (layers "B.Cu" "B.Mask")
      (net 408 "Net-(R128-Pad2)") (pinfunction "1") (pintype "passive"))
  )

  (footprint "sa800u-baseboard-hw-footprints:TP_SMD_0.75mm" (layer "B.Cu")
    (tedit 5E4A9375)
    (at 94.9 129.5 90)
    (property "Author" "Antmicro")
    (property "License" "Apache-2.0")
    (property "MPN" "")
    (property "Manufacturer" "")
    (property "Sheetfile" "usb-pd.kicad_sch")
    (property "Sheetname" "USB-PD")
    (attr smd)
    (fp_text reference "TP89" (at -0.37 -0.36) (layer "B.SilkS")
      (effects (font (size 0.7 0.7) (thickness 0.15)) (justify left bottom mirror))
    )
    (fp_text value "TP_0.75mm_SMD" (at 0 -1.2 270) (layer "B.Fab")
      (effects (font (size 0.7 0.7) (thickness 0.15)) (justify left bottom mirror))
    )
    (fp_text user "License: Apache-2.0" (at -0.4 -5.101 270) (layer "B.Fab") hide
      (effects (font (size 0.7 0.7) (thickness 0.15)) (justify left bottom mirror))
    )
    (fp_text user "Author: Antmicro" (at -0.4 -3.901 270) (layer "B.Fab") hide
      (effects (font (size 0.7 0.7) (thickness 0.15)) (justify left bottom mirror))
    )
    (fp_text user "${REFERENCE}" (at -0.4 -2.7 270) (layer "B.Fab") hide
      (effects (font (size 0.7 0.7) (thickness 0.15)) (justify left bottom mirror))
    )
    (pad "1" smd circle (at 0 0 90) (size 0.75 0.75) (layers "B.Cu" "B.Mask")
      (net 332 "/USB-PD/ALERT") (pinfunction "1") (pintype "passive"))
  )

  (footprint "sa800u-baseboard-hw-footprints:TP_SMD_0.75mm" (layer "B.Cu")
    (tedit 5E4A9375)
    (at 95 127)
    (property "Author" "Antmicro")
    (property "License" "Apache-2.0")
    (property "MPN" "")
    (property "Manufacturer" "")
    (property "Sheetfile" "usb-pd.kicad_sch")
    (property "Sheetname" "USB-PD")
    (attr smd)
    (fp_text reference "TP91" (at -0.31 0.37 180) (layer "B.SilkS")
      (effects (font (size 0.7 0.7) (thickness 0.15)) (justify left bottom mirror))
    )
    (fp_text value "TP_0.75mm_SMD" (at 0 -1.2 180) (layer "B.Fab")
      (effects (font (size 0.7 0.7) (thickness 0.15)) (justify left bottom mirror))
    )
    (fp_text user "${REFERENCE}" (at -0.4 -2.7 180) (layer "B.Fab") hide
      (effects (font (size 0.7 0.7) (thickness 0.15)) (justify left bottom mirror))
    )
    (fp_text user "Author: Antmicro" (at -0.4 -3.901 180) (layer "B.Fab") hide
      (effects (font (size 0.7 0.7) (thickness 0.15)) (justify left bottom mirror))
    )
    (fp_text user "License: Apache-2.0" (at -0.4 -5.101 180) (layer "B.Fab") hide
      (effects (font (size 0.7 0.7) (thickness 0.15)) (justify left bottom mirror))
    )
    (pad "1" smd circle (at 0 0) (size 0.75 0.75) (layers "B.Cu" "B.Mask")
      (net 333 "/USB-PD/AB_SIDE") (pinfunction "1") (pintype "passive"))
  )

  (footprint "sa800u-baseboard-hw-footprints:TP_SMD_0.75mm" (layer "B.Cu")
    (tedit 5E4A9375)
    (at 94.95 125.8 90)
    (property "Author" "Antmicro")
    (property "License" "Apache-2.0")
    (property "MPN" "")
    (property "Manufacturer" "")
    (property "Sheetfile" "usb-pd.kicad_sch")
    (property "Sheetname" "USB-PD")
    (attr smd)
    (fp_text reference "TP95" (at -0.27 -0.3) (layer "B.SilkS")
      (effects (font (size 0.7 0.7) (thickness 0.15)) (justify left bottom mirror))
    )
    (fp_text value "TP_0.75mm_SMD" (at 0 -1.2 270) (layer "B.Fab")
      (effects (font (size 0.7 0.7) (thickness 0.15)) (justify left bottom mirror))
    )
    (fp_text user "License: Apache-2.0" (at -0.4 -5.101 270) (layer "B.Fab") hide
      (effects (font (size 0.7 0.7) (thickness 0.15)) (justify left bottom mirror))
    )
    (fp_text user "${REFERENCE}" (at -0.4 -2.7 270) (layer "B.Fab") hide
      (effects (font (size 0.7 0.7) (thickness 0.15)) (justify left bottom mirror))
    )
    (fp_text user "Author: Antmicro" (at -0.4 -3.901 270) (layer "B.Fab") hide
      (effects (font (size 0.7 0.7) (thickness 0.15)) (justify left bottom mirror))
    )
    (pad "1" smd circle (at 0 0 90) (size 0.75 0.75) (layers "B.Cu" "B.Mask")
      (net 334 "/USB-PD/GPIO") (pinfunction "1") (pintype "passive"))
  )

  (footprint "sa800u-baseboard-hw-footprints:TP_SMD_0.75mm" (layer "B.Cu")
    (tedit 5E4A9375)
    (at 111.6 107)
    (property "Author" "Antmicro")
    (property "License" "Apache-2.0")
    (property "MPN" "")
    (property "Manufacturer" "")
    (property "Sheetfile" "other-interfaces.kicad_sch")
    (property "Sheetname" "Other Interfaces")
    (attr smd)
    (fp_text reference "TP44" (at -0.37 0.38 180) (layer "B.SilkS")
      (effects (font (size 0.7 0.7) (thickness 0.15)) (justify left bottom mirror))
    )
    (fp_text value "TP_0.75mm_SMD" (at 0 -1.2 180) (layer "B.Fab")
      (effects (font (size 0.7 0.7) (thickness 0.15)) (justify left bottom mirror))
    )
    (fp_text user "License: Apache-2.0" (at -0.4 -5.101 180) (layer "B.Fab") hide
      (effects (font (size 0.7 0.7) (thickness 0.15)) (justify left bottom mirror))
    )
    (fp_text user "Author: Antmicro" (at -0.4 -3.901 180) (layer "B.Fab") hide
      (effects (font (size 0.7 0.7) (thickness 0.15)) (justify left bottom mirror))
    )
    (fp_text user "${REFERENCE}" (at -0.4 -2.7 180) (layer "B.Fab") hide
      (effects (font (size 0.7 0.7) (thickness 0.15)) (justify left bottom mirror))
    )
    (pad "1" smd circle (at 0 0) (size 0.75 0.75) (layers "B.Cu" "B.Mask")
      (net 151 "I2C10_SDA") (pinfunction "1") (pintype "passive"))
  )

  (footprint "sa800u-baseboard-hw-footprints:TP_SMD_0.75mm" (layer "B.Cu")
    (tedit 5E4A9375)
    (at 111.6 108.2)
    (property "Author" "Antmicro")
    (property "License" "Apache-2.0")
    (property "MPN" "")
    (property "Manufacturer" "")
    (property "Sheetfile" "other-interfaces.kicad_sch")
    (property "Sheetname" "Other Interfaces")
    (attr smd)
    (fp_text reference "TP45" (at -0.37 0.38 180) (layer "B.SilkS")
      (effects (font (size 0.7 0.7) (thickness 0.15)) (justify left bottom mirror))
    )
    (fp_text value "TP_0.75mm_SMD" (at 0 -1.2 180) (layer "B.Fab")
      (effects (font (size 0.7 0.7) (thickness 0.15)) (justify left bottom mirror))
    )
    (fp_text user "${REFERENCE}" (at -0.4 -2.7 180) (layer "B.Fab") hide
      (effects (font (size 0.7 0.7) (thickness 0.15)) (justify left bottom mirror))
    )
    (fp_text user "Author: Antmicro" (at -0.4 -3.901 180) (layer "B.Fab") hide
      (effects (font (size 0.7 0.7) (thickness 0.15)) (justify left bottom mirror))
    )
    (fp_text user "License: Apache-2.0" (at -0.4 -5.101 180) (layer "B.Fab") hide
      (effects (font (size 0.7 0.7) (thickness 0.15)) (justify left bottom mirror))
    )
    (pad "1" smd circle (at 0 0) (size 0.75 0.75) (layers "B.Cu" "B.Mask")
      (net 150 "I2C10_SCL") (pinfunction "1") (pintype "passive"))
  )

  (footprint "sa800u-baseboard-hw-footprints:TP_SMD_0.75mm" (layer "B.Cu")
    (tedit 5E4A9375)
    (at 115.9 108.2)
    (property "Author" "Antmicro")
    (property "License" "Apache-2.0")
    (property "MPN" "")
    (property "Manufacturer" "")
    (property "Sheetfile" "other-interfaces.kicad_sch")
    (property "Sheetname" "Other Interfaces")
    (attr smd)
    (fp_text reference "TP46" (at -0.37 0.38 180) (layer "B.SilkS")
      (effects (font (size 0.7 0.7) (thickness 0.15)) (justify left bottom mirror))
    )
    (fp_text value "TP_0.75mm_SMD" (at 0 -1.2 180) (layer "B.Fab")
      (effects (font (size 0.7 0.7) (thickness 0.15)) (justify left bottom mirror))
    )
    (fp_text user "${REFERENCE}" (at -0.4 -2.7 180) (layer "B.Fab") hide
      (effects (font (size 0.7 0.7) (thickness 0.15)) (justify left bottom mirror))
    )
    (fp_text user "Author: Antmicro" (at -0.4 -3.901 180) (layer "B.Fab") hide
      (effects (font (size 0.7 0.7) (thickness 0.15)) (justify left bottom mirror))
    )
    (fp_text user "License: Apache-2.0" (at -0.4 -5.101 180) (layer "B.Fab") hide
      (effects (font (size 0.7 0.7) (thickness 0.15)) (justify left bottom mirror))
    )
    (pad "1" smd circle (at 0 0) (size 0.75 0.75) (layers "B.Cu" "B.Mask")
      (net 337 "/Other Interfaces/I2C10_SCL_3V3") (pinfunction "1") (pintype "passive"))
  )

  (footprint "sa800u-baseboard-hw-footprints:TP_SMD_0.75mm" (layer "B.Cu")
    (tedit 5E4A9375)
    (at 115.9 107)
    (property "Author" "Antmicro")
    (property "License" "Apache-2.0")
    (property "MPN" "")
    (property "Manufacturer" "")
    (property "Sheetfile" "other-interfaces.kicad_sch")
    (property "Sheetname" "Other Interfaces")
    (attr smd)
    (fp_text reference "TP47" (at -0.37 0.38 180) (layer "B.SilkS")
      (effects (font (size 0.7 0.7) (thickness 0.15)) (justify left bottom mirror))
    )
    (fp_text value "TP_0.75mm_SMD" (at 0 -1.2 180) (layer "B.Fab")
      (effects (font (size 0.7 0.7) (thickness 0.15)) (justify left bottom mirror))
    )
    (fp_text user "License: Apache-2.0" (at -0.4 -5.101 180) (layer "B.Fab") hide
      (effects (font (size 0.7 0.7) (thickness 0.15)) (justify left bottom mirror))
    )
    (fp_text user "${REFERENCE}" (at -0.4 -2.7 180) (layer "B.Fab") hide
      (effects (font (size 0.7 0.7) (thickness 0.15)) (justify left bottom mirror))
    )
    (fp_text user "Author: Antmicro" (at -0.4 -3.901 180) (layer "B.Fab") hide
      (effects (font (size 0.7 0.7) (thickness 0.15)) (justify left bottom mirror))
    )
    (pad "1" smd circle (at 0 0) (size 0.75 0.75) (layers "B.Cu" "B.Mask")
      (net 338 "/Other Interfaces/I2C10_SDA_3V3") (pinfunction "1") (pintype "passive"))
  )

  (footprint "sa800u-baseboard-hw-footprints:TP_SMD_0.75mm" (layer "B.Cu")
    (tedit 5E4A9375)
    (at 95 128.2)
    (property "Author" "Antmicro")
    (property "License" "Apache-2.0")
    (property "MPN" "")
    (property "Manufacturer" "")
    (property "Sheetfile" "usb-pd.kicad_sch")
    (property "Sheetname" "USB-PD")
    (attr smd)
    (fp_text reference "TP96" (at -0.43 0.4 180) (layer "B.SilkS")
      (effects (font (size 0.7 0.7) (thickness 0.15)) (justify left bottom mirror))
    )
    (fp_text value "TP_0.75mm_SMD" (at 0 -1.2 180) (layer "B.Fab")
      (effects (font (size 0.7 0.7) (thickness 0.15)) (justify left bottom mirror))
    )
    (fp_text user "Author: Antmicro" (at -0.4 -3.901 180) (layer "B.Fab") hide
      (effects (font (size 0.7 0.7) (thickness 0.15)) (justify left bottom mirror))
    )
    (fp_text user "License: Apache-2.0" (at -0.4 -5.101 180) (layer "B.Fab") hide
      (effects (font (size 0.7 0.7) (thickness 0.15)) (justify left bottom mirror))
    )
    (fp_text user "${REFERENCE}" (at -0.4 -2.7 180) (layer "B.Fab") hide
      (effects (font (size 0.7 0.7) (thickness 0.15)) (justify left bottom mirror))
    )
    (pad "1" smd circle (at 0 0) (size 0.75 0.75) (layers "B.Cu" "B.Mask")
      (net 335 "/USB-PD/ATTACH") (pinfunction "1") (pintype "passive"))
  )

  (footprint "sa800u-baseboard-hw-footprints:TP_SMD_0.75mm" (layer "B.Cu")
    (tedit 5E4A9375)
    (at 72.85 84 180)
    (property "Author" "Antmicro")
    (property "License" "Apache-2.0")
    (property "MPN" "")
    (property "Manufacturer" "")
    (property "Sheetfile" "poe.kicad_sch")
    (property "Sheetname" "PoE")
    (attr smd)
    (fp_text reference "TP83" (at -1.21 0.57) (layer "B.SilkS")
      (effects (font (size 0.7 0.7) (thickness 0.15)) (justify left bottom mirror))
    )
    (fp_text value "TP_0.75mm_SMD" (at 0 -1.2) (layer "B.Fab")
      (effects (font (size 0.7 0.7) (thickness 0.15)) (justify left bottom mirror))
    )
    (fp_text user "Author: Antmicro" (at -0.4 -3.901) (layer "B.Fab") hide
      (effects (font (size 0.7 0.7) (thickness 0.15)) (justify left bottom mirror))
    )
    (fp_text user "License: Apache-2.0" (at -0.4 -5.101) (layer "B.Fab") hide
      (effects (font (size 0.7 0.7) (thickness 0.15)) (justify left bottom mirror))
    )
    (fp_text user "${REFERENCE}" (at -0.4 -2.7) (layer "B.Fab") hide
      (effects (font (size 0.7 0.7) (thickness 0.15)) (justify left bottom mirror))
    )
    (pad "1" smd circle (at 0 0 180) (size 0.75 0.75) (layers "B.Cu" "B.Mask")
      (net 153 "/PoE/TRIM") (pinfunction "1") (pintype "passive"))
  )

  (footprint "sa800u-baseboard-hw-footprints:TP_SMD_0.75mm" (layer "B.Cu")
    (tedit 5E4A9375)
    (at 75.25 84 180)
    (property "Author" "Antmicro")
    (property "License" "Apache-2.0")
    (property "MPN" "")
    (property "Manufacturer" "")
    (property "Sheetfile" "poe.kicad_sch")
    (property "Sheetname" "PoE")
    (attr smd)
    (fp_text reference "TP84" (at -1.51 0.53) (layer "B.SilkS")
      (effects (font (size 0.7 0.7) (thickness 0.15)) (justify left bottom mirror))
    )
    (fp_text value "TP_0.75mm_SMD" (at 0 -1.2) (layer "B.Fab")
      (effects (font (size 0.7 0.7) (thickness 0.15)) (justify left bottom mirror))
    )
    (fp_text user "Author: Antmicro" (at -0.4 -3.901) (layer "B.Fab") hide
      (effects (font (size 0.7 0.7) (thickness 0.15)) (justify left bottom mirror))
    )
    (fp_text user "${REFERENCE}" (at -0.4 -2.7) (layer "B.Fab") hide
      (effects (font (size 0.7 0.7) (thickness 0.15)) (justify left bottom mirror))
    )
    (fp_text user "License: Apache-2.0" (at -0.4 -5.101) (layer "B.Fab") hide
      (effects (font (size 0.7 0.7) (thickness 0.15)) (justify left bottom mirror))
    )
    (pad "1" smd circle (at 0 0 180) (size 0.75 0.75) (layers "B.Cu" "B.Mask")
      (net 136 "5V_POE") (pinfunction "1") (pintype "passive"))
  )

  (footprint "sa800u-baseboard-hw-footprints:TP_SMD_0.75mm" (layer "B.Cu")
    (tedit 5E4A9375)
    (at 70.25 84 180)
    (property "Author" "Antmicro")
    (property "License" "Apache-2.0")
    (property "MPN" "")
    (property "Manufacturer" "")
    (property "Sheetfile" "poe.kicad_sch")
    (property "Sheetname" "PoE")
    (attr smd)
    (fp_text reference "TP85" (at -1.16 0.59) (layer "B.SilkS")
      (effects (font (size 0.7 0.7) (thickness 0.15)) (justify left bottom mirror))
    )
    (fp_text value "TP_0.75mm_SMD" (at 0 -1.2) (layer "B.Fab")
      (effects (font (size 0.7 0.7) (thickness 0.15)) (justify left bottom mirror))
    )
    (fp_text user "${REFERENCE}" (at -0.4 -2.7) (layer "B.Fab") hide
      (effects (font (size 0.7 0.7) (thickness 0.15)) (justify left bottom mirror))
    )
    (fp_text user "Author: Antmicro" (at -0.4 -3.901) (layer "B.Fab") hide
      (effects (font (size 0.7 0.7) (thickness 0.15)) (justify left bottom mirror))
    )
    (fp_text user "License: Apache-2.0" (at -0.4 -5.101) (layer "B.Fab") hide
      (effects (font (size 0.7 0.7) (thickness 0.15)) (justify left bottom mirror))
    )
    (pad "1" smd circle (at 0 0 180) (size 0.75 0.75) (layers "B.Cu" "B.Mask")
      (net 1 "GND") (pinfunction "1") (pintype "passive"))
  )

  (footprint "sa800u-baseboard-hw-footprints:TP_SMD_0.75mm" (layer "B.Cu")
    (tedit 5E4A9375)
    (at 59 101.5 90)
    (property "Author" "Antmicro")
    (property "License" "Apache-2.0")
    (property "MPN" "")
    (property "Manufacturer" "")
    (property "Sheetfile" "poe.kicad_sch")
    (property "Sheetname" "PoE")
    (attr smd)
    (fp_text reference "TP78" (at 2.99 0.42 270) (layer "B.SilkS")
      (effects (font (size 0.7 0.7) (thickness 0.15)) (justify left bottom mirror))
    )
    (fp_text value "TP_0.75mm_SMD" (at 0 -1.2 270) (layer "B.Fab")
      (effects (font (size 0.7 0.7) (thickness 0.15)) (justify left bottom mirror))
    )
    (fp_text user "License: Apache-2.0" (at -0.4 -5.101 270) (layer "B.Fab") hide
      (effects (font (size 0.7 0.7) (thickness 0.15)) (justify left bottom mirror))
    )
    (fp_text user "${REFERENCE}" (at -0.4 -2.7 270) (layer "B.Fab") hide
      (effects (font (size 0.7 0.7) (thickness 0.15)) (justify left bottom mirror))
    )
    (fp_text user "Author: Antmicro" (at -0.4 -3.901 270) (layer "B.Fab") hide
      (effects (font (size 0.7 0.7) (thickness 0.15)) (justify left bottom mirror))
    )
    (pad "1" smd circle (at 0 0 90) (size 0.75 0.75) (layers "B.Cu" "B.Mask")
      (net 73 "/PoE/VDD_POE") (pinfunction "1") (pintype "passive"))
  )

  (footprint "sa800u-baseboard-hw-footprints:TP_SMD_0.75mm" (layer "B.Cu")
    (tedit 5E4A9375)
    (at 56.5 109.25 90)
    (property "Author" "Antmicro")
    (property "License" "Apache-2.0")
    (property "MPN" "")
    (property "Manufacturer" "")
    (property "Sheetfile" "poe.kicad_sch")
    (property "Sheetname" "PoE")
    (attr smd)
    (fp_text reference "TP79" (at 0.48 1.33) (layer "B.SilkS")
      (effects (font (size 0.7 0.7) (thickness 0.15)) (justify left bottom mirror))
    )
    (fp_text value "TP_0.75mm_SMD" (at 0 -1.2 270) (layer "B.Fab")
      (effects (font (size 0.7 0.7) (thickness 0.15)) (justify left bottom mirror))
    )
    (fp_text user "Author: Antmicro" (at -0.4 -3.901 270) (layer "B.Fab") hide
      (effects (font (size 0.7 0.7) (thickness 0.15)) (justify left bottom mirror))
    )
    (fp_text user "${REFERENCE}" (at -0.4 -2.7 270) (layer "B.Fab") hide
      (effects (font (size 0.7 0.7) (thickness 0.15)) (justify left bottom mirror))
    )
    (fp_text user "License: Apache-2.0" (at -0.4 -5.101 270) (layer "B.Fab") hide
      (effects (font (size 0.7 0.7) (thickness 0.15)) (justify left bottom mirror))
    )
    (pad "1" smd circle (at 0 0 90) (size 0.75 0.75) (layers "B.Cu" "B.Mask")
      (net 135 "/PoE/VSS_POE") (pinfunction "1") (pintype "passive"))
  )

  (footprint "sa800u-baseboard-hw-footprints:TP_SMD_0.75mm" (layer "B.Cu")
    (tedit 5E4A9375)
    (at 56.5 101.5 90)
    (property "Author" "Antmicro")
    (property "License" "Apache-2.0")
    (property "MPN" "")
    (property "Manufacturer" "")
    (property "Sheetfile" "poe.kicad_sch")
    (property "Sheetname" "PoE")
    (attr smd)
    (fp_text reference "TP80" (at 3.02 0.38 270) (layer "B.SilkS")
      (effects (font (size 0.7 0.7) (thickness 0.15)) (justify left bottom mirror))
    )
    (fp_text value "TP_0.75mm_SMD" (at 0 -1.2 270) (layer "B.Fab")
      (effects (font (size 0.7 0.7) (thickness 0.15)) (justify left bottom mirror))
    )
    (fp_text user "${REFERENCE}" (at -0.4 -2.7 270) (layer "B.Fab") hide
      (effects (font (size 0.7 0.7) (thickness 0.15)) (justify left bottom mirror))
    )
    (fp_text user "Author: Antmicro" (at -0.4 -3.901 270) (layer "B.Fab") hide
      (effects (font (size 0.7 0.7) (thickness 0.15)) (justify left bottom mirror))
    )
    (fp_text user "License: Apache-2.0" (at -0.4 -5.101 270) (layer "B.Fab") hide
      (effects (font (size 0.7 0.7) (thickness 0.15)) (justify left bottom mirror))
    )
    (pad "1" smd circle (at 0 0 90) (size 0.75 0.75) (layers "B.Cu" "B.Mask")
      (net 384 "Net-(IC2-Pad7)") (pinfunction "1") (pintype "passive"))
  )

  (footprint "sa800u-baseboard-hw-footprints:TP_SMD_0.75mm" (layer "B.Cu")
    (tedit 5E4A9375)
    (at 61.515 101.32 90)
    (property "Author" "Antmicro")
    (property "License" "Apache-2.0")
    (property "MPN" "")
    (property "Manufacturer" "")
    (property "Sheetfile" "poe.kicad_sch")
    (property "Sheetname" "PoE")
    (attr smd)
    (fp_text reference "TP82" (at 3.07 0.39 90) (layer "B.SilkS")
      (effects (font (size 0.7 0.7) (thickness 0.15)) (justify left bottom mirror))
    )
    (fp_text value "TP_0.75mm_SMD" (at 0 -1.2 270) (layer "B.Fab")
      (effects (font (size 0.7 0.7) (thickness 0.15)) (justify left bottom mirror))
    )
    (fp_text user "${REFERENCE}" (at -0.4 -2.7 270) (layer "B.Fab") hide
      (effects (font (size 0.7 0.7) (thickness 0.15)) (justify left bottom mirror))
    )
    (fp_text user "License: Apache-2.0" (at -0.4 -5.101 270) (layer "B.Fab") hide
      (effects (font (size 0.7 0.7) (thickness 0.15)) (justify left bottom mirror))
    )
    (fp_text user "Author: Antmicro" (at -0.4 -3.901 270) (layer "B.Fab") hide
      (effects (font (size 0.7 0.7) (thickness 0.15)) (justify left bottom mirror))
    )
    (pad "1" smd circle (at 0 0 90) (size 0.75 0.75) (layers "B.Cu" "B.Mask")
      (net 76 "/PoE/SMPS_CTRL") (pinfunction "1") (pintype "passive"))
  )

  (footprint "sa800u-baseboard-hw-footprints:TP_SMD_0.75mm" (layer "B.Cu")
    (tedit 5E4A9375)
    (at 56.5 104)
    (property "Author" "Antmicro")
    (property "License" "Apache-2.0")
    (property "MPN" "")
    (property "Manufacturer" "")
    (property "Sheetfile" "poe.kicad_sch")
    (property "Sheetname" "PoE")
    (attr smd)
    (fp_text reference "TP81" (at 1.32 1.2 180) (layer "B.SilkS")
      (effects (font (size 0.7 0.7) (thickness 0.15)) (justify left bottom mirror))
    )
    (fp_text value "TP_0.75mm_SMD" (at 0 -1.2 180) (layer "B.Fab")
      (effects (font (size 0.7 0.7) (thickness 0.15)) (justify left bottom mirror))
    )
    (fp_text user "${REFERENCE}" (at -0.4 -2.7 180) (layer "B.Fab") hide
      (effects (font (size 0.7 0.7) (thickness 0.15)) (justify left bottom mirror))
    )
    (fp_text user "License: Apache-2.0" (at -0.4 -5.101 180) (layer "B.Fab") hide
      (effects (font (size 0.7 0.7) (thickness 0.15)) (justify left bottom mirror))
    )
    (fp_text user "Author: Antmicro" (at -0.4 -3.901 180) (layer "B.Fab") hide
      (effects (font (size 0.7 0.7) (thickness 0.15)) (justify left bottom mirror))
    )
    (pad "1" smd circle (at 0 0) (size 0.75 0.75) (layers "B.Cu" "B.Mask")
      (net 7 "GNDD") (pinfunction "1") (pintype "passive"))
  )

  (footprint "sa800u-baseboard-hw-footprints:R_0402_1005Metric" (layer "B.Cu")
    (tedit 5FD9C158)
    (at 120.6 133.5 -90)
    (descr "Resistor SMD 0402")
    (tags "resistor SMD 0402")
    (property "Author" "Antmicro")
    (property "License" "Apache-2.0")
    (property "MPN" "CR0402-FX-2003GLF")
    (property "Manufacturer" "Bourns")
    (property "Sheetfile" "usb-c-interface.kicad_sch")
    (property "Sheetname" "USB-C Interface ")
    (property "Tolerance" "1%")
    (property "Val" "200k")
    (attr smd)
    (fp_text reference "R64" (at -1.091 -2.34 90) (layer "B.SilkS")
      (effects (font (size 0.7 0.7) (thickness 0.15)) (justify left bottom mirror))
    )
    (fp_text value "R_200k_0402" (at 0 -1.4 90) (layer "B.Fab")
      (effects (font (size 0.7 0.7) (thickness 0.15)) (justify left bottom mirror))
    )
    (fp_text user "${REFERENCE}" (at -0.95 -3.168 90) (layer "B.Fab") hide
      (effects (font (size 0.7 0.7) (thickness 0.15)) (justify left bottom mirror))
    )
    (fp_text user "License: Apache-2.0" (at -0.95 -5.169 90) (layer "B.Fab") hide
      (effects (font (size 0.7 0.7) (thickness 0.15)) (justify left bottom mirror))
    )
    (fp_text user "Author: Antmicro" (at -0.95 -4.169 90) (layer "B.Fab") hide
      (effects (font (size 0.7 0.7) (thickness 0.15)) (justify left bottom mirror))
    )
    (fp_rect (start -0.93 0.47) (end 0.93 -0.47) (layer "B.CrtYd") (width 0.05) (fill none))
    (fp_rect (start -0.5 0.25) (end 0.5 -0.25) (layer "B.Fab") (width 0.15) (fill none))
    (pad "1" smd roundrect (at -0.485 0 270) (size 0.59 0.64) (layers "B.Cu" "B.Paste" "B.Mask") (roundrect_rratio 0.25)
      (net 290 "/USB-C Interface /USB2_CC_SELECT") (pintype "passive"))
    (pad "2" smd roundrect (at 0.485 0 270) (size 0.59 0.64) (layers "B.Cu" "B.Paste" "B.Mask") (roundrect_rratio 0.25)
      (net 1 "GND") (pintype "passive"))
  )

  (footprint "sa800u-baseboard-hw-footprints:L_0603_1608Metric" (layer "B.Cu")
    (tedit 5D5D3F54)
    (at 134.000003 120.766849)
    (property "Author" "Antmicro")
    (property "IMax" "")
    (property "ISat" "")
    (property "License" "Apache-2.0")
    (property "MPN" "BRC1608TR35M")
    (property "Manufacturer" "Taiyo Yuden")
    (property "Sheetfile" "hdmi-converter.kicad_sch")
    (property "Sheetname" "HDMI converter")
    (property "Size" "")
    (property "Val" "350n/1.4A")
    (attr smd)
    (fp_text reference "L4" (at 0.669997 -0.896849 180) (layer "B.SilkS")
      (effects (font (size 0.7 0.7) (thickness 0.15)) (justify left bottom mirror))
    )
    (fp_text value "L_350n_1.4A_0603" (at 0 -2 180) (layer "B.Fab")
      (effects (font (size 0.7 0.7) (thickness 0.15)) (justify left bottom mirror))
    )
    (fp_text user "License: Apache-2.0" (at -1.9 -5.75 180) (layer "B.Fab") hide
      (effects (font (size 0.7 0.7) (thickness 0.15)) (justify left bottom mirror))
    )
    (fp_text user "Author: Antmicro" (at -1.9 -4.4 180) (layer "B.Fab") hide
      (effects (font (size 0.7 0.7) (thickness 0.15)) (justify left bottom mirror))
    )
    (fp_text user "${REFERENCE}" (at -1.9 -3.1 180) (layer "B.Fab") hide
      (effects (font (size 0.7 0.7) (thickness 0.15)) (justify left bottom mirror))
    )
    (fp_line (start -0.25 -0.45) (end 0.25 -0.45) (layer "B.SilkS") (width 0.1))
    (fp_line (start -0.25 0.45) (end 0.25 0.45) (layer "B.SilkS") (width 0.1))
    (fp_rect (start -1.15 0.75) (end 1.15 -0.75) (layer "B.CrtYd") (width 0.05) (fill none))
    (fp_rect (start -0.8 0.4) (end 0.8 -0.4) (layer "B.Fab") (width 0.1) (fill none))
    (pad "1" smd roundrect (at -0.625 0) (size 0.55 1) (layers "B.Cu" "B.Paste" "B.Mask") (roundrect_rratio 0.15)
      (net 138 "1V2_SYS") (pintype "passive"))
    (pad "2" smd roundrect (at 0.625 0) (size 0.55 1) (layers "B.Cu" "B.Paste" "B.Mask") (roundrect_rratio 0.15)
      (net 188 "/HDMI converter/LT9611_VDD12") (pintype "passive"))
  )

  (footprint "sa800u-baseboard-hw-footprints:TP_SMD_0.75mm" (layer "B.Cu")
    (tedit 5E4A9375)
    (at 134 127.6)
    (property "Author" "Antmicro")
    (property "License" "Apache-2.0")
    (property "MPN" "")
    (property "Manufacturer" "")
    (property "Sheetfile" "hdmi-converter.kicad_sch")
    (property "Sheetname" "HDMI converter")
    (attr smd)
    (fp_text reference "TP27" (at -0.31 0.52 180) (layer "B.SilkS")
      (effects (font (size 0.7 0.7) (thickness 0.15)) (justify left bottom mirror))
    )
    (fp_text value "TP_0.75mm_SMD" (at 0 -1.2 180) (layer "B.Fab")
      (effects (font (size 0.7 0.7) (thickness 0.15)) (justify left bottom mirror))
    )
    (fp_text user "Author: Antmicro" (at -0.4 -3.901 180) (layer "B.Fab") hide
      (effects (font (size 0.7 0.7) (thickness 0.15)) (justify left bottom mirror))
    )
    (fp_text user "${REFERENCE}" (at -0.4 -2.7 180) (layer "B.Fab") hide
      (effects (font (size 0.7 0.7) (thickness 0.15)) (justify left bottom mirror))
    )
    (fp_text user "License: Apache-2.0" (at -0.4 -5.101 180) (layer "B.Fab") hide
      (effects (font (size 0.7 0.7) (thickness 0.15)) (justify left bottom mirror))
    )
    (pad "1" smd circle (at 0 0) (size 0.75 0.75) (layers "B.Cu" "B.Mask")
      (net 1 "GND") (pinfunction "1") (pintype "passive"))
  )

  (footprint "sa800u-baseboard-hw-footprints:TP_SMD_0.75mm" (layer "B.Cu")
    (tedit 5E4A9375)
    (at 78.2 124)
    (property "Author" "Antmicro")
    (property "License" "Apache-2.0")
    (property "MPN" "")
    (property "Manufacturer" "")
    (property "Sheetfile" "psu.kicad_sch")
    (property "Sheetname" "PSU")
    (attr smd)
    (fp_text reference "TP54" (at -0.21 1.06 180) (layer "B.SilkS")
      (effects (font (size 0.7 0.7) (thickness 0.15)) (justify left bottom mirror))
    )
    (fp_text value "TP_0.75mm_SMD" (at 0 -1.2 180) (layer "B.Fab")
      (effects (font (size 0.7 0.7) (thickness 0.15)) (justify left bottom mirror))
    )
    (fp_text user "${REFERENCE}" (at -0.4 -2.7 180) (layer "B.Fab") hide
      (effects (font (size 0.7 0.7) (thickness 0.15)) (justify left bottom mirror))
    )
    (fp_text user "Author: Antmicro" (at -0.4 -3.901 180) (layer "B.Fab") hide
      (effects (font (size 0.7 0.7) (thickness 0.15)) (justify left bottom mirror))
    )
    (fp_text user "License: Apache-2.0" (at -0.4 -5.101 180) (layer "B.Fab") hide
      (effects (font (size 0.7 0.7) (thickness 0.15)) (justify left bottom mirror))
    )
    (pad "1" smd circle (at 0 0) (size 0.75 0.75) (layers "B.Cu" "B.Mask")
      (net 340 "/PSU/POE_VALID") (pinfunction "1") (pintype "passive"))
  )

  (footprint "sa800u-baseboard-hw-footprints:TP_SMD_0.75mm" (layer "B.Cu")
    (tedit 5E4A9375)
    (at 78.18 125.55)
    (property "Author" "Antmicro")
    (property "License" "Apache-2.0")
    (property "MPN" "")
    (property "Manufacturer" "")
    (property "Sheetfile" "psu.kicad_sch")
    (property "Sheetname" "PSU")
    (attr smd)
    (fp_text reference "TP55" (at -0.32 0.54 180) (layer "B.SilkS")
      (effects (font (size 0.7 0.7) (thickness 0.15)) (justify left bottom mirror))
    )
    (fp_text value "TP_0.75mm_SMD" (at 0 -1.2 180) (layer "B.Fab")
      (effects (font (size 0.7 0.7) (thickness 0.15)) (justify left bottom mirror))
    )
    (fp_text user "License: Apache-2.0" (at -0.4 -5.101 180) (layer "B.Fab") hide
      (effects (font (size 0.7 0.7) (thickness 0.15)) (justify left bottom mirror))
    )
    (fp_text user "${REFERENCE}" (at -0.4 -2.7 180) (layer "B.Fab") hide
      (effects (font (size 0.7 0.7) (thickness 0.15)) (justify left bottom mirror))
    )
    (fp_text user "Author: Antmicro" (at -0.4 -3.901 180) (layer "B.Fab") hide
      (effects (font (size 0.7 0.7) (thickness 0.15)) (justify left bottom mirror))
    )
    (pad "1" smd circle (at 0 0) (size 0.75 0.75) (layers "B.Cu" "B.Mask")
      (net 341 "/PSU/USB_PD_VALID") (pinfunction "1") (pintype "passive"))
  )

  (footprint "sa800u-baseboard-hw-footprints:TP_SMD_0.75mm" (layer "B.Cu")
    (tedit 5E4A9375)
    (at 76 130.25)
    (property "Author" "Antmicro")
    (property "License" "Apache-2.0")
    (property "MPN" "")
    (property "Manufacturer" "")
    (property "Sheetfile" "psu.kicad_sch")
    (property "Sheetname" "PSU")
    (attr smd)
    (fp_text reference "TP56" (at 1.22 -0.47 180) (layer "B.SilkS")
      (effects (font (size 0.7 0.7) (thickness 0.15)) (justify left bottom mirror))
    )
    (fp_text value "TP_0.75mm_SMD" (at 0 -1.2 180) (layer "B.Fab")
      (effects (font (size 0.7 0.7) (thickness 0.15)) (justify left bottom mirror))
    )
    (fp_text user "${REFERENCE}" (at -0.4 -2.7 180) (layer "B.Fab") hide
      (effects (font (size 0.7 0.7) (thickness 0.15)) (justify left bottom mirror))
    )
    (fp_text user "License: Apache-2.0" (at -0.4 -5.101 180) (layer "B.Fab") hide
      (effects (font (size 0.7 0.7) (thickness 0.15)) (justify left bottom mirror))
    )
    (fp_text user "Author: Antmicro" (at -0.4 -3.901 180) (layer "B.Fab") hide
      (effects (font (size 0.7 0.7) (thickness 0.15)) (justify left bottom mirror))
    )
    (pad "1" smd circle (at 0 0) (size 0.75 0.75) (layers "B.Cu" "B.Mask")
      (net 74 "VDD") (pinfunction "1") (pintype "passive"))
  )

  (footprint "sa800u-baseboard-hw-footprints:TP_SMD_0.75mm" (layer "B.Cu")
    (tedit 5E4A9375)
    (at 78.2 127.15)
    (property "Author" "Antmicro")
    (property "License" "Apache-2.0")
    (property "MPN" "")
    (property "Manufacturer" "")
    (property "Sheetfile" "psu.kicad_sch")
    (property "Sheetname" "PSU")
    (attr smd)
    (fp_text reference "TP57" (at 0.59 1.2 180) (layer "B.SilkS")
      (effects (font (size 0.7 0.7) (thickness 0.15)) (justify left bottom mirror))
    )
    (fp_text value "TP_0.75mm_SMD" (at 0 -1.2 180) (layer "B.Fab")
      (effects (font (size 0.7 0.7) (thickness 0.15)) (justify left bottom mirror))
    )
    (fp_text user "License: Apache-2.0" (at -0.4 -5.101 180) (layer "B.Fab") hide
      (effects (font (size 0.7 0.7) (thickness 0.15)) (justify left bottom mirror))
    )
    (fp_text user "${REFERENCE}" (at -0.4 -2.7 180) (layer "B.Fab") hide
      (effects (font (size 0.7 0.7) (thickness 0.15)) (justify left bottom mirror))
    )
    (fp_text user "Author: Antmicro" (at -0.4 -3.901 180) (layer "B.Fab") hide
      (effects (font (size 0.7 0.7) (thickness 0.15)) (justify left bottom mirror))
    )
    (pad "1" smd circle (at 0 0) (size 0.75 0.75) (layers "B.Cu" "B.Mask")
      (net 339 "/PSU/AUX_VALID") (pinfunction "1") (pintype "passive"))
  )

  (footprint "sa800u-baseboard-hw-footprints:TP_SMD_0.75mm" (layer "B.Cu")
    (tedit 5E4A9375)
    (at 71.2 128.8)
    (property "Author" "Antmicro")
    (property "License" "Apache-2.0")
    (property "MPN" "")
    (property "Manufacturer" "")
    (property "Sheetfile" "psu.kicad_sch")
    (property "Sheetname" "PSU")
    (attr smd)
    (fp_text reference "TP58" (at -0.38 0.78 180) (layer "B.SilkS")
      (effects (font (size 0.7 0.7) (thickness 0.15)) (justify left bottom mirror))
    )
    (fp_text value "TP_0.75mm_SMD" (at 0 -1.2 180) (layer "B.Fab")
      (effects (font (size 0.7 0.7) (thickness 0.15)) (justify left bottom mirror))
    )
    (fp_text user "License: Apache-2.0" (at -0.4 -5.101 180) (layer "B.Fab") hide
      (effects (font (size 0.7 0.7) (thickness 0.15)) (justify left bottom mirror))
    )
    (fp_text user "${REFERENCE}" (at -0.4 -2.7 180) (layer "B.Fab") hide
      (effects (font (size 0.7 0.7) (thickness 0.15)) (justify left bottom mirror))
    )
    (fp_text user "Author: Antmicro" (at -0.4 -3.901 180) (layer "B.Fab") hide
      (effects (font (size 0.7 0.7) (thickness 0.15)) (justify left bottom mirror))
    )
    (pad "1" smd circle (at 0 0) (size 0.75 0.75) (layers "B.Cu" "B.Mask")
      (net 1 "GND") (pinfunction "1") (pintype "passive"))
  )

  (footprint "sa800u-baseboard-hw-footprints:TP_SMD_0.75mm" (layer "B.Cu")
    (tedit 5E4A9375)
    (at 78.5 112)
    (property "Author" "Antmicro")
    (property "License" "Apache-2.0")
    (property "MPN" "")
    (property "Manufacturer" "")
    (property "Sheetfile" "psu.kicad_sch")
    (property "Sheetname" "PSU")
    (attr smd)
    (fp_text reference "TP62" (at 1.23 -0.45 180) (layer "B.SilkS")
      (effects (font (size 0.7 0.7) (thickness 0.15)) (justify left bottom mirror))
    )
    (fp_text value "TP_0.75mm_SMD" (at 0 -1.2 180) (layer "B.Fab")
      (effects (font (size 0.7 0.7) (thickness 0.15)) (justify left bottom mirror))
    )
    (fp_text user "Author: Antmicro" (at -0.4 -3.901 180) (layer "B.Fab") hide
      (effects (font (size 0.7 0.7) (thickness 0.15)) (justify left bottom mirror))
    )
    (fp_text user "${REFERENCE}" (at -0.4 -2.7 180) (layer "B.Fab") hide
      (effects (font (size 0.7 0.7) (thickness 0.15)) (justify left bottom mirror))
    )
    (fp_text user "License: Apache-2.0" (at -0.4 -5.101 180) (layer "B.Fab") hide
      (effects (font (size 0.7 0.7) (thickness 0.15)) (justify left bottom mirror))
    )
    (pad "1" smd circle (at 0 0) (size 0.75 0.75) (layers "B.Cu" "B.Mask")
      (net 74 "VDD") (pinfunction "1") (pintype "passive"))
  )

  (footprint "sa800u-baseboard-hw-footprints:TP_SMD_0.75mm" (layer "B.Cu")
    (tedit 5E4A9375)
    (at 123.4 128.2)
    (property "Author" "Antmicro")
    (property "License" "Apache-2.0")
    (property "MPN" "")
    (property "Manufacturer" "")
    (property "Sheetfile" "psu.kicad_sch")
    (property "Sheetname" "PSU")
    (attr smd)
    (fp_text reference "TP63" (at 1.2 -0.38 180) (layer "B.SilkS")
      (effects (font (size 0.7 0.7) (thickness 0.15)) (justify left bottom mirror))
    )
    (fp_text value "TP_0.75mm_SMD" (at 0 -1.2 180) (layer "B.Fab")
      (effects (font (size 0.7 0.7) (thickness 0.15)) (justify left bottom mirror))
    )
    (fp_text user "${REFERENCE}" (at -0.4 -2.7 180) (layer "B.Fab") hide
      (effects (font (size 0.7 0.7) (thickness 0.15)) (justify left bottom mirror))
    )
    (fp_text user "License: Apache-2.0" (at -0.4 -5.101 180) (layer "B.Fab") hide
      (effects (font (size 0.7 0.7) (thickness 0.15)) (justify left bottom mirror))
    )
    (fp_text user "Author: Antmicro" (at -0.4 -3.901 180) (layer "B.Fab") hide
      (effects (font (size 0.7 0.7) (thickness 0.15)) (justify left bottom mirror))
    )
    (pad "1" smd circle (at 0 0) (size 0.75 0.75) (layers "B.Cu" "B.Mask")
      (net 133 "5V_SYS") (pinfunction "1") (pintype "passive"))
  )

  (footprint "sa800u-baseboard-hw-footprints:TP_SMD_0.75mm" (layer "B.Cu")
    (tedit 5E4A9375)
    (at 81 112)
    (property "Author" "Antmicro")
    (property "License" "Apache-2.0")
    (property "MPN" "")
    (property "Manufacturer" "")
    (property "Sheetfile" "psu.kicad_sch")
    (property "Sheetname" "PSU")
    (attr smd)
    (fp_text reference "TP71" (at 1.63 -0.47 180) (layer "B.SilkS")
      (effects (font (size 0.7 0.7) (thickness 0.15)) (justify left bottom mirror))
    )
    (fp_text value "TP_0.75mm_SMD" (at 0 -1.2 180) (layer "B.Fab")
      (effects (font (size 0.7 0.7) (thickness 0.15)) (justify left bottom mirror))
    )
    (fp_text user "License: Apache-2.0" (at -0.4 -5.101 180) (layer "B.Fab") hide
      (effects (font (size 0.7 0.7) (thickness 0.15)) (justify left bottom mirror))
    )
    (fp_text user "Author: Antmicro" (at -0.4 -3.901 180) (layer "B.Fab") hide
      (effects (font (size 0.7 0.7) (thickness 0.15)) (justify left bottom mirror))
    )
    (fp_text user "${REFERENCE}" (at -0.4 -2.7 180) (layer "B.Fab") hide
      (effects (font (size 0.7 0.7) (thickness 0.15)) (justify left bottom mirror))
    )
    (pad "1" smd circle (at 0 0) (size 0.75 0.75) (layers "B.Cu" "B.Mask")
      (net 131 "3V3_SYS") (pinfunction "1") (pintype "passive"))
  )

  (footprint "sa800u-baseboard-hw-footprints:TP_SMD_0.75mm" (layer "B.Cu")
    (tedit 5E4A9375)
    (at 126 128.2)
    (property "Author" "Antmicro")
    (property "License" "Apache-2.0")
    (property "MPN" "")
    (property "Manufacturer" "")
    (property "Sheetfile" "psu.kicad_sch")
    (property "Sheetname" "PSU")
    (attr smd)
    (fp_text reference "TP72" (at 1.28 1.22 180) (layer "B.SilkS")
      (effects (font (size 0.7 0.7) (thickness 0.15)) (justify left bottom mirror))
    )
    (fp_text value "TP_0.75mm_SMD" (at 0 -1.2 180) (layer "B.Fab")
      (effects (font (size 0.7 0.7) (thickness 0.15)) (justify left bottom mirror))
    )
    (fp_text user "Author: Antmicro" (at -0.4 -3.901 180) (layer "B.Fab") hide
      (effects (font (size 0.7 0.7) (thickness 0.15)) (justify left bottom mirror))
    )
    (fp_text user "License: Apache-2.0" (at -0.4 -5.101 180) (layer "B.Fab") hide
      (effects (font (size 0.7 0.7) (thickness 0.15)) (justify left bottom mirror))
    )
    (fp_text user "${REFERENCE}" (at -0.4 -2.7 180) (layer "B.Fab") hide
      (effects (font (size 0.7 0.7) (thickness 0.15)) (justify left bottom mirror))
    )
    (pad "1" smd circle (at 0 0) (size 0.75 0.75) (layers "B.Cu" "B.Mask")
      (net 138 "1V2_SYS") (pinfunction "1") (pintype "passive"))
  )

  (footprint "sa800u-baseboard-hw-footprints:TP_SMD_0.75mm" (layer "B.Cu")
    (tedit 5E4A9375)
    (at 120.8 128.2)
    (property "Author" "Antmicro")
    (property "License" "Apache-2.0")
    (property "MPN" "")
    (property "Manufacturer" "")
    (property "Sheetfile" "psu.kicad_sch")
    (property "Sheetname" "PSU")
    (attr smd)
    (fp_text reference "TP76" (at 1.23 1.28 180) (layer "B.SilkS")
      (effects (font (size 0.7 0.7) (thickness 0.15)) (justify left bottom mirror))
    )
    (fp_text value "TP_0.75mm_SMD" (at 0 -1.2 180) (layer "B.Fab")
      (effects (font (size 0.7 0.7) (thickness 0.15)) (justify left bottom mirror))
    )
    (fp_text user "${REFERENCE}" (at -0.4 -2.7 180) (layer "B.Fab") hide
      (effects (font (size 0.7 0.7) (thickness 0.15)) (justify left bottom mirror))
    )
    (fp_text user "License: Apache-2.0" (at -0.4 -5.101 180) (layer "B.Fab") hide
      (effects (font (size 0.7 0.7) (thickness 0.15)) (justify left bottom mirror))
    )
    (fp_text user "Author: Antmicro" (at -0.4 -3.901 180) (layer "B.Fab") hide
      (effects (font (size 0.7 0.7) (thickness 0.15)) (justify left bottom mirror))
    )
    (pad "1" smd circle (at 0 0) (size 0.75 0.75) (layers "B.Cu" "B.Mask")
      (net 1 "GND") (pinfunction "1") (pintype "passive"))
  )

  (footprint "sa800u-baseboard-hw-footprints:TP_SMD_0.75mm" (layer "B.Cu")
    (tedit 5E4A9375)
    (at 85.2 119.2)
    (property "Author" "Antmicro")
    (property "License" "Apache-2.0")
    (property "MPN" "")
    (property "Manufacturer" "")
    (property "Sheetfile" "psu.kicad_sch")
    (property "Sheetname" "PSU")
    (attr smd)
    (fp_text reference "TP77" (at 1.26 1.24 180) (layer "B.SilkS")
      (effects (font (size 0.7 0.7) (thickness 0.15)) (justify left bottom mirror))
    )
    (fp_text value "TP_0.75mm_SMD" (at 0 -1.2 180) (layer "B.Fab")
      (effects (font (size 0.7 0.7) (thickness 0.15)) (justify left bottom mirror))
    )
    (fp_text user "License: Apache-2.0" (at -0.4 -5.101 180) (layer "B.Fab") hide
      (effects (font (size 0.7 0.7) (thickness 0.15)) (justify left bottom mirror))
    )
    (fp_text user "${REFERENCE}" (at -0.4 -2.7 180) (layer "B.Fab") hide
      (effects (font (size 0.7 0.7) (thickness 0.15)) (justify left bottom mirror))
    )
    (fp_text user "Author: Antmicro" (at -0.4 -3.901 180) (layer "B.Fab") hide
      (effects (font (size 0.7 0.7) (thickness 0.15)) (justify left bottom mirror))
    )
    (pad "1" smd circle (at 0 0) (size 0.75 0.75) (layers "B.Cu" "B.Mask")
      (net 1 "GND") (pinfunction "1") (pintype "passive"))
  )

  (footprint "sa800u-baseboard-hw-footprints:TP_SMD_0.75mm" (layer "B.Cu")
    (tedit 5E4A9375)
    (at 76 112)
    (property "Author" "Antmicro")
    (property "License" "Apache-2.0")
    (property "MPN" "")
    (property "Manufacturer" "")
    (property "Sheetfile" "psu.kicad_sch")
    (property "Sheetname" "PSU")
    (attr smd)
    (fp_text reference "TP75" (at 0.88 -0.45 180) (layer "B.SilkS")
      (effects (font (size 0.7 0.7) (thickness 0.15)) (justify left bottom mirror))
    )
    (fp_text value "TP_0.75mm_SMD" (at 0 -1.2 180) (layer "B.Fab")
      (effects (font (size 0.7 0.7) (thickness 0.15)) (justify left bottom mirror))
    )
    (fp_text user "${REFERENCE}" (at -0.4 -2.7 180) (layer "B.Fab") hide
      (effects (font (size 0.7 0.7) (thickness 0.15)) (justify left bottom mirror))
    )
    (fp_text user "License: Apache-2.0" (at -0.4 -5.101 180) (layer "B.Fab") hide
      (effects (font (size 0.7 0.7) (thickness 0.15)) (justify left bottom mirror))
    )
    (fp_text user "Author: Antmicro" (at -0.4 -3.901 180) (layer "B.Fab") hide
      (effects (font (size 0.7 0.7) (thickness 0.15)) (justify left bottom mirror))
    )
    (pad "1" smd circle (at 0 0) (size 0.75 0.75) (layers "B.Cu" "B.Mask")
      (net 1 "GND") (pinfunction "1") (pintype "passive"))
  )

  (footprint "sa800u-baseboard-hw-footprints:TP_SMD_0.75mm" (layer "B.Cu")
    (tedit 5E4A9375)
    (at 89.4 140.2)
    (property "Author" "Antmicro")
    (property "License" "Apache-2.0")
    (property "MPN" "")
    (property "Manufacturer" "")
    (property "Sheetfile" "usb-pd.kicad_sch")
    (property "Sheetname" "USB-PD")
    (attr smd)
    (fp_text reference "TP86" (at 0.94 1.22 180) (layer "B.SilkS")
      (effects (font (size 0.7 0.7) (thickness 0.15)) (justify left bottom mirror))
    )
    (fp_text value "TP_0.75mm_SMD" (at 0 -1.2 180) (layer "B.Fab")
      (effects (font (size 0.7 0.7) (thickness 0.15)) (justify left bottom mirror))
    )
    (fp_text user "Author: Antmicro" (at -0.4 -3.901 180) (layer "B.Fab") hide
      (effects (font (size 0.7 0.7) (thickness 0.15)) (justify left bottom mirror))
    )
    (fp_text user "${REFERENCE}" (at -0.4 -2.7 180) (layer "B.Fab") hide
      (effects (font (size 0.7 0.7) (thickness 0.15)) (justify left bottom mirror))
    )
    (fp_text user "License: Apache-2.0" (at -0.4 -5.101 180) (layer "B.Fab") hide
      (effects (font (size 0.7 0.7) (thickness 0.15)) (justify left bottom mirror))
    )
    (pad "1" smd circle (at 0 0) (size 0.75 0.75) (layers "B.Cu" "B.Mask")
      (net 143 "/USB-PD/PD_CC1") (pinfunction "1") (pintype "passive"))
  )

  (footprint "sa800u-baseboard-hw-footprints:TP_SMD_0.75mm" (layer "B.Cu")
    (tedit 5E4A9375)
    (at 92 140.2)
    (property "Author" "Antmicro")
    (property "License" "Apache-2.0")
    (property "MPN" "")
    (property "Manufacturer" "")
    (property "Sheetfile" "usb-pd.kicad_sch")
    (property "Sheetname" "USB-PD")
    (attr smd)
    (fp_text reference "TP87" (at 1.46 1.21 180) (layer "B.SilkS")
      (effects (font (size 0.7 0.7) (thickness 0.15)) (justify left bottom mirror))
    )
    (fp_text value "TP_0.75mm_SMD" (at 0 -1.2 180) (layer "B.Fab")
      (effects (font (size 0.7 0.7) (thickness 0.15)) (justify left bottom mirror))
    )
    (fp_text user "Author: Antmicro" (at -0.4 -3.901 180) (layer "B.Fab") hide
      (effects (font (size 0.7 0.7) (thickness 0.15)) (justify left bottom mirror))
    )
    (fp_text user "${REFERENCE}" (at -0.4 -2.7 180) (layer "B.Fab") hide
      (effects (font (size 0.7 0.7) (thickness 0.15)) (justify left bottom mirror))
    )
    (fp_text user "License: Apache-2.0" (at -0.4 -5.101 180) (layer "B.Fab") hide
      (effects (font (size 0.7 0.7) (thickness 0.15)) (justify left bottom mirror))
    )
    (pad "1" smd circle (at 0 0) (size 0.75 0.75) (layers "B.Cu" "B.Mask")
      (net 144 "/USB-PD/PD_CC2") (pinfunction "1") (pintype "passive"))
  )

  (footprint "sa800u-baseboard-hw-footprints:TP_SMD_0.75mm" (layer "B.Cu")
    (tedit 5E4A9375)
    (at 90.6 135)
    (property "Author" "Antmicro")
    (property "License" "Apache-2.0")
    (property "MPN" "")
    (property "Manufacturer" "")
    (property "Sheetfile" "usb-pd.kicad_sch")
    (property "Sheetname" "USB-PD")
    (attr smd)
    (fp_text reference "TP88" (at 1.21 -0.41 180) (layer "B.SilkS")
      (effects (font (size 0.7 0.7) (thickness 0.15)) (justify left bottom mirror))
    )
    (fp_text value "TP_0.75mm_SMD" (at 0 -1.2 180) (layer "B.Fab")
      (effects (font (size 0.7 0.7) (thickness 0.15)) (justify left bottom mirror))
    )
    (fp_text user "Author: Antmicro" (at -0.4 -3.901 180) (layer "B.Fab") hide
      (effects (font (size 0.7 0.7) (thickness 0.15)) (justify left bottom mirror))
    )
    (fp_text user "${REFERENCE}" (at -0.4 -2.7 180) (layer "B.Fab") hide
      (effects (font (size 0.7 0.7) (thickness 0.15)) (justify left bottom mirror))
    )
    (fp_text user "License: Apache-2.0" (at -0.4 -5.101 180) (layer "B.Fab") hide
      (effects (font (size 0.7 0.7) (thickness 0.15)) (justify left bottom mirror))
    )
    (pad "1" smd circle (at 0 0) (size 0.75 0.75) (layers "B.Cu" "B.Mask")
      (net 351 "USB_PD_DISABLE") (pinfunction "1") (pintype "passive"))
  )

  (footprint "sa800u-baseboard-hw-footprints:TP_SMD_0.75mm" (layer "B.Cu")
    (tedit 5E4A9375)
    (at 89.6 137.8)
    (property "Author" "Antmicro")
    (property "License" "Apache-2.0")
    (property "MPN" "")
    (property "Manufacturer" "")
    (property "Sheetfile" "usb-pd.kicad_sch")
    (property "Sheetname" "USB-PD")
    (attr smd)
    (fp_text reference "TP90" (at 1.19 -0.49 180) (layer "B.SilkS")
      (effects (font (size 0.7 0.7) (thickness 0.15)) (justify left bottom mirror))
    )
    (fp_text value "TP_0.75mm_SMD" (at 0 -1.2 180) (layer "B.Fab")
      (effects (font (size 0.7 0.7) (thickness 0.15)) (justify left bottom mirror))
    )
    (fp_text user "License: Apache-2.0" (at -0.4 -5.101 180) (layer "B.Fab") hide
      (effects (font (size 0.7 0.7) (thickness 0.15)) (justify left bottom mirror))
    )
    (fp_text user "Author: Antmicro" (at -0.4 -3.901 180) (layer "B.Fab") hide
      (effects (font (size 0.7 0.7) (thickness 0.15)) (justify left bottom mirror))
    )
    (fp_text user "${REFERENCE}" (at -0.4 -2.7 180) (layer "B.Fab") hide
      (effects (font (size 0.7 0.7) (thickness 0.15)) (justify left bottom mirror))
    )
    (pad "1" smd circle (at 0 0) (size 0.75 0.75) (layers "B.Cu" "B.Mask")
      (net 141 "/USB-PD/VREG_2V7") (pinfunction "1") (pintype "passive"))
  )

  (footprint "sa800u-baseboard-hw-footprints:TP_SMD_0.75mm" (layer "B.Cu")
    (tedit 5E4A9375)
    (at 95.6 132.8)
    (property "Author" "Antmicro")
    (property "License" "Apache-2.0")
    (property "MPN" "")
    (property "Manufacturer" "")
    (property "Sheetfile" "usb-pd.kicad_sch")
    (property "Sheetname" "USB-PD")
    (attr smd)
    (fp_text reference "TP93" (at -0.4 0.37 180) (layer "B.SilkS")
      (effects (font (size 0.7 0.7) (thickness 0.15)) (justify left bottom mirror))
    )
    (fp_text value "TP_0.75mm_SMD" (at 0 -1.2 180) (layer "B.Fab")
      (effects (font (size 0.7 0.7) (thickness 0.15)) (justify left bottom mirror))
    )
    (fp_text user "Author: Antmicro" (at -0.4 -3.901 180) (layer "B.Fab") hide
      (effects (font (size 0.7 0.7) (thickness 0.15)) (justify left bottom mirror))
    )
    (fp_text user "License: Apache-2.0" (at -0.4 -5.101 180) (layer "B.Fab") hide
      (effects (font (size 0.7 0.7) (thickness 0.15)) (justify left bottom mirror))
    )
    (fp_text user "${REFERENCE}" (at -0.4 -2.7 180) (layer "B.Fab") hide
      (effects (font (size 0.7 0.7) (thickness 0.15)) (justify left bottom mirror))
    )
    (pad "1" smd circle (at 0 0) (size 0.75 0.75) (layers "B.Cu" "B.Mask")
      (net 169 "/USB-PD/STUSB4500_PWR_OK2") (pinfunction "1") (pintype "passive"))
  )

  (footprint "sa800u-baseboard-hw-footprints:TP_SMD_0.75mm" (layer "B.Cu")
    (tedit 5E4A9375)
    (at 95.6 131.2)
    (property "Author" "Antmicro")
    (property "License" "Apache-2.0")
    (property "MPN" "")
    (property "Manufacturer" "")
    (property "Sheetfile" "usb-pd.kicad_sch")
    (property "Sheetname" "USB-PD")
    (attr smd)
    (fp_text reference "TP94" (at -0.5 0.34 180) (layer "B.SilkS")
      (effects (font (size 0.7 0.7) (thickness 0.15)) (justify left bottom mirror))
    )
    (fp_text value "TP_0.75mm_SMD" (at 0 -1.2 180) (layer "B.Fab")
      (effects (font (size 0.7 0.7) (thickness 0.15)) (justify left bottom mirror))
    )
    (fp_text user "Author: Antmicro" (at -0.4 -3.901 180) (layer "B.Fab") hide
      (effects (font (size 0.7 0.7) (thickness 0.15)) (justify left bottom mirror))
    )
    (fp_text user "License: Apache-2.0" (at -0.4 -5.101 180) (layer "B.Fab") hide
      (effects (font (size 0.7 0.7) (thickness 0.15)) (justify left bottom mirror))
    )
    (fp_text user "${REFERENCE}" (at -0.4 -2.7 180) (layer "B.Fab") hide
      (effects (font (size 0.7 0.7) (thickness 0.15)) (justify left bottom mirror))
    )
    (pad "1" smd circle (at 0 0) (size 0.75 0.75) (layers "B.Cu" "B.Mask")
      (net 170 "/USB-PD/STUSB4500_PWR_OK3") (pinfunction "1") (pintype "passive"))
  )

  (footprint "sa800u-baseboard-hw-footprints:TP_SMD_0.75mm" (layer "B.Cu")
    (tedit 5E4A9375)
    (at 91 137.8)
    (property "Author" "Antmicro")
    (property "License" "Apache-2.0")
    (property "MPN" "")
    (property "Manufacturer" "")
    (property "Sheetfile" "usb-pd.kicad_sch")
    (property "Sheetname" "USB-PD")
    (attr smd)
    (fp_text reference "TP97" (at 1.44 1.24 180) (layer "B.SilkS")
      (effects (font (size 0.7 0.7) (thickness 0.15)) (justify left bottom mirror))
    )
    (fp_text value "TP_0.75mm_SMD" (at 0 -1.2 180) (layer "B.Fab")
      (effects (font (size 0.7 0.7) (thickness 0.15)) (justify left bottom mirror))
    )
    (fp_text user "License: Apache-2.0" (at -0.4 -5.101 180) (layer "B.Fab") hide
      (effects (font (size 0.7 0.7) (thickness 0.15)) (justify left bottom mirror))
    )
    (fp_text user "Author: Antmicro" (at -0.4 -3.901 180) (layer "B.Fab") hide
      (effects (font (size 0.7 0.7) (thickness 0.15)) (justify left bottom mirror))
    )
    (fp_text user "${REFERENCE}" (at -0.4 -2.7 180) (layer "B.Fab") hide
      (effects (font (size 0.7 0.7) (thickness 0.15)) (justify left bottom mirror))
    )
    (pad "1" smd circle (at 0 0) (size 0.75 0.75) (layers "B.Cu" "B.Mask")
      (net 107 "/USB-PD/PD_VBUS") (pinfunction "1") (pintype "passive"))
  )

  (footprint "sa800u-baseboard-hw-footprints:TP_SMD_0.75mm" (layer "B.Cu")
    (tedit 5E4A9375)
    (at 74.4 147.4)
    (property "Author" "Antmicro")
    (property "License" "Apache-2.0")
    (property "MPN" "")
    (property "Manufacturer" "")
    (property "Sheetfile" "usb-pd.kicad_sch")
    (property "Sheetname" "USB-PD")
    (attr smd)
    (fp_text reference "TP98" (at 0.78 1.28 180) (layer "B.SilkS")
      (effects (font (size 0.7 0.7) (thickness 0.15)) (justify left bottom mirror))
    )
    (fp_text value "TP_0.75mm_SMD" (at 0 -1.2 180) (layer "B.Fab")
      (effects (font (size 0.7 0.7) (thickness 0.15)) (justify left bottom mirror))
    )
    (fp_text user "License: Apache-2.0" (at -0.4 -5.101 180) (layer "B.Fab") hide
      (effects (font (size 0.7 0.7) (thickness 0.15)) (justify left bottom mirror))
    )
    (fp_text user "${REFERENCE}" (at -0.4 -2.7 180) (layer "B.Fab") hide
      (effects (font (size 0.7 0.7) (thickness 0.15)) (justify left bottom mirror))
    )
    (fp_text user "Author: Antmicro" (at -0.4 -3.901 180) (layer "B.Fab") hide
      (effects (font (size 0.7 0.7) (thickness 0.15)) (justify left bottom mirror))
    )
    (pad "1" smd circle (at 0 0) (size 0.75 0.75) (layers "B.Cu" "B.Mask")
      (net 1 "GND") (pinfunction "1") (pintype "passive"))
  )

  (footprint "sa800u-baseboard-hw-footprints:TP_SMD_0.75mm" (layer "B.Cu")
    (tedit 5E4A9375)
    (at 80.05 126.95)
    (property "Author" "Antmicro")
    (property "License" "Apache-2.0")
    (property "MPN" "")
    (property "Manufacturer" "")
    (property "Sheetfile" "psu.kicad_sch")
    (property "Sheetname" "PSU")
    (attr smd)
    (fp_text reference "TP48" (at 1.59 1.23 180) (layer "B.SilkS")
      (effects (font (size 0.7 0.7) (thickness 0.15)) (justify left bottom mirror))
    )
    (fp_text value "TP_0.75mm_SMD" (at 0 -1.2 180) (layer "B.Fab")
      (effects (font (size 0.7 0.7) (thickness 0.15)) (justify left bottom mirror))
    )
    (fp_text user "${REFERENCE}" (at -0.4 -2.7 180) (layer "B.Fab") hide
      (effects (font (size 0.7 0.7) (thickness 0.15)) (justify left bottom mirror))
    )
    (fp_text user "Author: Antmicro" (at -0.4 -3.901 180) (layer "B.Fab") hide
      (effects (font (size 0.7 0.7) (thickness 0.15)) (justify left bottom mirror))
    )
    (fp_text user "License: Apache-2.0" (at -0.4 -5.101 180) (layer "B.Fab") hide
      (effects (font (size 0.7 0.7) (thickness 0.15)) (justify left bottom mirror))
    )
    (pad "1" smd circle (at 0 0) (size 0.75 0.75) (layers "B.Cu" "B.Mask")
      (net 152 "/PSU/AUX_VDD") (pinfunction "1") (pintype "passive"))
  )

  (footprint "sa800u-baseboard-hw-footprints:TP_SMD_0.75mm" (layer "B.Cu")
    (tedit 5E4A9375)
    (at 80.05 125.2)
    (property "Author" "Antmicro")
    (property "License" "Apache-2.0")
    (property "MPN" "")
    (property "Manufacturer" "")
    (property "Sheetfile" "psu.kicad_sch")
    (property "Sheetname" "PSU")
    (attr smd)
    (fp_text reference "TP49" (at 1.57 1.24 180) (layer "B.SilkS")
      (effects (font (size 0.7 0.7) (thickness 0.15)) (justify left bottom mirror))
    )
    (fp_text value "TP_0.75mm_SMD" (at 0 -1.2 180) (layer "B.Fab")
      (effects (font (size 0.7 0.7) (thickness 0.15)) (justify left bottom mirror))
    )
    (fp_text user "License: Apache-2.0" (at -0.4 -5.101 180) (layer "B.Fab") hide
      (effects (font (size 0.7 0.7) (thickness 0.15)) (justify left bottom mirror))
    )
    (fp_text user "${REFERENCE}" (at -0.4 -2.7 180) (layer "B.Fab") hide
      (effects (font (size 0.7 0.7) (thickness 0.15)) (justify left bottom mirror))
    )
    (fp_text user "Author: Antmicro" (at -0.4 -3.901 180) (layer "B.Fab") hide
      (effects (font (size 0.7 0.7) (thickness 0.15)) (justify left bottom mirror))
    )
    (pad "1" smd circle (at 0 0) (size 0.75 0.75) (layers "B.Cu" "B.Mask")
      (net 142 "PD_VDD") (pinfunction "1") (pintype "passive"))
  )

  (footprint "sa800u-baseboard-hw-footprints:TP_SMD_0.75mm" (layer "B.Cu")
    (tedit 5E4A9375)
    (at 80.05 123.5492)
    (property "Author" "Antmicro")
    (property "License" "Apache-2.0")
    (property "MPN" "")
    (property "Manufacturer" "")
    (property "Sheetfile" "psu.kicad_sch")
    (property "Sheetname" "PSU")
    (attr smd)
    (fp_text reference "TP50" (at 1.59 1.2 180) (layer "B.SilkS")
      (effects (font (size 0.7 0.7) (thickness 0.15)) (justify left bottom mirror))
    )
    (fp_text value "TP_0.75mm_SMD" (at 0 -1.2 180) (layer "B.Fab")
      (effects (font (size 0.7 0.7) (thickness 0.15)) (justify left bottom mirror))
    )
    (fp_text user "Author: Antmicro" (at -0.4 -3.901 180) (layer "B.Fab") hide
      (effects (font (size 0.7 0.7) (thickness 0.15)) (justify left bottom mirror))
    )
    (fp_text user "License: Apache-2.0" (at -0.4 -5.101 180) (layer "B.Fab") hide
      (effects (font (size 0.7 0.7) (thickness 0.15)) (justify left bottom mirror))
    )
    (fp_text user "${REFERENCE}" (at -0.4 -2.7 180) (layer "B.Fab") hide
      (effects (font (size 0.7 0.7) (thickness 0.15)) (justify left bottom mirror))
    )
    (pad "1" smd circle (at 0 0) (size 0.75 0.75) (layers "B.Cu" "B.Mask")
      (net 136 "5V_POE") (pinfunction "1") (pintype "passive"))
  )

  (footprint "sa800u-baseboard-hw-footprints:TP_SMD_0.75mm" (layer "B.Cu")
    (tedit 5E4A9375)
    (at 70.7492 126.6 90)
    (property "Author" "Antmicro")
    (property "License" "Apache-2.0")
    (property "MPN" "")
    (property "Manufacturer" "")
    (property "Sheetfile" "psu.kicad_sch")
    (property "Sheetname" "PSU")
    (attr smd)
    (fp_text reference "TP51" (at -1.22 1.7808) (layer "B.SilkS")
      (effects (font (size 0.7 0.7) (thickness 0.15)) (justify left bottom mirror))
    )
    (fp_text value "TP_0.75mm_SMD" (at 0 -1.2 270) (layer "B.Fab")
      (effects (font (size 0.7 0.7) (thickness 0.15)) (justify left bottom mirror))
    )
    (fp_text user "License: Apache-2.0" (at -0.4 -5.101 270) (layer "B.Fab") hide
      (effects (font (size 0.7 0.7) (thickness 0.15)) (justify left bottom mirror))
    )
    (fp_text user "Author: Antmicro" (at -0.4 -3.901 270) (layer "B.Fab") hide
      (effects (font (size 0.7 0.7) (thickness 0.15)) (justify left bottom mirror))
    )
    (fp_text user "${REFERENCE}" (at -0.4 -2.7 270) (layer "B.Fab") hide
      (effects (font (size 0.7 0.7) (thickness 0.15)) (justify left bottom mirror))
    )
    (pad "1" smd circle (at 0 0 90) (size 0.75 0.75) (layers "B.Cu" "B.Mask")
      (net 354 "/PSU/G1") (pinfunction "1") (pintype "passive"))
  )

  (footprint "sa800u-baseboard-hw-footprints:TP_SMD_0.75mm" (layer "B.Cu")
    (tedit 5E4A9375)
    (at 70.8 125 90)
    (property "Author" "Antmicro")
    (property "License" "Apache-2.0")
    (property "MPN" "")
    (property "Manufacturer" "")
    (property "Sheetfile" "psu.kicad_sch")
    (property "Sheetname" "PSU")
    (attr smd)
    (fp_text reference "TP52" (at 0.49 1.77) (layer "B.SilkS")
      (effects (font (size 0.7 0.7) (thickness 0.15)) (justify left bottom mirror))
    )
    (fp_text value "TP_0.75mm_SMD" (at 0 -1.2 270) (layer "B.Fab")
      (effects (font (size 0.7 0.7) (thickness 0.15)) (justify left bottom mirror))
    )
    (fp_text user "Author: Antmicro" (at -0.4 -3.901 270) (layer "B.Fab") hide
      (effects (font (size 0.7 0.7) (thickness 0.15)) (justify left bottom mirror))
    )
    (fp_text user "${REFERENCE}" (at -0.4 -2.7 270) (layer "B.Fab") hide
      (effects (font (size 0.7 0.7) (thickness 0.15)) (justify left bottom mirror))
    )
    (fp_text user "License: Apache-2.0" (at -0.4 -5.101 270) (layer "B.Fab") hide
      (effects (font (size 0.7 0.7) (thickness 0.15)) (justify left bottom mirror))
    )
    (pad "1" smd circle (at 0 0 90) (size 0.75 0.75) (layers "B.Cu" "B.Mask")
      (net 355 "/PSU/G2") (pinfunction "1") (pintype "passive"))
  )

  (footprint "sa800u-baseboard-hw-footprints:TP_SMD_0.75mm" (layer "B.Cu")
    (tedit 5E4A9375)
    (at 70.7492 123.2 90)
    (property "Author" "Antmicro")
    (property "License" "Apache-2.0")
    (property "MPN" "")
    (property "Manufacturer" "")
    (property "Sheetfile" "psu.kicad_sch")
    (property "Sheetname" "PSU")
    (attr smd)
    (fp_text reference "TP53" (at 0.55 1.8108) (layer "B.SilkS")
      (effects (font (size 0.7 0.7) (thickness 0.15)) (justify left bottom mirror))
    )
    (fp_text value "TP_0.75mm_SMD" (at 0 -1.2 270) (layer "B.Fab")
      (effects (font (size 0.7 0.7) (thickness 0.15)) (justify left bottom mirror))
    )
    (fp_text user "License: Apache-2.0" (at -0.4 -5.101 270) (layer "B.Fab") hide
      (effects (font (size 0.7 0.7) (thickness 0.15)) (justify left bottom mirror))
    )
    (fp_text user "${REFERENCE}" (at -0.4 -2.7 270) (layer "B.Fab") hide
      (effects (font (size 0.7 0.7) (thickness 0.15)) (justify left bottom mirror))
    )
    (fp_text user "Author: Antmicro" (at -0.4 -3.901 270) (layer "B.Fab") hide
      (effects (font (size 0.7 0.7) (thickness 0.15)) (justify left bottom mirror))
    )
    (pad "1" smd circle (at 0 0 90) (size 0.75 0.75) (layers "B.Cu" "B.Mask")
      (net 367 "/PSU/G3") (pinfunction "1") (pintype "passive"))
  )

  (footprint "sa800u-baseboard-hw-footprints:TP_SMD_0.75mm" (layer "B.Cu")
    (tedit 5E4A9375)
    (at 88.2 137.8)
    (property "Author" "Antmicro")
    (property "License" "Apache-2.0")
    (property "MPN" "")
    (property "Manufacturer" "")
    (property "Sheetfile" "usb-pd.kicad_sch")
    (property "Sheetname" "USB-PD")
    (attr smd)
    (fp_text reference "TP92" (at 1.28 1.23 180) (layer "B.SilkS")
      (effects (font (size 0.7 0.7) (thickness 0.15)) (justify left bottom mirror))
    )
    (fp_text value "TP_0.75mm_SMD" (at 0 -1.2 180) (layer "B.Fab")
      (effects (font (size 0.7 0.7) (thickness 0.15)) (justify left bottom mirror))
    )
    (fp_text user "License: Apache-2.0" (at -0.4 -5.101 180) (layer "B.Fab") hide
      (effects (font (size 0.7 0.7) (thickness 0.15)) (justify left bottom mirror))
    )
    (fp_text user "${REFERENCE}" (at -0.4 -2.7 180) (layer "B.Fab") hide
      (effects (font (size 0.7 0.7) (thickness 0.15)) (justify left bottom mirror))
    )
    (fp_text user "Author: Antmicro" (at -0.4 -3.901 180) (layer "B.Fab") hide
      (effects (font (size 0.7 0.7) (thickness 0.15)) (justify left bottom mirror))
    )
    (pad "1" smd circle (at 0 0) (size 0.75 0.75) (layers "B.Cu" "B.Mask")
      (net 140 "/USB-PD/VREG_1V2") (pinfunction "1") (pintype "passive"))
  )

  (footprint "sa800u-baseboard-hw-footprints:TP_SMD_0.75mm" (layer "B.Cu")
    (tedit 5E4A9375)
    (at 90 119.2)
    (property "Author" "Antmicro")
    (property "License" "Apache-2.0")
    (property "MPN" "")
    (property "Manufacturer" "")
    (property "Sheetfile" "psu.kicad_sch")
    (property "Sheetname" "PSU")
    (attr smd)
    (fp_text reference "TP73" (at 1.33 1.23 180) (layer "B.SilkS")
      (effects (font (size 0.7 0.7) (thickness 0.15)) (justify left bottom mirror))
    )
    (fp_text value "TP_0.75mm_SMD" (at 0 -1.2 180) (layer "B.Fab")
      (effects (font (size 0.7 0.7) (thickness 0.15)) (justify left bottom mirror))
    )
    (fp_text user "License: Apache-2.0" (at -0.4 -5.101 180) (layer "B.Fab") hide
      (effects (font (size 0.7 0.7) (thickness 0.15)) (justify left bottom mirror))
    )
    (fp_text user "${REFERENCE}" (at -0.4 -2.7 180) (layer "B.Fab") hide
      (effects (font (size 0.7 0.7) (thickness 0.15)) (justify left bottom mirror))
    )
    (fp_text user "Author: Antmicro" (at -0.4 -3.901 180) (layer "B.Fab") hide
      (effects (font (size 0.7 0.7) (thickness 0.15)) (justify left bottom mirror))
    )
    (pad "1" smd circle (at 0 0) (size 0.75 0.75) (layers "B.Cu" "B.Mask")
      (net 133 "5V_SYS") (pinfunction "1") (pintype "passive"))
  )

  (footprint "sa800u-baseboard-hw-footprints:TP_SMD_0.75mm" (layer "B.Cu")
    (tedit 5E4A9375)
    (at 87.6 119.2)
    (property "Author" "Antmicro")
    (property "License" "Apache-2.0")
    (property "MPN" "")
    (property "Manufacturer" "")
    (property "Sheetfile" "psu.kicad_sch")
    (property "Sheetname" "PSU")
    (attr smd)
    (fp_text reference "TP68" (at 1.23 -0.46 180) (layer "B.SilkS")
      (effects (font (size 0.7 0.7) (thickness 0.15)) (justify left bottom mirror))
    )
    (fp_text value "TP_0.75mm_SMD" (at 0 -1.2 180) (layer "B.Fab")
      (effects (font (size 0.7 0.7) (thickness 0.15)) (justify left bottom mirror))
    )
    (fp_text user "License: Apache-2.0" (at -0.4 -5.101 180) (layer "B.Fab") hide
      (effects (font (size 0.7 0.7) (thickness 0.15)) (justify left bottom mirror))
    )
    (fp_text user "Author: Antmicro" (at -0.4 -3.901 180) (layer "B.Fab") hide
      (effects (font (size 0.7 0.7) (thickness 0.15)) (justify left bottom mirror))
    )
    (fp_text user "${REFERENCE}" (at -0.4 -2.7 180) (layer "B.Fab") hide
      (effects (font (size 0.7 0.7) (thickness 0.15)) (justify left bottom mirror))
    )
    (pad "1" smd circle (at 0 0) (size 0.75 0.75) (layers "B.Cu" "B.Mask")
      (net 74 "VDD") (pinfunction "1") (pintype "passive"))
  )

  (footprint "sa800u-baseboard-hw-footprints:TP_SMD_0.75mm" (layer "B.Cu")
    (tedit 5E4A9375)
    (at 87.6 100.4)
    (property "Author" "Antmicro")
    (property "License" "Apache-2.0")
    (property "MPN" "")
    (property "Manufacturer" "")
    (property "Sheetfile" "psu.kicad_sch")
    (property "Sheetname" "PSU")
    (attr smd)
    (fp_text reference "TP61" (at 1.14 1.3 180) (layer "B.SilkS")
      (effects (font (size 0.7 0.7) (thickness 0.15)) (justify left bottom mirror))
    )
    (fp_text value "TP_0.75mm_SMD" (at 0 -1.2 180) (layer "B.Fab")
      (effects (font (size 0.7 0.7) (thickness 0.15)) (justify left bottom mirror))
    )
    (fp_text user "Author: Antmicro" (at -0.4 -3.901 180) (layer "B.Fab") hide
      (effects (font (size 0.7 0.7) (thickness 0.15)) (justify left bottom mirror))
    )
    (fp_text user "${REFERENCE}" (at -0.4 -2.7 180) (layer "B.Fab") hide
      (effects (font (size 0.7 0.7) (thickness 0.15)) (justify left bottom mirror))
    )
    (fp_text user "License: Apache-2.0" (at -0.4 -5.101 180) (layer "B.Fab") hide
      (effects (font (size 0.7 0.7) (thickness 0.15)) (justify left bottom mirror))
    )
    (pad "1" smd circle (at 0 0) (size 0.75 0.75) (layers "B.Cu" "B.Mask")
      (net 74 "VDD") (pinfunction "1") (pintype "passive"))
  )

  (footprint "sa800u-baseboard-hw-footprints:TP_SMD_0.75mm" (layer "B.Cu")
    (tedit 5E4A9375)
    (at 90.1 100.4)
    (property "Author" "Antmicro")
    (property "License" "Apache-2.0")
    (property "MPN" "")
    (property "Manufacturer" "")
    (property "Sheetfile" "psu.kicad_sch")
    (property "Sheetname" "PSU")
    (attr smd)
    (fp_text reference "TP70" (at 1.38 1.3 180) (layer "B.SilkS")
      (effects (font (size 0.7 0.7) (thickness 0.15)) (justify left bottom mirror))
    )
    (fp_text value "TP_0.75mm_SMD" (at 0 -1.2 180) (layer "B.Fab")
      (effects (font (size 0.7 0.7) (thickness 0.15)) (justify left bottom mirror))
    )
    (fp_text user "${REFERENCE}" (at -0.4 -2.7 180) (layer "B.Fab") hide
      (effects (font (size 0.7 0.7) (thickness 0.15)) (justify left bottom mirror))
    )
    (fp_text user "Author: Antmicro" (at -0.4 -3.901 180) (layer "B.Fab") hide
      (effects (font (size 0.7 0.7) (thickness 0.15)) (justify left bottom mirror))
    )
    (fp_text user "License: Apache-2.0" (at -0.4 -5.101 180) (layer "B.Fab") hide
      (effects (font (size 0.7 0.7) (thickness 0.15)) (justify left bottom mirror))
    )
    (pad "1" smd circle (at 0 0) (size 0.75 0.75) (layers "B.Cu" "B.Mask")
      (net 137 "3V8_SYS") (pinfunction "1") (pintype "passive"))
  )

  (footprint "sa800u-baseboard-hw-footprints:TP_SMD_0.75mm" (layer "B.Cu")
    (tedit 5E4A9375)
    (at 85.1 100.4)
    (property "Author" "Antmicro")
    (property "License" "Apache-2.0")
    (property "MPN" "")
    (property "Manufacturer" "")
    (property "Sheetfile" "psu.kicad_sch")
    (property "Sheetname" "PSU")
    (attr smd)
    (fp_text reference "TP74" (at 0.85 1.32 180) (layer "B.SilkS")
      (effects (font (size 0.7 0.7) (thickness 0.15)) (justify left bottom mirror))
    )
    (fp_text value "TP_0.75mm_SMD" (at 0 -1.2 180) (layer "B.Fab")
      (effects (font (size 0.7 0.7) (thickness 0.15)) (justify left bottom mirror))
    )
    (fp_text user "Author: Antmicro" (at -0.4 -3.901 180) (layer "B.Fab") hide
      (effects (font (size 0.7 0.7) (thickness 0.15)) (justify left bottom mirror))
    )
    (fp_text user "License: Apache-2.0" (at -0.4 -5.101 180) (layer "B.Fab") hide
      (effects (font (size 0.7 0.7) (thickness 0.15)) (justify left bottom mirror))
    )
    (fp_text user "${REFERENCE}" (at -0.4 -2.7 180) (layer "B.Fab") hide
      (effects (font (size 0.7 0.7) (thickness 0.15)) (justify left bottom mirror))
    )
    (pad "1" smd circle (at 0 0) (size 0.75 0.75) (layers "B.Cu" "B.Mask")
      (net 1 "GND") (pinfunction "1") (pintype "passive"))
  )

  (footprint "sa800u-baseboard-hw-footprints:TP_SMD_0.75mm" (layer "B.Cu")
    (tedit 5E4A9375)
    (at 119.5 106.3)
    (property "Author" "Antmicro")
    (property "License" "Apache-2.0")
    (property "MPN" "")
    (property "Manufacturer" "")
    (property "Sheetfile" "camera-interface.kicad_sch")
    (property "Sheetname" "Camera Interface")
    (attr smd)
    (fp_text reference "TP28" (at -0.31 0.39 180) (layer "B.SilkS")
      (effects (font (size 0.7 0.7) (thickness 0.15)) (justify left bottom mirror))
    )
    (fp_text value "TP_0.75mm_SMD" (at 0 -1.2 180) (layer "B.Fab")
      (effects (font (size 0.7 0.7) (thickness 0.15)) (justify left bottom mirror))
    )
    (fp_text user "License: Apache-2.0" (at -0.4 -5.101 180) (layer "B.Fab") hide
      (effects (font (size 0.7 0.7) (thickness 0.15)) (justify left bottom mirror))
    )
    (fp_text user "${REFERENCE}" (at -0.4 -2.7 180) (layer "B.Fab") hide
      (effects (font (size 0.7 0.7) (thickness 0.15)) (justify left bottom mirror))
    )
    (fp_text user "Author: Antmicro" (at -0.4 -3.901 180) (layer "B.Fab") hide
      (effects (font (size 0.7 0.7) (thickness 0.15)) (justify left bottom mirror))
    )
    (pad "1" smd circle (at 0 0) (size 0.75 0.75) (layers "B.Cu" "B.Mask")
      (net 133 "5V_SYS") (pinfunction "1") (pintype "passive"))
  )

  (footprint "sa800u-baseboard-hw-footprints:TP_SMD_0.75mm" (layer "B.Cu")
    (tedit 5E4A9375)
    (at 110.4 97.2)
    (property "Author" "Antmicro")
    (property "License" "Apache-2.0")
    (property "MPN" "")
    (property "Manufacturer" "")
    (property "Sheetfile" "camera-interface.kicad_sch")
    (property "Sheetname" "Camera Interface")
    (attr smd)
    (fp_text reference "TP29" (at 0.44 0.34 270) (layer "B.SilkS")
      (effects (font (size 0.7 0.7) (thickness 0.15)) (justify left bottom mirror))
    )
    (fp_text value "TP_0.75mm_SMD" (at 0 -1.2 180) (layer "B.Fab")
      (effects (font (size 0.7 0.7) (thickness 0.15)) (justify left bottom mirror))
    )
    (fp_text user "${REFERENCE}" (at -0.4 -2.7 180) (layer "B.Fab") hide
      (effects (font (size 0.7 0.7) (thickness 0.15)) (justify left bottom mirror))
    )
    (fp_text user "License: Apache-2.0" (at -0.4 -5.101 180) (layer "B.Fab") hide
      (effects (font (size 0.7 0.7) (thickness 0.15)) (justify left bottom mirror))
    )
    (fp_text user "Author: Antmicro" (at -0.4 -3.901 180) (layer "B.Fab") hide
      (effects (font (size 0.7 0.7) (thickness 0.15)) (justify left bottom mirror))
    )
    (pad "1" smd circle (at 0 0) (size 0.75 0.75) (layers "B.Cu" "B.Mask")
      (net 45 "CCI1_I2C_SDA") (pinfunction "1") (pintype "passive"))
  )

  (footprint "sa800u-baseboard-hw-footprints:TP_SMD_0.75mm" (layer "B.Cu")
    (tedit 5E4A9375)
    (at 111.8 97.2)
    (property "Author" "Antmicro")
    (property "License" "Apache-2.0")
    (property "MPN" "")
    (property "Manufacturer" "")
    (property "Sheetfile" "camera-interface.kicad_sch")
    (property "Sheetname" "Camera Interface")
    (attr smd)
    (fp_text reference "TP31" (at 0.4 0.34 270) (layer "B.SilkS")
      (effects (font (size 0.7 0.7) (thickness 0.15)) (justify left bottom mirror))
    )
    (fp_text value "TP_0.75mm_SMD" (at 0 -1.2 180) (layer "B.Fab")
      (effects (font (size 0.7 0.7) (thickness 0.15)) (justify left bottom mirror))
    )
    (fp_text user "Author: Antmicro" (at -0.4 -3.901 180) (layer "B.Fab") hide
      (effects (font (size 0.7 0.7) (thickness 0.15)) (justify left bottom mirror))
    )
    (fp_text user "License: Apache-2.0" (at -0.4 -5.101 180) (layer "B.Fab") hide
      (effects (font (size 0.7 0.7) (thickness 0.15)) (justify left bottom mirror))
    )
    (fp_text user "${REFERENCE}" (at -0.4 -2.7 180) (layer "B.Fab") hide
      (effects (font (size 0.7 0.7) (thickness 0.15)) (justify left bottom mirror))
    )
    (pad "1" smd circle (at 0 0) (size 0.75 0.75) (layers "B.Cu" "B.Mask")
      (net 44 "CCI1_I2C_SCL") (pinfunction "1") (pintype "passive"))
  )

  (footprint "sa800u-baseboard-hw-footprints:TP_SMD_0.75mm" (layer "B.Cu")
    (tedit 5E4A9375)
    (at 111.2 94.6)
    (property "Author" "Antmicro")
    (property "License" "Apache-2.0")
    (property "MPN" "")
    (property "Manufacturer" "")
    (property "Sheetfile" "camera-interface.kicad_sch")
    (property "Sheetname" "Camera Interface")
    (attr smd)
    (fp_text reference "TP32" (at 3 0.86 180) (layer "B.SilkS")
      (effects (font (size 0.7 0.7) (thickness 0.15)) (justify left bottom mirror))
    )
    (fp_text value "TP_0.75mm_SMD" (at 0 -1.2 180) (layer "B.Fab")
      (effects (font (size 0.7 0.7) (thickness 0.15)) (justify left bottom mirror))
    )
    (fp_text user "Author: Antmicro" (at -0.4 -3.901 180) (layer "B.Fab") hide
      (effects (font (size 0.7 0.7) (thickness 0.15)) (justify left bottom mirror))
    )
    (fp_text user "${REFERENCE}" (at -0.4 -2.7 180) (layer "B.Fab") hide
      (effects (font (size 0.7 0.7) (thickness 0.15)) (justify left bottom mirror))
    )
    (fp_text user "License: Apache-2.0" (at -0.4 -5.101 180) (layer "B.Fab") hide
      (effects (font (size 0.7 0.7) (thickness 0.15)) (justify left bottom mirror))
    )
    (pad "1" smd circle (at 0 0) (size 0.75 0.75) (layers "B.Cu" "B.Mask")
      (net 42 "CCI0_I2C_SCL") (pinfunction "1") (pintype "passive"))
  )

  (footprint "sa800u-baseboard-hw-footprints:TP_SMD_0.75mm" (layer "B.Cu")
    (tedit 5E4A9375)
    (at 117.35 94.4992)
    (property "Author" "Antmicro")
    (property "License" "Apache-2.0")
    (property "MPN" "")
    (property "Manufacturer" "")
    (property "Sheetfile" "camera-interface.kicad_sch")
    (property "Sheetname" "Camera Interface")
    (attr smd)
    (fp_text reference "TP33" (at 1.25 -0.4892 180) (layer "B.SilkS")
      (effects (font (size 0.7 0.7) (thickness 0.15)) (justify left bottom mirror))
    )
    (fp_text value "TP_0.75mm_SMD" (at 0 -1.2 180) (layer "B.Fab")
      (effects (font (size 0.7 0.7) (thickness 0.15)) (justify left bottom mirror))
    )
    (fp_text user "License: Apache-2.0" (at -0.4 -5.101 180) (layer "B.Fab") hide
      (effects (font (size 0.7 0.7) (thickness 0.15)) (justify left bottom mirror))
    )
    (fp_text user "Author: Antmicro" (at -0.4 -3.901 180) (layer "B.Fab") hide
      (effects (font (size 0.7 0.7) (thickness 0.15)) (justify left bottom mirror))
    )
    (fp_text user "${REFERENCE}" (at -0.4 -2.7 180) (layer "B.Fab") hide
      (effects (font (size 0.7 0.7) (thickness 0.15)) (justify left bottom mirror))
    )
    (pad "1" smd circle (at 0 0) (size 0.75 0.75) (layers "B.Cu" "B.Mask")
      (net 353 "Net-(C108-Pad1)") (pinfunction "1") (pintype "passive"))
  )

  (footprint "sa800u-baseboard-hw-footprints:TP_SMD_0.75mm" (layer "B.Cu")
    (tedit 5E4A9375)
    (at 114.1 92)
    (property "Author" "Antmicro")
    (property "License" "Apache-2.0")
    (property "MPN" "")
    (property "Manufacturer" "")
    (property "Sheetfile" "camera-interface.kicad_sch")
    (property "Sheetname" "Camera Interface")
    (attr smd)
    (fp_text reference "TP35" (at 1.43 -0.5 180) (layer "B.SilkS")
      (effects (font (size 0.7 0.7) (thickness 0.15)) (justify left bottom mirror))
    )
    (fp_text value "TP_0.75mm_SMD" (at 0 -1.2 180) (layer "B.Fab")
      (effects (font (size 0.7 0.7) (thickness 0.15)) (justify left bottom mirror))
    )
    (fp_text user "${REFERENCE}" (at -0.4 -2.7 180) (layer "B.Fab") hide
      (effects (font (size 0.7 0.7) (thickness 0.15)) (justify left bottom mirror))
    )
    (fp_text user "License: Apache-2.0" (at -0.4 -5.101 180) (layer "B.Fab") hide
      (effects (font (size 0.7 0.7) (thickness 0.15)) (justify left bottom mirror))
    )
    (fp_text user "Author: Antmicro" (at -0.4 -3.901 180) (layer "B.Fab") hide
      (effects (font (size 0.7 0.7) (thickness 0.15)) (justify left bottom mirror))
    )
    (pad "1" smd circle (at 0 0) (size 0.75 0.75) (layers "B.Cu" "B.Mask")
      (net 293 "/Camera Interface/CCI1_I2C_SCL_3V3") (pinfunction "1") (pintype "passive"))
  )

  (footprint "sa800u-baseboard-hw-footprints:TP_SMD_0.75mm" (layer "B.Cu")
    (tedit 5E4A9375)
    (at 107.6 97.2)
    (property "Author" "Antmicro")
    (property "License" "Apache-2.0")
    (property "MPN" "")
    (property "Manufacturer" "")
    (property "Sheetfile" "camera-interface.kicad_sch")
    (property "Sheetname" "Camera Interface")
    (attr smd)
    (fp_text reference "TP39" (at 0.38 0.32 270) (layer "B.SilkS")
      (effects (font (size 0.7 0.7) (thickness 0.15)) (justify left bottom mirror))
    )
    (fp_text value "TP_0.75mm_SMD" (at 0 -1.2 180) (layer "B.Fab")
      (effects (font (size 0.7 0.7) (thickness 0.15)) (justify left bottom mirror))
    )
    (fp_text user "License: Apache-2.0" (at -0.4 -5.101 180) (layer "B.Fab") hide
      (effects (font (size 0.7 0.7) (thickness 0.15)) (justify left bottom mirror))
    )
    (fp_text user "${REFERENCE}" (at -0.4 -2.7 180) (layer "B.Fab") hide
      (effects (font (size 0.7 0.7) (thickness 0.15)) (justify left bottom mirror))
    )
    (fp_text user "Author: Antmicro" (at -0.4 -3.901 180) (layer "B.Fab") hide
      (effects (font (size 0.7 0.7) (thickness 0.15)) (justify left bottom mirror))
    )
    (pad "1" smd circle (at 0 0) (size 0.75 0.75) (layers "B.Cu" "B.Mask")
      (net 15 "CAM0_RST") (pinfunction "1") (pintype "passive"))
  )

  (footprint "sa800u-baseboard-hw-footprints:TP_SMD_0.75mm" (layer "B.Cu")
    (tedit 5E4A9375)
    (at 106.2 97.2)
    (property "Author" "Antmicro")
    (property "License" "Apache-2.0")
    (property "MPN" "")
    (property "Manufacturer" "")
    (property "Sheetfile" "camera-interface.kicad_sch")
    (property "Sheetname" "Camera Interface")
    (attr smd)
    (fp_text reference "TP40" (at 0.41 0.29 270) (layer "B.SilkS")
      (effects (font (size 0.7 0.7) (thickness 0.15)) (justify left bottom mirror))
    )
    (fp_text value "TP_0.75mm_SMD" (at 0 -1.2 180) (layer "B.Fab")
      (effects (font (size 0.7 0.7) (thickness 0.15)) (justify left bottom mirror))
    )
    (fp_text user "Author: Antmicro" (at -0.4 -3.901 180) (layer "B.Fab") hide
      (effects (font (size 0.7 0.7) (thickness 0.15)) (justify left bottom mirror))
    )
    (fp_text user "${REFERENCE}" (at -0.4 -2.7 180) (layer "B.Fab") hide
      (effects (font (size 0.7 0.7) (thickness 0.15)) (justify left bottom mirror))
    )
    (fp_text user "License: Apache-2.0" (at -0.4 -5.101 180) (layer "B.Fab") hide
      (effects (font (size 0.7 0.7) (thickness 0.15)) (justify left bottom mirror))
    )
    (pad "1" smd circle (at 0 0) (size 0.75 0.75) (layers "B.Cu" "B.Mask")
      (net 14 "CAM0_PWDN") (pinfunction "1") (pintype "passive"))
  )

  (footprint "sa800u-baseboard-hw-footprints:TP_SMD_0.75mm" (layer "B.Cu")
    (tedit 5E4A9375)
    (at 109 97.2)
    (property "Author" "Antmicro")
    (property "License" "Apache-2.0")
    (property "MPN" "")
    (property "Manufacturer" "")
    (property "Sheetfile" "camera-interface.kicad_sch")
    (property "Sheetname" "Camera Interface")
    (attr smd)
    (fp_text reference "TP41" (at 0.39 0.35 270) (layer "B.SilkS")
      (effects (font (size 0.7 0.7) (thickness 0.15)) (justify left bottom mirror))
    )
    (fp_text value "TP_0.75mm_SMD" (at 0 -1.2 180) (layer "B.Fab")
      (effects (font (size 0.7 0.7) (thickness 0.15)) (justify left bottom mirror))
    )
    (fp_text user "${REFERENCE}" (at -0.4 -2.7 180) (layer "B.Fab") hide
      (effects (font (size 0.7 0.7) (thickness 0.15)) (justify left bottom mirror))
    )
    (fp_text user "Author: Antmicro" (at -0.4 -3.901 180) (layer "B.Fab") hide
      (effects (font (size 0.7 0.7) (thickness 0.15)) (justify left bottom mirror))
    )
    (fp_text user "License: Apache-2.0" (at -0.4 -5.101 180) (layer "B.Fab") hide
      (effects (font (size 0.7 0.7) (thickness 0.15)) (justify left bottom mirror))
    )
    (pad "1" smd circle (at 0 0) (size 0.75 0.75) (layers "B.Cu" "B.Mask")
      (net 16 "CAM1_PWDN") (pinfunction "1") (pintype "passive"))
  )

  (footprint "sa800u-baseboard-hw-footprints:TP_SMD_0.75mm" (layer "B.Cu")
    (tedit 5E4A9375)
    (at 82.25 86.5)
    (property "Author" "Antmicro")
    (property "License" "Apache-2.0")
    (property "MPN" "")
    (property "Manufacturer" "")
    (property "Sheetfile" "som.kicad_sch")
    (property "Sheetname" "SoM")
    (attr smd)
    (fp_text reference "TP112" (at 1.33 -0.57 180) (layer "B.SilkS")
      (effects (font (size 0.7 0.7) (thickness 0.15)) (justify left bottom mirror))
    )
    (fp_text value "TP_0.75mm_SMD" (at 0 -1.2 180) (layer "B.Fab")
      (effects (font (size 0.7 0.7) (thickness 0.15)) (justify left bottom mirror))
    )
    (fp_text user "License: Apache-2.0" (at -0.4 -5.101 180) (layer "B.Fab") hide
      (effects (font (size 0.7 0.7) (thickness 0.15)) (justify left bottom mirror))
    )
    (fp_text user "${REFERENCE}" (at -0.4 -2.7 180) (layer "B.Fab") hide
      (effects (font (size 0.7 0.7) (thickness 0.15)) (justify left bottom mirror))
    )
    (fp_text user "Author: Antmicro" (at -0.4 -3.901 180) (layer "B.Fab") hide
      (effects (font (size 0.7 0.7) (thickness 0.15)) (justify left bottom mirror))
    )
    (pad "1" smd circle (at 0 0) (size 0.75 0.75) (layers "B.Cu" "B.Mask")
      (net 424 "/SoM/VBAT_SOM") (pinfunction "1") (pintype "passive"))
  )

  (footprint "sa800u-baseboard-hw-footprints:Spacer_SMD_M2.5_H4mm_Wurth_9774040151" (layer "B.Cu")
    (tedit 6215E167)
    (at 66.81 100.45 180)
    (descr "Spacer steel M2.5 h=4mm fi=5.1mm")
    (property "Author" "Antmicro")
    (property "License" "Apache-2.0")
    (property "MPN" "9774040151R")
    (property "Manufacturer" "Würth Elektronik")
    (property "Sheetfile" "m2.kicad_sch")
    (property "Sheetname" "M2")
    (attr smd)
    (fp_text reference "SP5" (at -1.1 3.4) (layer "B.SilkS")
      (effects (font (size 0.7 0.7) (thickness 0.15)) (justify left bottom mirror))
    )
    (fp_text value "Spacer_H4.0mm_9774040151" (at -11.7 -4.2) (layer "B.Fab")
      (effects (font (size 0.7 0.7) (thickness 0.15)) (justify left bottom mirror))
    )
    (fp_text user "${REFERENCE}" (at -2.551 -6.349) (layer "B.Fab") hide
      (effects (font (size 0.7 0.7) (thickness 0.15)) (justify left bottom mirror))
    )
    (fp_text user "License: Apache-2.0" (at -2.551 -8.749) (layer "B.Fab") hide
      (effects (font (size 0.7 0.7) (thickness 0.15)) (justify left bottom mirror))
    )
    (fp_text user "Author: Antmicro" (at -2.551 -7.549) (layer "B.Fab") hide
      (effects (font (size 0.7 0.7) (thickness 0.15)) (justify left bottom mirror))
    )
    (fp_circle (center 0 0) (end 2.499 0) (layer "B.Paste") (width 1) (fill none))
    (pad "1" thru_hole circle (at 0 0 180) (size 6 6) (drill 3.7) (layers *.Cu *.Mask)
      (net 1 "GND") (pinfunction "1") (pintype "passive") (solder_paste_margin -1.2))
  )
  (gr_line (start 55 152) (end 155 152) (layer "Edge.Cuts") (width 0.05))
  (gr_line (start 155 82) (end 155 132) (layer "Edge.Cuts") (width 0.05))
  (gr_line (start 55 82) (end 155 82) (layer "Edge.Cuts") (width 0.05))
  (gr_line (start 155 132) (end 155 152) (layer "Edge.Cuts") (width 0.05))
  (gr_line (start 55 82) (end 55 132) (layer "Edge.Cuts") (width 0.05))
  (gr_line (start 55 152) (end 55 132) (layer "Edge.Cuts") (width 0.05))
  (gr_line (start 69.5 110.7) (end 69.5 128.5) (layer "Edge.Cuts") (width 0.05))
  (gr_line (start 69.9 110.7) (end 69.9 128.5) (layer "Edge.Cuts") (width 0.05))
  (gr_arc (start 69.5 110.7) (mid 69.7 110.5) (end 69.9 110.7) (layer "Edge.Cuts") (width 0.05))
  (gr_arc (start 69.9 128.5) (mid 69.7 128.7) (end 69.5 128.5) (layer "Edge.Cuts") (width 0.05))
  (gr_text "10/2023" (at 110.75 132.25) (layer "F.Cu")
    (effects (font (size 0.65 0.65) (thickness 0.15)) (justify left))
  )
  (gr_text "Rev. 1.0.3\n" (at 105.25 132.25) (layer "F.Cu")
    (effects (font (size 0.65 0.65) (thickness 0.15)) (justify left))
  )
  (gr_text "SA800U Baseboard" (at 105.25 130.75) (layer "F.Cu")
    (effects (font (size 0.65 0.65) (thickness 0.15)) (justify left))
  )

  (segment (start 102.034174 104.972734) (end 101.949174 105.057734) (width 0.23) (layer "F.Cu") (net 1))
  (segment (start 102.034174 104.257733) (end 102.034174 104.972734) (width 0.23) (layer "F.Cu") (net 1))
  (segment (start 93.1 139.315) (end 93.1 138.65) (width 0.155) (layer "F.Cu") (net 1))
  (segment (start 113 143.04) (end 113 143.9) (width 0.25) (layer "F.Cu") (net 1))
  (segment (start 112.75 144.74) (end 112.75 144.15) (width 0.25) (layer "F.Cu") (net 1))
  (segment (start 112.75 144.15) (end 113 143.9) (width 0.25) (layer "F.Cu") (net 1))
  (segment (start 131.225 138.175) (end 130.5 138.175) (width 0.2) (layer "F.Cu") (net 1))
  (segment (start 130.5 138.175) (end 128.75 136.425) (width 0.2) (layer "F.Cu") (net 1))
  (segment (start 131.225 136.675) (end 129.175 136.675) (width 0.2) (layer "F.Cu") (net 1))
  (segment (start 131.225 134.675) (end 130.6 134.675) (width 0.2) (layer "F.Cu") (net 1))
  (segment (start 130.6 134.675) (end 128.85 136.425) (width 0.2) (layer "F.Cu") (net 1))
  (segment (start 130 133.95) (end 130 135) (width 0.2) (layer "F.Cu") (net 1))
  (segment (start 126.275 136.175) (end 128.5 136.175) (width 0.2) (layer "F.Cu") (net 1))
  (segment (start 129 140.6125) (end 129 139.8) (width 0.2) (layer "F.Cu") (net 1))
  (segment (start 129 141.3875) (end 129 140.6125) (width 0.2) (layer "F.Cu") (net 1))
  (segment (start 133.385 137.3) (end 133.385 138.085) (width 0.2) (layer "F.Cu") (net 1))
  (segment (start 133.385 138.085) (end 133.4 138.1) (width 0.2) (layer "F.Cu") (net 1))
  (segment (start 133.385 138.9) (end 133.385 138.115) (width 0.2) (layer "F.Cu") (net 1))
  (segment (start 133.385 138.115) (end 133.4 138.1) (width 0.2) (layer "F.Cu") (net 1))
  (segment (start 132.5 143.04) (end 132.5 143.7) (width 0.2) (layer "F.Cu") (net 1))
  (segment (start 132.5 143.7) (end 132.3 143.9) (width 0.2) (layer "F.Cu") (net 1))
  (segment (start 132.25 144.74) (end 132.25 143.95) (width 0.2) (layer "F.Cu") (net 1))
  (segment (start 132.25 143.95) (end 132.3 143.9) (width 0.2) (layer "F.Cu") (net 1))
  (segment (start 95.8 130.55) (end 94.65 130.55) (width 0.15) (layer "F.Cu") (net 1))
  (segment (start 145.25 139.1625) (end 145.25 138.65) (width 0.2) (layer "F.Cu") (net 1))
  (segment (start 145.25 139.9375) (end 145.25 139.1625) (width 0.2) (layer "F.Cu") (net 1))
  (segment (start 142.2 139.1625) (end 142.2 138.575003) (width 0.2) (layer "F.Cu") (net 1))
  (segment (start 142.2 139.1625) (end 142.2 139.9375) (width 0.2) (layer "F.Cu") (net 1))
  (segment (start 138.85 139.1625) (end 138.85 138.575003) (width 0.2) (layer "F.Cu") (net 1))
  (segment (start 138.85 139.1625) (end 138.85 139.9375) (width 0.2) (layer "F.Cu") (net 1))
  (segment (start 115.35 139.0875) (end 115.35 138.3125) (width 0.2) (layer "F.Cu") (net 1))
  (segment (start 147.4 113.54) (end 146.15 113.54) (width 0.125) (layer "F.Cu") (net 1))
  (segment (start 94.7 147.324998) (end 94.775002 147.4) (width 0.2) (layer "F.Cu") (net 1))
  (segment (start 149.95 110.7) (end 151.6 110.7) (width 0.155) (layer "F.Cu") (net 1))
  (segment (start 97.2 103.8) (end 96.9 103.5) (width 0.25) (layer "F.Cu") (net 1))
  (segment (start 82.915 134) (end 82.915 134.635) (width 0.2) (layer "F.Cu") (net 1))
  (segment (start 122.25 84.495911) (end 122.13749 84.608421) (width 0.3) (layer "F.Cu") (net 1))
  (segment (start 102.960002 88.3) (end 101.35 88.3) (width 0.3) (layer "F.Cu") (net 1))
  (segment (start 90.95 117.35) (end 92.1 117.35) (width 0.2) (layer "F.Cu") (net 1))
  (segment (start 83.3 103.2) (end 82.4 103.2) (width 0.155) (layer "F.Cu") (net 1))
  (segment (start 120.2 108.35) (end 119.75 107.9) (width 0.2) (layer "F.Cu") (net 1))
  (segment (start 122.25 112.45) (end 122.25 111.3) (width 0.25) (layer "F.Cu") (net 1))
  (segment (start 85 143.04) (end 85 143.8) (width 0.3) (layer "F.Cu") (net 1))
  (segment (start 126.75 113.75) (end 126.8 113.8) (width 0.3) (layer "F.Cu") (net 1))
  (segment (start 136.715 103) (end 136.715 102.215) (width 0.15) (layer "F.Cu") (net 1))
  (segment (start 112.25 88.589998) (end 112.060002 88.4) (width 0.3) (layer "F.Cu") (net 1))
  (segment (start 145.45 147.55) (end 145.7 147.8) (width 0.23) (layer "F.Cu") (net 1))
  (segment (start 93.25 112.45) (end 93.25 111.25) (width 0.25) (layer "F.Cu") (net 1))
  (segment (start 123.75 111.4) (end 123.3 110.95) (width 0.25) (layer "F.Cu") (net 1))
  (segment (start 100.75 118.55) (end 100.75 117.35) (width 0.3) (layer "F.Cu") (net 1))
  (segment (start 92.25 117.5) (end 92.25 118.55) (width 0.2) (layer "F.Cu") (net 1))
  (segment (start 119.25 83.45) (end 119.25 84.95) (width 0.3) (layer "F.Cu") (net 1))
  (segment (start 105.960002 88.3) (end 105.75 88.3) (width 0.3) (layer "F.Cu") (net 1))
  (segment (start 118.515 108.8) (end 119.415 107.9) (width 0.2) (layer "F.Cu") (net 1))
  (segment (start 122.25 83.45) (end 122.25 84.495911) (width 0.3) (layer "F.Cu") (net 1))
  (segment (start 112.55 93.25) (end 112.05 92.75) (width 0.2) (layer "F.Cu") (net 1))
  (segment (start 84.75 144.74) (end 83.83 144.74) (width 0.3) (layer "F.Cu") (net 1))
  (segment (start 140.985 143.115) (end 140.6 143.5) (width 0.2) (layer "F.Cu") (net 1))
  (segment (start 80.385 125.9) (end 81.05 125.9) (width 0.125) (layer "F.Cu") (net 1))
  (segment (start 112.25 89.55) (end 112.25 88.589998) (width 0.3) (layer "F.Cu") (net 1))
  (segment (start 151.93 113.9) (end 152.5 113.9) (width 0.3) (layer "F.Cu") (net 1))
  (segment (start 83.2 141.8) (end 83.9 141.8) (width 0.4) (layer "F.Cu") (net 1))
  (segment (start 129.75 89.55) (end 129.75 91.1) (width 0.23) (layer "F.Cu") (net 1))
  (segment (start 113.96 90.7) (end 113.75 90.49) (width 0.3) (layer "F.Cu") (net 1))
  (segment (start 91.485 135) (end 91.485 135.785) (width 0.15) (layer "F.Cu") (net 1))
  (segment (start 98.75 144.74) (end 97.83 144.74) (width 0.3) (layer "F.Cu") (net 1))
  (segment (start 134.753164 129.062953) (end 134.012953 129.062953) (width 0.2) (layer "F.Cu") (net 1))
  (segment (start 110.25 89.55) (end 110.25 90.510002) (width 0.3) (layer "F.Cu") (net 1))
  (segment (start 120.75 83.45) (end 120.75 86.858905) (width 0.3) (layer "F.Cu") (net 1))
  (segment (start 133.215 130.05) (end 132.45 130.05) (width 0.25) (layer "F.Cu") (net 1))
  (segment (start 92.1 117.35) (end 92.25 117.5) (width 0.2) (layer "F.Cu") (net 1))
  (segment (start 96.7 121.8) (end 96.7 121.285) (width 0.2) (layer "F.Cu") (net 1))
  (segment (start 90.20499 121.63999) (end 90.75 122.185) (width 0.2) (layer "F.Cu") (net 1))
  (segment (start 93.75 118.55) (end 93.75 120.1) (width 0.3) (layer "F.Cu") (net 1))
  (segment (start 98.75 144.124307) (end 98.75 144.74) (width 0.3) (layer "F.Cu") (net 1))
  (segment (start 145.2 115.85) (end 145.2 115.112) (width 0.125) (layer "F.Cu") (net 1))
  (segment (start 83.9 141.8) (end 85.34 140.36) (width 0.4) (layer "F.Cu") (net 1))
  (segment (start 128.25 113.604599) (end 128.257901 113.6125) (width 0.25) (layer "F.Cu") (net 1))
  (segment (start 118.46 144.95) (end 118.25 144.74) (width 0.3) (layer "F.Cu") (net 1))
  (segment (start 103.25 88.589998) (end 102.960002 88.3) (width 0.3) (layer "F.Cu") (net 1))
  (segment (start 109.74 94.05) (end 109.05 93.36) (width 0.2) (layer "F.Cu") (net 1))
  (segment (start 110.060002 90.7) (end 109.25 90.7) (width 0.3) (layer "F.Cu") (net 1))
  (segment (start 151.7 104.7) (end 151.6 104.6) (width 0.155) (layer "F.Cu") (net 1))
  (segment (start 116.25 85.6) (end 116.2 85.65) (width 0.3) (layer "F.Cu") (net 1))
  (segment (start 131.25 83.45) (end 131.25 84.584574) (width 0.2) (layer "F.Cu") (net 1))
  (segment (start 112.365 109.4) (end 111.4 109.4) (width 0.2) (layer "F.Cu") (net 1))
  (segment (start 95.2 141.6) (end 95.6 141.2) (width 0.2) (layer "F.Cu") (net 1))
  (segment (start 152.9 95.9) (end 152.18 95.9) (width 0.3) (layer "F.Cu") (net 1))
  (segment (start 133.1 121.315) (end 133.1 121.9) (width 0.18) (layer "F.Cu") (net 1))
  (segment (start 77.435 127.55) (end 77.435 127.242108) (width 0.15) (layer "F.Cu") (net 1))
  (segment (start 129.75 118.55) (end 129.75 119.75) (width 0.25) (layer "F.Cu") (net 1))
  (segment (start 108.05 88.3) (end 107.25 88.3) (width 0.3) (layer "F.Cu") (net 1))
  (segment (start 148.2 111.55) (end 148.2 109.72) (width 0.125) (layer "F.Cu") (net 1))
  (segment (start 106.25 89.55) (end 106.25 88.589998) (width 0.3) (layer "F.Cu") (net 1))
  (segment (start 96.9 103.5) (end 96.205286 103.5) (width 0.25) (layer "F.Cu") (net 1))
  (segment (start 108.25 112.45) (end 108.25 111.25) (width 0.25) (layer "F.Cu") (net 1))
  (segment (start 86.8 140.36) (end 85.34 140.36) (width 0.4) (layer "F.Cu") (net 1))
  (segment (start 113.505 94.05) (end 113.27 94.05) (width 0.2) (layer "F.Cu") (net 1))
  (segment (start 118.5 143.5) (end 118.5 143.04) (width 0.3) (layer "F.Cu") (net 1))
  (segment (start 108.25 88.5) (end 108.05 88.3) (width 0.3) (layer "F.Cu") (net 1))
  (segment (start 89.82 139.4) (end 89.82 139.98) (width 0.2) (layer "F.Cu") (net 1))
  (segment (start 90.25 144.74) (end 91.67 144.74) (width 0.3) (layer "F.Cu") (net 1))
  (segment (start 104.75 89.55) (end 104.75 88.589998) (width 0.3) (layer "F.Cu") (net 1))
  (segment (start 152.6 107.95) (end 151.93 107.95) (width 0.3) (layer "F.Cu") (net 1))
  (segment (start 133.915 120.5) (end 133.1 121.315) (width 0.18) (layer "F.Cu") (net 1))
  (segment (start 104.5 143.51) (end 104.25 143.76) (width 0.3) (layer "F.Cu") (net 1))
  (segment (start 124.25 90.75) (end 124.25 89.55) (width 0.23) (layer "F.Cu") (net 1))
  (segment (start 104.25 143.76) (end 104.25 144.74) (width 0.3) (layer "F.Cu") (net 1))
  (segment (start 117.4 85.7) (end 118.5 85.7) (width 0.3) (layer "F.Cu") (net 1))
  (segment (start 102.25 112.45) (end 102.25 111.25) (width 0.25) (layer "F.Cu") (net 1))
  (segment (start 119.415 107.9) (end 119.75 107.9) (width 0.2) (layer "F.Cu") (net 1))
  (segment (start 116.25 83.45) (end 116.25 85.6) (width 0.3) (layer "F.Cu") (net 1))
  (segment (start 71.05 109.865) (end 71.05 109.2) (width 0.2) (layer "F.Cu") (net 1))
  (segment (start 84.9 131.915) (end 85.715 131.915) (width 0.2) (layer "F.Cu") (net 1))
  (segment (start 95.75 85.65) (end 95.8 85.7) (width 0.23) (layer "F.Cu") (net 1))
  (segment (start 118.25 143.75) (end 118.5 143.5) (width 0.3) (layer "F.Cu") (net 1))
  (segment (start 122.13749 85.595698) (end 122.191792 85.65) (width 0.3) (layer "F.Cu") (net 1))
  (segment (start 101.6 88.3) (end 101.35 88.3) (width 0.3) (layer "F.Cu") (net 1))
  (segment (start 134.25 83.45) (end 134.95 83.45) (width 0.23) (layer "F.Cu") (net 1))
  (segment (start 126.75 119.85) (end 126.4 120.2) (width 0.25) (layer "F.Cu") (net 1))
  (segment (start 115.35 138.3125) (end 115.35 137.875) (width 0.2) (layer "F.Cu") (net 1))
  (segment (start 91.38 138.4) (end 91.95 138.4) (width 0.3) (layer "F.Cu") (net 1))
  (segment (start 90.20499 120.9132) (end 90.20499 121.63999) (width 0.2) (layer "F.Cu") (net 1))
  (segment (start 149.285 125.75) (end 149.285 123.715) (width 0.25) (layer "F.Cu") (net 1))
  (segment (start 117.4 85) (end 117.75 84.65) (width 0.3) (layer "F.Cu") (net 1))
  (segment (start 125.249999 84.810499) (end 125.112499 84.947999) (width 0.2) (layer "F.Cu") (net 1))
  (segment (start 133.903164 124.512952) (end 132.903164 124.512952) (width 0.25) (layer "F.Cu") (net 1))
  (segment (start 111.25 85.6) (end 111.2 85.65) (width 0.3) (layer "F.Cu") (net 1))
  (segment (start 96 102.6) (end 96.05 102.65) (width 0.25) (layer "F.Cu") (net 1))
  (segment (start 111.55 93.25) (end 112.05 92.75) (width 0.2) (layer "F.Cu") (net 1))
  (segment (start 109.25 89.55) (end 109.25 90.7) (width 0.23) (layer "F.Cu") (net 1))
  (segment (start 99 143.04) (end 99 143.874307) (width 0.3) (layer "F.Cu") (net 1))
  (segment (start 132.75 89.55) (end 132.75 91.05) (width 0.23) (layer "F.Cu") (net 1))
  (segment (start 136.15 139.285) (end 135.465 139.285) (width 0.2) (layer "F.Cu") (net 1))
  (segment (start 110.005 94.05) (end 109.74 94.05) (width 0.2) (layer "F.Cu") (net 1))
  (segment (start 97.025 102.675) (end 97 102.7) (width 0.25) (layer "F.Cu") (net 1))
  (segment (start 143.65 144.05) (end 143.6 144) (width 0.125) (layer "F.Cu") (net 1))
  (segment (start 80.385 123.9) (end 81.05 123.9) (width 0.125) (layer "F.Cu") (net 1))
  (segment (start 111.62 144.95) (end 112.54 144.95) (width 0.3) (layer "F.Cu") (net 1))
  (segment (start 132.75 83.45) (end 132.75 84.517852) (width 0.23) (layer "F.Cu") (net 1))
  (segment (start 73.4 128.7) (end 73.4 127.2) (width 0.2) (layer "F.Cu") (net 1))
  (segment (start 133.888164 128.938164) (end 134 129.05) (width 0.15) (layer "F.Cu") (net 1))
  (segment (start 146.15 113.54) (end 145.2 114.49) (width 0.125) (layer "F.Cu") (net 1))
  (segment (start 115.05 94.285) (end 116.285 94.285) (width 0.2) (layer "F.Cu") (net 1))
  (segment (start 95.8 87.15) (end 95.8 85.7) (width 0.23) (layer "F.Cu") (net 1))
  (segment (start 108.9 138.1) (end 108.8 138.2) (width 0.2) (layer "F.Cu") (net 1))
  (segment (start 123.75 118.55) (end 123.75 119.75) (width 0.25) (layer "F.Cu") (net 1))
  (segment (start 90.75 118.55) (end 90.75 120.36819) (width 0.2) (layer "F.Cu") (net 1))
  (segment (start 115.235 109.4) (end 115.9 109.4) (width 0.2) (layer "F.Cu") (net 1))
  (segment (start 80.385 121.9) (end 81.05 121.9) (width 0.125) (layer "F.Cu") (net 1))
  (segment (start 106.25 88.589998) (end 105.960002 88.3) (width 0.3) (layer "F.Cu") (net 1))
  (segment (start 123.8 84.9) (end 123.75 84.619707) (width 0.2) (layer "F.Cu") (net 1))
  (segment (start 147.238164 129.512952) (end 147.238164 130.423164) (width 0.125) (layer "F.Cu") (net 1))
  (segment (start 132.763001 84.530853) (end 132.763001 84.648067) (width 0.23) (layer "F.Cu") (net 1))
  (segment (start 118.25 144.74) (end 118.25 143.75) (width 0.3) (layer "F.Cu") (net 1))
  (segment (start 86.8 134.345) (end 86.8 136.025) (width 0.25) (layer "F.Cu") (net 1))
  (segment (start 71.115 116.3) (end 71.115 115.3) (width 0.2) (layer "F.Cu") (net 1))
  (segment (start 116.75 89.55) (end 116.75 90.7) (width 0.25) (layer "F.Cu") (net 1))
  (segment (start 135.465 139.285) (end 135.45 139.3) (width 0.2) (layer "F.Cu") (net 1))
  (segment (start 129.750001 84.553551) (end 129.737499 84.566053) (width 0.2) (layer "F.Cu") (net 1))
  (segment (start 89.82 139.98) (end 89.44 140.36) (width 0.2) (layer "F.Cu") (net 1))
  (segment (start 105.039998 88.3) (end 105.75 88.3) (width 0.3) (layer "F.Cu") (net 1))
  (segment (start 114.75 83.45) (end 114.75 85.65) (width 0.3) (layer "F.Cu") (net 1))
  (segment (start 120.75 86.858905) (end 120.791094 86.899999) (width 0.3) (layer "F.Cu") (net 1))
  (segment (start 151.5 104.7) (end 151.6 104.6) (width 0.155) (layer "F.Cu") (net 1))
  (segment (start 92.25 118.55) (end 92.25 120.05) (width 0.2) (layer "F.Cu") (net 1))
  (segment (start 95.2 141.975) (end 95.2 141.6) (width 0.2) (layer "F.Cu") (net 1))
  (segment (start 145.2 114.49) (end 145.2 115.85) (width 0.125) (layer "F.Cu") (net 1))
  (segment (start 92.757933 105.432933) (end 92.75 105.425) (width 0.23) (layer "F.Cu") (net 1))
  (segment (start 106.75 112.45) (end 106.75 111.25) (width 0.25) (layer "F.Cu") (net 1))
  (segment (start 126.749999 83.45) (end 126.749999 84.547351) (width 0.2) (layer "F.Cu") (net 1))
  (segment (start 144.25 149.25) (end 144.3 149.3) (width 0.23) (layer "F.Cu") (net 1))
  (segment (start 90.25 144.74) (end 90.25 143.75) (width 0.3) (layer "F.Cu") (net 1))
  (segment (start 95.4 85.7) (end 95.8 85.7) (width 0.23) (layer "F.Cu") (net 1))
  (segment (start 144.875 84.4) (end 146 84.4) (width 0.2) (layer "F.Cu") (net 1))
  (segment (start 95.25 87.7) (end 95.8 87.15) (width 0.23) (layer "F.Cu") (net 1))
  (segment (start 98.515 103.8) (end 97.2 103.8) (width 0.25) (layer "F.Cu") (net 1))
  (segment (start 115.35 137.875) (end 115.175 137.7) (width 0.2) (layer "F.Cu") (net 1))
  (segment (start 128.249999 119.75) (end 128.25 119.612499) (width 0.25) (layer "F.Cu") (net 1))
  (segment (start 111.25 89.55) (end 111.25 88.4) (width 0.3) (layer "F.Cu") (net 1))
  (segment (start 149.95 104.7) (end 151.5 104.7) (width 0.155) (layer "F.Cu") (net 1))
  (segment (start 136.715 102.215) (end 136.7 102.2) (width 0.15) (layer "F.Cu") (net 1))
  (segment (start 147.238164 130.423164) (end 147.715 130.9) (width 0.125) (layer "F.Cu") (net 1))
  (segment (start 119.25 117.45) (end 119.5 117.2) (width 0.3) (layer "F.Cu") (net 1))
  (segment (start 148.2 115.85) (end 148.2 114.34) (width 0.125) (layer "F.Cu") (net 1))
  (segment (start 103.75 118.55) (end 103.75 117.35) (width 0.3) (layer "F.Cu") (net 1))
  (segment (start 90.5 143.04) (end 90.5 143.5) (width 0.3) (layer "F.Cu") (net 1))
  (segment (start 127.07 143.89) (end 127 143.82) (width 0.2) (layer "F.Cu") (net 1))
  (segment (start 149.3 123.7) (end 149.3 123.4) (width 0.25) (layer "F.Cu") (net 1))
  (segment (start 132.75 83.449998) (end 132.75 84.517852) (width 0.125) (layer "F.Cu") (net 1))
  (segment (start 99 143.874307) (end 98.75 144.124307) (width 0.3) (layer "F.Cu") (net 1))
  (segment (start 125.249999 83.45) (end 125.249999 84.810499) (width 0.2) (layer "F.Cu") (net 1))
  (segment (start 117.75 83.45) (end 117.75 84.65) (width 0.3) (layer "F.Cu") (net 1))
  (segment (start 96.205286 103.5) (end 96.004764 103.700522) (width 0.25) (layer "F.Cu") (net 1))
  (segment (start 145.7 147.8) (end 146.1 147.8) (width 0.23) (layer "F.Cu") (net 1))
  (segment (start 154.05 92.7) (end 153 92.7) (width 0.155) (layer "F.Cu") (net 1))
  (segment (start 119.88 144.95) (end 118.46 144.95) (width 0.3) (layer "F.Cu") (net 1))
  (segment (start 142.981747 147.633823) (end 143.05 147.56557) (width 0.23) (layer "F.Cu") (net 1))
  (segment (start 97.15 102.55) (end 98.1 102.55) (width 0.25) (layer "F.Cu") (net 1))
  (segment (start 114.75 85.65) (end 114.7 85.7) (width 0.3) (layer "F.Cu") (net 1))
  (segment (start 117.4 85.7) (end 117.4 85) (width 0.3) (layer "F.Cu") (net 1))
  (segment (start 95.75 83.45) (end 95.75 85.65) (width 0.23) (layer "F.Cu") (net 1))
  (segment (start 71.115 115.3) (end 71.115 114.615) (width 0.2) (layer "F.Cu") (net 1))
  (segment (start 154.05 104.7) (end 151.7 104.7) (width 0.155) (layer "F.Cu") (net 1))
  (segment (start 149.038164 125.996836) (end 149.285 125.75) (width 0.125) (layer "F.Cu") (net 1))
  (segment (start 89.44 140.36) (end 88.8 140.36) (width 0.2) (layer "F.Cu") (net 1))
  (segment (start 141.7 143.115) (end 140.985 143.115) (width 0.2) (layer "F.Cu") (net 1))
  (segment (start 106.75 118.55) (end 106.75 117.3525) (width 0.25) (layer "F.Cu") (net 1))
  (segment (start 127 143.82) (end 127 143.04) (width 0.2) (layer "F.Cu") (net 1))
  (segment (start 120.6 108.35) (end 120.2 108.35) (width 0.2) (layer "F.Cu") (net 1))
  (segment (start 103.75 112.45) (end 103.75 111.25) (width 0.25) (layer "F.Cu") (net 1))
  (segment (start 101.75 88.45) (end 101.6 88.3) (width 0.3) (layer "F.Cu") (net 1))
  (segment (start 147.715 131.685) (end 147.7 131.7) (width 0.125) (layer "F.Cu") (net 1))
  (segment (start 154.05 98.7) (end 153.1 98.7) (width 0.155) (layer "F.Cu") (net 1))
  (segment (start 109.05 90.9) (end 109.05 93.315) (width 0.3) (layer "F.Cu") (net 1))
  (segment (start 109.25 90.7) (end 109.05 90.9) (width 0.3) (layer "F.Cu") (net 1))
  (segment (start 119.75 90.683999) (end 119.733999 90.7) (width 0.23) (layer "F.Cu") (net 1))
  (segment (start 128.250001 83.45) (end 128.250001 84.558104) (width 0.2) (layer "F.Cu") (net 1))
  (segment (start 83.6 104.8) (end 83.6 103.8) (width 0.155) (layer "F.Cu") (net 1))
  (segment (start 145.2 111.55) (end 148.2 111.55) (width 0.125) (layer "F.Cu") (net 1))
  (segment (start 75.25 124.4) (end 74.75 123.4) (width 0.2) (layer "F.Cu") (net 1))
  (segment (start 148.2 109.72) (end 148.29 109.63) (width 0.125) (layer "F.Cu") (net 1))
  (segment (start 82.915 134.635) (end 82.9 134.65) (width 0.2) (layer "F.Cu") (net 1))
  (segment (start 144.85 145.525) (end 144.85 143.45) (width 0.2) (layer "F.Cu") (net 1))
  (segment (start 129.750001 83.45) (end 129.750001 84.553551) (width 0.2) (layer "F.Cu") (net 1))
  (segment (start 148.285 144) (end 148.95 144) (width 0.25) (layer "F.Cu") (net 1))
  (segment (start 111.25 83.45) (end 111.25 85.6) (width 0.3) (layer "F.Cu") (net 1))
  (segment (start 132.45 130.05) (end 132.4 130.1) (width 0.25) (layer "F.Cu") (net 1))
  (segment (start 123.285 108.8) (end 123.95 108.8) (width 0.2) (layer "F.Cu") (net 1))
  (segment (start 114.05 106.85) (end 114.2 106.7) (width 0.2) (layer "F.Cu") (net 1))
  (segment (start 128.25 89.55) (end 128.25 91.1) (width 0.23) (layer "F.Cu") (net 1))
  (segment (start 105.25 117.4025) (end 105.2475 117.4) (width 0.3) (layer "F.Cu") (net 1))
  (segment (start 94.7 146.285) (end 94.7 147.324998) (width 0.2) (layer "F.Cu") (net 1))
  (segment (start 73.7 129) (end 73.4 128.7) (width 0.2) (layer "F.Cu") (net 1))
  (segment (start 149.3 123.4) (end 148.7 122.8) (width 0.25) (layer "F.Cu") (net 1))
  (segment (start 85.715 131.915) (end 86.10962 132.30962) (width 0.2) (layer "F.Cu") (net 1))
  (segment (start 126.749999 84.547351) (end 126.7375 84.55985) (width 0.2) (layer "F.Cu") (net 1))
  (segment (start 112.54 144.95) (end 112.75 144.74) (width 0.3) (layer "F.Cu") (net 1))
  (segment (start 102.25 118.55) (end 102.25 117.35) (width 0.3) (layer "F.Cu") (net 1))
  (segment (start 116.285 94.285) (end 116.5 94.5) (width 0.2) (layer "F.Cu") (net 1))
  (segment (start 125.112499 84.947999) (end 125.112499 85.452001) (width 0.2) (layer "F.Cu") (net 1))
  (segment (start 132.75 84.517852) (end 132.763001 84.530853) (width 0.23) (layer "F.Cu") (net 1))
  (segment (start 115.25 90.7) (end 113.96 90.7) (width 0.3) (layer "F.Cu") (net 1))
  (segment (start 95.25 89.55) (end 95.25 87.7) (width 0.23) (layer "F.Cu") (net 1))
  (segment (start 75 122.447601) (end 75 124.15) (width 0.2) (layer "F.Cu") (net 1))
  (segment (start 125.25 89.55) (end 125.25 90.75) (width 0.23) (layer "F.Cu") (net 1))
  (segment (start 144.25 146.75) (end 144.25 149.25) (width 0.23) (layer "F.Cu") (net 1))
  (segment (start 128.25 112.45) (end 128.25 113.604599) (width 0.25) (layer "F.Cu") (net 1))
  (segment (start 125.25 112.45) (end 125.25 110.35) (width 0.25) (layer "F.Cu") (net 1))
  (segment (start 95.6 141.2) (end 95.8 141.2) (width 0.2) (layer "F.Cu") (net 1))
  (segment (start 119.75 89.55) (end 119.75 90.683999) (width 0.23) (layer "F.Cu") (net 1))
  (segment (start 134.012953 129.062953) (end 134 129.05) (width 0.2) (layer "F.Cu") (net 1))
  (segment (start 106.75 117.3525) (end 106.7525 117.35) (width 0.25) (layer "F.Cu") (net 1))
  (segment (start 97.025 102.675) (end 97.15 102.55) (width 0.25) (layer "F.Cu") (net 1))
  (segment (start 143.65 145.525) (end 143.65 144.05) (width 0.125) (layer "F.Cu") (net 1))
  (segment (start 110.25 90.510002) (end 110.060002 90.7) (width 0.3) (layer "F.Cu") (net 1))
  (segment (start 128.25 119.612499) (end 128.25 118.55) (width 0.25) (layer "F.Cu") (net 1))
  (segment (start 115.25 89.55) (end 115.25 90.7) (width 0.25) (layer "F.Cu") (net 1))
  (segment (start 71.115 114.615) (end 71.1 114.6) (width 0.2) (layer "F.Cu") (net 1))
  (segment (start 125.25 119.85) (end 125.6 120.2) (width 0.25) (layer "F.Cu") (net 1))
  (segment (start 126.75 112.45) (end 126.75 113.75) (width 0.3) (layer "F.Cu") (net 1))
  (segment (start 132.75 91.05) (end 132.7 91.1) (width 0.23) (layer "F.Cu") (net 1))
  (segment (start 82.4 103.2) (end 81.5 102.3) (width 0.155) (layer "F.Cu") (net 1))
  (segment (start 90.75 118.55) (end 90.75 117.55) (width 0.2) (layer "F.Cu") (net 1))
  (segment (start 125.112499 85.452001) (end 125.491941 85.831443) (width 0.2) (layer "F.Cu") (net 1))
  (segment (start 123.75 84.619707) (end 123.75 83.45) (width 0.2) (layer "F.Cu") (net 1))
  (segment (start 132.9 123.6) (end 132.9 124.516116) (width 0.25) (layer "F.Cu") (net 1))
  (segment (start 113.27 94.05) (end 112.55 93.33) (width 0.2) (layer "F.Cu") (net 1))
  (segment (start 122.13749 84.608421) (end 122.13749 85.595698) (width 0.3) (layer "F.Cu") (net 1))
  (segment (start 149.95 98.7) (end 153.1 98.7) (width 0.155) (layer "F.Cu") (net 1))
  (segment (start 103.25 89.55) (end 103.25 88.589998) (width 0.3) (layer "F.Cu") (net 1))
  (segment (start 90.75 117.55) (end 90.95 117.35) (width 0.2) (layer "F.Cu") (net 1))
  (segment (start 97 102.7) (end 97 101.835) (width 0.25) (layer "F.Cu") (net 1))
  (segment (start 126.75 118.55) (end 126.75 119.85) (width 0.25) (layer "F.Cu") (net 1))
  (segment (start 152.7 101.9) (end 151.91 101.9) (width 0.3) (layer "F.Cu") (net 1))
  (segment (start 84.75 144.74) (end 84.75 144.25) (width 0.3) (layer "F.Cu") (net 1))
  (segment (start 105.25 112.45) (end 105.25 111.25) (width 0.25) (layer "F.Cu") (net 1))
  (segment (start 91.485 135.785) (end 91.503554 135.803554) (width 0.15) (layer "F.Cu") (net 1))
  (segment (start 104.5 143.04) (end 104.5 143.51) (width 0.3) (layer "F.Cu") (net 1))
  (segment (start 122.25 118.55) (end 122.25 119.75) (width 0.25) (layer "F.Cu") (net 1))
  (segment (start 154.05 110.7) (end 151.6 110.7) (width 0.155) (layer "F.Cu") (net 1))
  (segment (start 113.75 90.49) (end 113.75 89.55) (width 0.3) (layer "F.Cu") (net 1))
  (segment (start 126.75 144.21) (end 126.75 144.74) (width 0.2) (layer "F.Cu") (net 1))
  (segment (start 109.5 138.1) (end 108.9 138.1) (width 0.2) (layer "F.Cu") (net 1))
  (segment (start 104.25 144.74) (end 105.67 144.74) (width 0.3) (layer "F.Cu") (net 1))
  (segment (start 131.25 89.55) (end 131.25 91.1) (width 0.23) (layer "F.Cu") (net 1))
  (segment (start 131.25 84.584574) (end 131.248363 84.586211) (width 0.2) (layer "F.Cu") (net 1))
  (segment (start 128.250001 84.558104) (end 128.2625 84.570603) (width 0.2) (layer "F.Cu") (net 1))
  (segment (start 147.715 130.9) (end 147.715 131.685) (width 0.125) (layer "F.Cu") (net 1))
  (segment (start 119.5 117.2) (end 119.8 117.2) (width 0.3) (layer "F.Cu") (net 1))
  (segment (start 149.038164 127.212952) (end 149.038164 125.996836) (width 0.125) (layer "F.Cu") (net 1))
  (segment (start 133.888164 128.112953) (end 133.888164 128.938164) (width 0.15) (layer "F.Cu") (net 1))
  (segment (start 114.05 107.405) (end 114.05 106.85) (width 0.2) (layer "F.Cu") (net 1))
  (segment (start 129.75 112.45) (end 129.75 113.6125) (width 0.25) (layer "F.Cu") (net 1))
  (segment (start 121.25 118.55) (end 121.25 117.35) (width 0.25) (layer "F.Cu") (net 1))
  (segment (start 126.75 89.55) (end 126.75 90.75) (width 0.23) (layer "F.Cu") (net 1))
  (segment (start 127.07 143.89) (end 126.75 144.21) (width 0.2) (layer "F.Cu") (net 1))
  (segment (start 118.25 89.55) (end 118.25 90.675002) (width 0.23) (layer "F.Cu") (net 1))
  (segment (start 96 101.835) (end 96 102.6) (width 0.25) (layer "F.Cu") (net 1))
  (segment (start 148.2 114.34) (end 147.4 113.54) (width 0.125) (layer "F.Cu") (net 1))
  (segment (start 87.3 138.205) (end 87.3 136.525) (width 0.25) (layer "F.Cu") (net 1))
  (segment (start 119.25 84.95) (end 118.5 85.7) (width 0.3) (layer "F.Cu") (net 1))
  (segment (start 144.85 143.45) (end 145 143.3) (width 0.2) (layer "F.Cu") (net 1))
  (segment (start 95.25 85.55) (end 95.4 85.7) (width 0.23) (layer "F.Cu") (net 1))
  (segment (start 125.25 118.55) (end 125.25 119.85) (width 0.25) (layer "F.Cu") (net 1))
  (segment (start 108.25 89.55) (end 108.25 88.5) (width 0.3) (layer "F.Cu") (net 1))
  (segment (start 115.175 137.7) (end 113.7 137.7) (width 0.2) (layer "F.Cu") (net 1))
  (segment (start 101.75 89.55) (end 101.75 88.45) (width 0.3) (layer "F.Cu") (net 1))
  (segment (start 104.75 88.589998) (end 105.039998 88.3) (width 0.3) (layer "F.Cu") (net 1))
  (segment (start 77.435 127.242108) (end 77.039554 126.846662) (width 0.15) (layer "F.Cu") (net 1))
  (segment (start 143.05 147.56557) (end 143.05 146.75) (width 0.23) (layer "F.Cu") (net 1))
  (segment (start 119.25 118.55) (end 119.25 117.45) (width 0.3) (layer "F.Cu") (net 1))
  (segment (start 149.95 92.7) (end 153 92.7) (width 0.155) (layer "F.Cu") (net 1))
  (segment (start 125.491941 85.831443) (end 126.00626 85.831443) (width 0.2) (layer "F.Cu") (net 1))
  (segment (start 112.060002 88.4) (end 111.25 88.4) (width 0.3) (layer "F.Cu") (net 1))
  (segment (start 95.25 83.45) (end 95.25 85.55) (width 0.23) (layer "F.Cu") (net 1))
  (segment (start 145.45 146.75) (end 145.45 147.55) (width 0.23) (layer "F.Cu") (net 1))
  (segment (start 90.75 120.36819) (end 90.20499 120.9132) (width 0.2) (layer "F.Cu") (net 1))
  (segment (start 123.75 112.45) (end 123.75 111.4) (width 0.25) (layer "F.Cu") (net 1))
  (segment (start 105.25 118.55) (end 105.25 117.4025) (width 0.3) (layer "F.Cu") (net 1))
  (segment (start 84.75 144.25) (end 85 144) (width 0.3) (layer "F.Cu") (net 1))
  (segment (start 93.443774 105.432933) (end 92.757933 105.432933) (width 0.23) (layer "F.Cu") (net 1))
  (segment (start 101.75 89.55) (end 101.75 88.55) (width 0.23) (layer "F.Cu") (net 1))
  (segment (start 85 144) (end 85 143.8) (width 0.3) (layer "F.Cu") (net 1))
  (segment (start 134.95 83.45) (end 135 83.4) (width 0.23) (layer "F.Cu") (net 1))
  (segment (start 90.25 143.75) (end 90.5 143.5) (width 0.3) (layer "F.Cu") (net 1))
  (via (at 101.949174 105.057734) (size 0.6) (drill 0.25) (layers "F.Cu" "B.Cu") (net 1))
  (via (at 101.549174 107.557733) (size 0.6) (drill 0.25) (layers "F.Cu" "B.Cu") (net 1))
  (via (at 104.5 139.6) (size 0.6) (drill 0.25) (layers "F.Cu" "B.Cu") (net 1))
  (via (at 116.45 149.95) (size 0.6) (drill 0.25) (layers "F.Cu" "B.Cu") (net 1))
  (via (at 114.55 149.95) (size 0.6) (drill 0.25) (layers "F.Cu" "B.Cu") (net 1))
  (via (at 115.5 149.95) (size 0.6) (drill 0.25) (layers "F.Cu" "B.Cu") (net 1))
  (via (at 107.2 137.4) (size 0.6) (drill 0.25) (layers "F.Cu" "B.Cu") (net 1))
  (via (at 108 137.4) (size 0.6) (drill 0.25) (layers "F.Cu" "B.Cu") (net 1))
  (via (at 108.8 137.4) (size 0.6) (drill 0.25) (layers "F.Cu" "B.Cu") (net 1))
  (via (at 108.8 138.2) (size 0.6) (drill 0.25) (layers "F.Cu" "B.Cu") (net 1))
  (via (at 108 138.2) (size 0.6) (drill 0.25) (layers "F.Cu" "B.Cu") (net 1))
  (via (at 107.2 138.2) (size 0.6) (drill 0.25) (layers "F.Cu" "B.Cu") (net 1))
  (via (at 99 139.6) (size 0.6) (drill 0.25) (layers "F.Cu" "B.Cu") (net 1))
  (via (at 123.3 133.9) (size 0.6) (drill 0.25) (layers "F.Cu" "B.Cu") (net 1))
  (via (at 125 139.2) (size 0.6) (drill 0.25) (layers "F.Cu" "B.Cu") (net 1))
  (via (at 124.2 139.2) (size 0.6) (drill 0.25) (layers "F.Cu" "B.Cu") (net 1))
  (via (at 129 139.8) (size 0.6) (drill 0.25) (layers "F.Cu" "B.Cu") (net 1))
  (via (at 133.4 138.1) (size 0.6) (drill 0.25) (layers "F.Cu" "B.Cu") (net 1))
  (via (at 132.3 143.9) (size 0.6) (drill 0.25) (layers "F.Cu" "B.Cu") (net 1))
  (via (at 128.55 136.25) (size 0.6) (drill 0.25) (layers "F.Cu" "B.Cu") (net 1))
  (via (at 128.55 137) (size 0.6) (drill 0.25) (layers "F.Cu" "B.Cu") (net 1))
  (via (at 127.07 143.89) (size 0.6) (drill 0.25) (layers "F.Cu" "B.Cu") (net 1))
  (via (at 84.75 98.45) (size 0.6) (drill 0.25) (layers "F.Cu" "B.Cu") (net 1))
  (via (at 84.15 98.45) (size 0.6) (drill 0.25) (layers "F.Cu" "B.Cu") (free) (net 1))
  (via (at 107.2 148.55) (size 0.6) (drill 0.25) (layers "F.Cu" "B.Cu") (net 1))
  (via (at 107.8 148.55) (size 0.6) (drill 0.25) (layers "F.Cu" "B.Cu") (net 1))
  (via (at 93.1 138.65) (size 0.6) (drill 0.25) (layers "F.Cu" "B.Cu") (net 1))
  (via (at 82.45 121.55) (size 0.6) (drill 0.25) (layers "F.Cu" "B.Cu") (net 1))
  (via (at 82.45 122.15) (size 0.6) (drill 0.25) (layers "F.Cu" "B.Cu") (net 1))
  (via (at 83.05 121.55) (size 0.6) (drill 0.25) (layers "F.Cu" "B.Cu") (net 1))
  (via (at 81.85 121.55) (size 0.6) (drill 0.25) (layers "F.Cu" "B.Cu") (net 1))
  (via (at 81.85 122.15) (size 0.6) (drill 0.25) (layers "F.Cu" "B.Cu") (net 1))
  (via (at 74.95 118.75) (size 0.6) (drill 0.25) (layers "F.Cu" "B.Cu") (free) (net 1))
  (via (at 74.95 119.35) (size 0.6) (drill 0.25) (layers "F.Cu" "B.Cu") (free) (net 1))
  (via (at 76.15 119.35) (size 0.6) (drill 0.25) (layers "F.Cu" "B.Cu") (free) (net 1))
  (via (at 75.55 119.35) (size 0.6) (drill 0.25) (layers "F.Cu" "B.Cu") (free) (net 1))
  (via (at 79.1 109.2) (size 0.6) (drill 0.25) (layers "F.Cu" "B.Cu") (net 1))
  (via (at 78.5 108.6) (size 0.6) (drill 0.25) (layers "F.Cu" "B.Cu") (net 1))
  (via (at 79.1 108.6) (size 0.6) (drill 0.25) (layers "F.Cu" "B.Cu") (net 1))
  (via (at 78.5 109.2) (size 0.6) (drill 0.25) (layers "F.Cu" "B.Cu") (net 1))
  (via (at 125.5 107.1) (size 0.6) (drill 0.25) (layers "F.Cu" "B.Cu") (net 1))
  (via (at 125.5 107.7) (size 0.6) (drill 0.25) (layers "F.Cu" "B.Cu") (net 1))
  (via (at 124.9 107.1) (size 0.6) (drill 0.25) (layers "F.Cu" "B.Cu") (net 1))
  (via (at 124.9 107.7) (size 0.6) (drill 0.25) (layers "F.Cu" "B.Cu") (net 1))
  (via (at 94.65 130.55) (size 0.6) (drill 0.25) (layers "F.Cu" "B.Cu") (net 1))
  (via (at 83.75 125.6) (size 0.6) (drill 0.25) (layers "F.Cu" "B.Cu") (net 1))
  (via (at 84.35 125.6) (size 0.6) (drill 0.25) (layers "F.Cu" "B.Cu") (net 1))
  (via (at 84.95 125.6) (size 0.6) (drill 0.25) (layers "F.Cu" "B.Cu") (net 1))
  (via (at 83.15 125.6) (size 0.6) (drill 0.25) (layers "F.Cu" "B.Cu") (net 1))
  (via (at 142.2 138.575003) (size 0.6) (drill 0.25) (layers "F.Cu" "B.Cu") (net 1))
  (via (at 138.85 138.575003) (size 0.6) (drill 0.25) (layers "F.Cu" "B.Cu") (net 1))
  (via (at 145.25 138.65) (size 0.6) (drill 0.25) (layers "F.Cu" "B.Cu") (net 1))
  (via (at 148.609028 100.105831) (size 0.6) (drill 0.25) (layers "F.Cu" "B.Cu") (net 1))
  (via (at 151.4 90) (size 0.6) (drill 0.25) (layers "F.Cu" "B.Cu") (net 1))
  (via (at 123.95 108.8) (size 0.6) (drill 0.25) (layers "F.Cu" "B.Cu") (net 1))
  (via (at 119.733999 90.7) (size 0.6) (drill 0.25) (layers "F.Cu" "B.Cu") (net 1))
  (via (at 96.05 102.65) (size 0.6) (drill 0.25) (layers "F.Cu" "B.Cu") (net 1))
  (via (at 77.039554 126.846662) (size 0.6) (drill 0.25) (layers "F.Cu" "B.Cu") (net 1))
  (via (at 119.8 117.2) (size 0.6) (drill 0.25) (layers "F.Cu" "B.Cu") (net 1))
  (via (at 70.5 85.5) (size 0.6) (drill 0.25) (layers "F.Cu" "B.Cu") (net 1))
  (via (at 127.6 126.4) (size 0.6) (drill 0.25) (layers "F.Cu" "B.Cu") (net 1))
  (via (at 84.8 91.3) (size 0.6) (drill 0.25) (layers "F.Cu" "B.Cu") (net 1))
  (via (at 147.7 131.7) (size 0.6) (drill 0.25) (layers "F.Cu" "B.Cu") (net 1))
  (via (at 120.791094 86.899999) (size 0.6) (drill 0.25) (layers "F.Cu" "B.Cu") (net 1))
  (via (at 128.4 125.6) (size 0.6) (drill 0.25) (layers "F.Cu" "B.Cu") (net 1))
  (via (at 83.15 126.2) (size 0.6) (drill 0.25) (layers "F.Cu" "B.Cu") (net 1))
  (via (at 126.8 113.8) (size 0.6) (drill 0.25) (layers "F.Cu" "B.Cu") (net 1))
  (via (at 77.6 99.4) (size 0.6) (drill 0.25) (layers "F.Cu" "B.Cu") (net 1))
  (via (at 136.7 102.2) (size 0.6) (drill 0.25) (layers "F.Cu" "B.Cu") (net 1))
  (via (at 144.3 149.3) (size 0.6) (drill 0.25) (layers "F.Cu" "B.Cu") (net 1))
  (via (at 74 101) (size 0.6) (drill 0.25) (layers "F.Cu" "B.Cu") (net 1))
  (via (at 131.25 91.1) (size 0.6) (drill 0.25) (layers "F.Cu" "B.Cu") (net 1))
  (via (at 152.5 113.9) (size 0.6) (drill 0.25) (layers "F.Cu" "B.Cu") (net 1))
  (via (at 114.7 85.7) (size 0.6) (drill 0.25) (layers "F.Cu" "B.Cu") (net 1))
  (via (at 94.775002 147.4) (size 0.6) (drill 0.25) (layers "F.Cu" "B.Cu") (net 1))
  (via (at 146.1 147.8) (size 0.6) (drill 0.25) (layers "F.Cu" "B.Cu") (net 1))
  (via (at 135.9 134.5) (size 0.6) (drill 0.25) (layers "F.Cu" "B.Cu") (net 1))
  (via (at 135.65 105.95) (size 0.6) (drill 0.25) (layers "F.Cu" "B.Cu") (net 1))
  (via (at 128.249999 119.75) (size 0.6) (drill 0.25) (layers "F.Cu" "B.Cu") (net 1))
  (via (at 80.3 108.6) (size 0.6) (drill 0.25) (layers "F.Cu" "B.Cu") (net 1))
  (via (at 126.75 90.75) (size 0.6) (drill 0.25) (layers "F.Cu" "B.Cu") (net 1))
  (via (at 126.00626 85.831443) (size 0.6) (drill 0.25) (layers "F.Cu" "B.Cu") (net 1))
  (via (at 88.3 142) (size 0.6) (drill 0.25) (layers "F.Cu" "B.Cu") (net 1))
  (via (at 139.4 127.4) (size 0.6) (drill 0.25) (layers "F.Cu" "B.Cu") (net 1))
  (via (at 140.6 143.5) (size 0.6) (drill 0.25) (layers "F.Cu" "B.Cu") (net 1))
  (via (at 133.1 121.9) (size 0.6) (drill 0.25) (layers "F.Cu" "B.Cu") (net 1))
  (via (at 146 84.4) (size 0.6) (drill 0.25) (layers "F.Cu" "B.Cu") (net 1))
  (via (at 93.75 120.1) (size 0.6) (drill 0.25) (layers "F.Cu" "B.Cu") (net 1))
  (via (at 118.9 133.9) (size 0.6) (drill 0.25) (layers "F.Cu" "B.Cu") (net 1))
  (via (at 150.4 135) (size 0.6) (drill 0.25) (layers "F.Cu" "B.Cu") (net 1))
  (via (at 71.05 109.2) (size 0.6) (drill 0.25) (layers "F.Cu" "B.Cu") (net 1))
  (via (at 97.025 102.675) (size 0.6) (drill 0.25) (layers "F.Cu" "B.Cu") (net 1))
  (via (at 108.4 143.8) (size 0.6) (drill 0.25) (layers "F.Cu" "B.Cu") (net 1))
  (via (at 139.145 106.6) (size 0.6) (drill 0.25) (layers "F.Cu" "B.Cu") (net 1))
  (via (at 97.6 114.6) (size 0.6) (drill 0.25) (layers "F.Cu" "B.Cu") (net 1))
  (via (at 128.2625 84.570603) (size 0.6) (drill 0.25) (layers "F.Cu" "B.Cu") (net 1))
  (via (at 151.6 110.7) (size 0.6) (drill 0.25) (layers "F.Cu" "B.Cu") (net 1))
  (via (at 122.25 119.75) (size 0.6) (drill 0.25) (layers "F.Cu" "B.Cu") (net 1))
  (via (at 117.4 85.7) (size 0.6) (drill 0.25) (layers "F.Cu" "B.Cu") (net 1))
  (via (at 78.2 99.8) (size 0.6) (drill 0.25) (layers "F.Cu" "B.Cu") (net 1))
  (via (at 99.8 88.3) (size 0.6) (drill 0.25) (layers "F.Cu" "B.Cu") (net 1))
  (via (at 73.4 99.8) (size 0.6) (drill 0.25) (layers "F.Cu" "B.Cu") (net 1))
  (via (at 90.425 95.8) (size 0.6) (drill 0.25) (layers "F.Cu" "B.Cu") (net 1))
  (via (at 139.65 91.9) (size 0.6) (drill 0.25) (layers "F.Cu" "B.Cu") (net 1))
  (via (at 132.4 130.1) (size 0.6) (drill 0.25) (layers "F.Cu" "B.Cu") (net 1))
  (via (at 139.1 83.6) (size 0.6) (drill 0.25) (layers "F.Cu" "B.Cu") (net 1))
  (via (at 71.1 114.6) (size 0.6) (drill 0.25) (layers "F.Cu" "B.Cu") (net 1))
  (via (at 91.025 94.6) (size 0.6) (drill 0.25) (layers "F.Cu" "B.Cu") (net 1))
  (via (at 74 99.4) (size 0.6) (drill 0.25) (layers "F.Cu" "B.Cu") (net 1))
  (via (at 113.6 104.95) (size 0.6) (drill 0.25) (layers "F.Cu" "B.Cu") (net 1))
  (via (at 102 149.95) (size 0.6) (drill 0.25) (layers "F.Cu" "B.Cu") (net 1))
  (via (at 83.7 90.3) (size 0.6) (drill 0.25) (layers "F.Cu" "B.Cu") (net 1))
  (via (at 99.275 108.05) (size 0.6) (drill 0.25) (layers "F.Cu" "B.Cu") (net 1))
  (via (at 83.05 122.15) (size 0.6) (drill 0.25) (layers "F.Cu" "B.Cu") (net 1))
  (via (at 79.2 115) (size 0.6) (drill 0.25) (layers "F.Cu" "B.Cu") (net 1))
  (via (at 135.45 139.3) (size 0.6) (drill 0.25) (layers "F.Cu" "B.Cu") (net 1))
  (via (at 75.2 99.4) (size 0.6) (drill 0.25) (layers "F.Cu" "B.Cu") (net 1))
  (via (at 153 92.7) (size 0.6) (drill 0.25) (layers "F.Cu" "B.Cu") (net 1))
  (via (at 92.75 105.425) (size 0.6) (drill 0.25) (layers "F.Cu" "B.Cu") (net 1))
  (via (at 127.6 125.6) (size 0.6) (drill 0.25) (layers "F.Cu" "B.Cu") (net 1))
  (via (at 152.1 91.9) (size 0.6) (drill 0.25) (layers "F.Cu" "B.Cu") (net 1))
  (via (at 129.737499 84.566053) (size 0.6) (drill 0.25) (layers "F.Cu" "B.Cu") (net 1))
  (via (at 76.4 99.4) (size 0.6) (drill 0.25) (layers "F.Cu" "B.Cu") (net 1))
  (via (at 152.6 107.95) (size 0.6) (drill 0.25) (layers "F.Cu" "B.Cu") (net 1))
  (via (at 132.763001 84.648067) (size 0.6) (drill 0.25) (layers "F.Cu" "B.Cu") (net 1))
  (via (at 138.4 127.3) (size 0.6) (drill 0.25) (layers "F.Cu" "B.Cu") (net 1))
  (via (at 91.025 95.8) (size 0.6) (drill 0.25) (layers "F.Cu" "B.Cu") (net 1))
  (via (at 78.6 114.4) (size 0.6) (drill 0.25) (layers "F.Cu" "B.Cu") (net 1))
  (via (at 114.8 104.95) (size 0.6) (drill 0.25) (layers "F.Cu" "B.Cu") (net 1))
  (via (at 135 83.4) (size 0.6) (drill 0.25) (layers "F.Cu" "B.Cu") (net 1))
  (via (at 139.145 105.6) (size 0.6) (drill 0.25) (layers "F.Cu" "B.Cu") (net 1))
  (via (at 114.8 105.55) (size 0.6) (drill 0.25) (layers "F.Cu" "B.Cu") (net 1))
  (via (at 122.191792 85.65) (size 0.6) (drill 0.25) (layers "F.Cu" "B.Cu") (net 1))
  (via (at 142.981747 147.633823) (size 0.6) (drill 0.25) (layers "F.Cu" "B.Cu") (net 1))
  (via (at 105.2475 117.4) (size 0.6) (drill 0.25) (layers "F.Cu" "B.Cu") (net 1))
  (via (at 128.4 126.4) (size 0.6) (drill 0.25) (layers "F.Cu" "B.Cu") (net 1))
  (via (at 101 149.95) (size 0.6) (drill 0.25) (layers "F.Cu" "B.Cu") (net 1))
  (via (at 101.35 88.3) (size 0.6) (drill 0.25) (layers "F.Cu" "B.Cu") (net 1))
  (via (at 72.8 101) (size 0.6) (drill 0.25) (layers "F.Cu" "B.Cu") (net 1))
  (via (at 91.025 96.4) (size 0.6) (drill 0.25) (layers "F.Cu" "B.Cu") (net 1))
  (via (at 80.9 108.6) (size 0.6) (drill 0.25) (layers "F.Cu" "B.Cu") (net 1))
  (via (at 102.25 111.25) (size 0.6) (drill 0.25) (layers "F.Cu" "B.Cu") (net 1))
  (via (at 143.2 126.6) (size 0.6) (drill 0.25) (layers "F.Cu" "B.Cu") (net 1))
  (via (at 106.75 111.25) (size 0.6) (drill 0.25) (layers "F.Cu" "B.Cu") (net 1))
  (via (at 79.4 99.8) (size 0.6) (drill 0.25) (layers "F.Cu" "B.Cu") (net 1))
  (via (at 102.75 149.95) (size 0.6) (drill 0.25) (layers "F.Cu" "B.Cu") (net 1))
  (via (at 151.7 125.6) (size 0.6) (drill 0.25) (layers "F.Cu" "B.Cu") (net 1))
  (via (at 151.6 97.1) (size 0.6) (drill 0.25) (layers "F.Cu" "B.Cu") (net 1))
  (via (at 86.25 135.575) (size 0.6) (drill 0.25) (layers "F.Cu" "B.Cu") (net 1))
  (via (at 151.8 128.6) (size 0.6) (drill 0.25) (layers "F.Cu" "B.Cu") (net 1))
  (via (at 94.9 110.225) (size 0.6) (drill 0.25) (layers "F.Cu" "B.Cu") (net 1))
  (via (at 111.4 109.4) (size 0.6) (drill 0.25) (layers "F.Cu" "B.Cu") (net 1))
  (via (at 75 113.5) (size 0.6) (drill 0.25) (layers "F.Cu" "B.Cu") (free) (net 1))
  (via (at 116.75 90.7) (size 0.6) (drill 0.25) (layers "F.Cu" "B.Cu") (net 1))
  (via (at 78.8 99.4) (size 0.6) (drill 0.25) (layers "F.Cu" "B.Cu") (net 1))
  (via (at 151.6 106.1) (size 0.6) (drill 0.25) (layers "F.Cu" "B.Cu") (net 1))
  (via (at 84.35 126.2) (size 0.6) (drill 0.25) (layers "F.Cu" "B.Cu") (net 1))
  (via (at 148.7 122.8) (size 0.6) (drill 0.25) (layers "F.Cu" "B.Cu") (net 1))
  (via (at 84.75 97.85) (size 0.6) (drill 0.25) (layers "F.Cu" "B.Cu") (net 1))
  (via (at 85.95 120) (size 0.6) (drill 0.25) (layers "F.Cu" "B.Cu") (net 1))
  (via (at 87.2 142) (size 0.6) (drill 0.25) (layers "F.Cu" "B.Cu") (net 1))
  (via (at 103.75 117.35) (size 0.6) (drill 0.25) (layers "F.Cu" "B.Cu") (net 1))
  (via (at 145.2 115.112) (size 0.6) (drill 0.25) (layers "F.Cu" "B.Cu") (net 1))
  (via (at 96.7 121.8) (size 0.6) (drill 0.25) (layers "F.Cu" "B.Cu") (net 1))
  (via (at 129.75 113.6125) (size 0.6) (drill 0.25) (layers "F.Cu" "B.Cu") (net 1))
  (via (at 143.6 144) (size 0.6) (drill 0.25) (layers "F.Cu" "B.Cu") (net 1))
  (via (at 153.1 98.7) (size 0.6) (drill 0.25) (layers "F.Cu" "B.Cu") (net 1))
  (via (at 83.75 126.2) (size 0.6) (drill 0.25) (layers "F.Cu" "B.Cu") (net 1))
  (via (at 151.6 104.6) (size 0.6) (drill 0.25) (layers "F.Cu" "B.Cu") (net 1))
  (via (at 126.7375 84.55985) (size 0.6) (drill 0.25) (layers "F.Cu" "B.Cu") (net 1))
  (via (at 112.05 92.75) (size 0.6) (drill 0.25) (layers "F.Cu" "B.Cu") (net 1))
  (via (at 128.25 91.1) (size 0.6) (drill 0.25) (layers "F.Cu" "B.Cu") (net 1))
  (via (at 90.425 94.6) (size 0.6) (drill 0.25) (layers "F.Cu" "B.Cu") (net 1))
  (via (at 113.6 105.55) (size 0.6) (drill 0.25) (layers "F.Cu" "B.Cu") (net 1))
  (via (at 151.6 103.1) (size 0.6) (drill 0.25) (layers "F.Cu" "B.Cu") (net 1))
  (via (at 151.6 109.6) (size 0.6) (drill 0.25) (layers "F.Cu" "B.Cu") (net 1))
  (via (at 75.8 99.8) (size 0.6) (drill 0.25) (layers "F.Cu" "B.Cu") (net 1))
  (via (at 78.6 115) (size 0.6) (drill 0.25) (layers "F.Cu" "B.Cu") (net 1))
  (via (at 125.2 121) (size 0.6) (drill 0.25) (layers "F.Cu" "B.Cu") (free) (net 1))
  (via (at 86.10962 132.30962) (size 0.6) (drill 0.25) (layers "F.Cu" "B.Cu") (net 1))
  (via (at 116.2 85.65) (size 0.6) (drill 0.25) (layers "F.Cu" "B.Cu") (net 1))
  (via (at 71.2 100.4) (size 0.6) (drill 0.25) (layers "F.Cu" "B.Cu") (net 1))
  (via (at 151.8 116.6) (size 0.6) (drill 0.25) (layers "F.Cu" "B.Cu") (net 1))
  (via (at 100.75 117.35) (size 0.6) (drill 0.25) (layers "F.Cu" "B.Cu") (net 1))
  (via (at 82.9 134.65) (size 0.6) (drill 0.25) (layers "F.Cu" "B.Cu") (net 1))
  (via (at 91.503554 135.803554) (size 0.6) (drill 0.25) (layers "F.Cu" "B.Cu") (net 1))
  (via (at 128.257901 113.6125) (size 0.6) (drill 0.25) (layers "F.Cu" "B.Cu") (net 1))
  (via (at 86.9 135.575) (size 0.6) (drill 0.25) (layers "F.Cu" "B.Cu") (net 1))
  (via (at 86.9 136.2) (size 0.6) (drill 0.25) (layers "F.Cu" "B.Cu") (net 1))
  (via (at 107.25 88.3) (size 0.6) (drill 0.25) (layers "F.Cu" "B.Cu") (net 1))
  (via (at 135.6 100.007495) (size 0.6) (drill 0.25) (layers "F.Cu" "B.Cu") (net 1))
  (via (at 75.6 113.5) (size 0.6) (drill 0.25) (layers "F.Cu" "B.Cu") (net 1))
  (via (at 77 99.8) (size 0.6) (drill 0.25) (layers "F.Cu" "B.Cu") (net 1))
  (via (at 151.5 91.9) (size 0.6) (drill 0.25) (layers "F.Cu" "B.Cu") (net 1))
  (via (at 72.8 99.4) (size 0.6) (drill 0.25) (layers "F.Cu" "B.Cu") (net 1))
  (via (at 73.4 100.6) (size 0.6) (drill 0.25) (layers "F.Cu" "B.Cu") (net 1))
  (via (at 132.35 103.3) (size 0.6) (drill 0.25) (layers "F.Cu" "B.Cu") (net 1))
  (via (at 74 100.2) (size 0.6) (drill 0.25) (layers "F.Cu" "B.Cu") (net 1))
  (via (at 81.05 123.9) (size 0.6) (drill 0.25) (layers "F.Cu" "B.Cu") (net 1))
  (via (at 72.8 100.2) (size 0.6) (drill 0.25) (layers "F.Cu" "B.Cu") (net 1))
  (via (at 96.9 104.2) (size 0.6) (drill 0.25) (layers "F.Cu" "B.Cu") (net 1))
  (via (at 91.025 95.2) (size 0.6) (drill 0.25) (layers "F.Cu" "B.Cu") (net 1))
  (via (at 114.2 104.95) (size 0.6) (drill 0.25) (layers "F.Cu" "B.Cu") (net 1))
  (via (at 84.2 91.3) (size 0.6) (drill 0.25) (layers "F.Cu" "B.Cu") (net 1))
  (via (at 114.2 106.7) (size 0.6) (drill 0.25) (layers "F.Cu" "B.Cu") (net 1))
  (via (at 102.25 117.35) (size 0.6) (drill 0.25) (layers "F.Cu" "B.Cu") (net 1))
  (via (at 109.25 90.7) (size 0.6) (drill 0.25) (layers "F.Cu" "B.Cu") (net 1))
  (via (at 106.7525 117.35) (size 0.6) (drill 0.25) (layers "F.Cu" "B.Cu") (net 1))
  (via (at 94.6 107.8) (size 0.6) (drill 0.25) (layers "F.Cu" "B.Cu") (net 1))
  (via (at 126.4 120.2) (size 0.6) (drill 0.25) (layers "F.Cu" "B.Cu") (net 1))
  (via (at 79.85 148.05) (size 0.6) (drill 0.25) (layers "F.Cu" "B.Cu") (net 1))
  (via (at 87.75 141.55) (size 0.6) (drill 0.25) (layers "F.Cu" "B.Cu") (net 1))
  (via (at 148.609032 98.594167) (size 0.6) (drill 0.25) (layers "F.Cu" "B.Cu") (net 1))
  (via (at 146 83) (size 0.6) (drill 0.25) (layers "F.Cu" "B.Cu") (net 1))
  (via (at 138.7 134.5) (size 0.6) (drill 0.25) (layers "F.Cu" "B.Cu") (net 1))
  (via (at 119.75 107.9) (size 0.6) (drill 0.25) (layers "F.Cu" "B.Cu") (net 1))
  (via (at 120.7 123.1) (size 0.6) (drill 0.25) (layers "F.Cu" "B.Cu") (net 1))
  (via (at 96.85 148.25) (size 0.6) (drill 0.25) (layers "F.Cu" "B.Cu") (net 1))
  (via (at 84.3 89.1) (size 0.6) (drill 0.25) (layers "F.Cu" "B.Cu") (net 1))
  (via (at 90.425 95.2) (size 0.6) (drill 0.25) (layers "F.Cu" "B.Cu") (net 1))
  (via (at 90.425 96.4) (size 0.6) (drill 0.25) (layers "F.Cu" "B.Cu") (net 1))
  (via (at 148.95 144) (size 0.6) (drill 0.25) (layers "F.Cu" "B.Cu") (net 1))
  (via (at 95.8 85.7) (size 0.6) (drill 0.25) (layers "F.Cu" "B.Cu") (net 1))
  (via (at 151.5 91.3) (size 0.6) (drill 0.25) (layers "F.Cu" "B.Cu") (net 1))
  (via (at 143.2 122.9) (size 0.6) (drill 0.25) (layers "F.Cu" "B.Cu") (net 1))
  (via (at 115.25 90.7) (size 0.6) (drill 0.25) (layers "F.Cu" "B.Cu") (net 1))
  (via (at 132.7 91.1) (size 0.6) (drill 0.25) (layers "F.Cu" "B.Cu") (net 1))
  (via (at 115.9 109.4) (size 0.6) (drill 0.25) (layers "F.Cu" "B.Cu") (net 1))
  (via (at 124.25 90.75) (size 0.6) (drill 0.25) (layers "F.Cu" "B.Cu") (net 1))
  (via (at 154 143.5) (size 0.6) (drill 0.25) (layers "F.Cu" "B.Cu") (net 1))
  (via (at 114.2 105.55) (size 0.6) (drill 0.25) (layers "F.Cu" "B.Cu") (net 1))
  (via (at 80.05 140.4) (size 0.6) (drill 0.25) (layers "F.Cu" "B.Cu") (net 1))
  (via (at 111.25 88.4) (size 0.6) (drill 0.25) (layers "F.Cu" "B.Cu") (net 1))
  (via (at 124.45 92.5) (size 0.6) (drill 0.25) (layers "F.Cu" "B.Cu") (net 1))
  (via (at 152.1 91.3) (size 0.6) (drill 0.25) (layers "F.Cu" "B.Cu") (net 1))
  (via (at 149.965099 120.331308) (size 0.6) (drill 0.25) (layers "F.Cu" "B.Cu") (net 1))
  (via (at 83.6 104.8) (size 0.6) (drill 0.25) (layers "F.Cu" "B.Cu") (net 1))
  (via (at 86.25 136.2) (size 0.6) (drill 0.25) (layers "F.Cu" "B.Cu") (net 1))
  (via (at 123.75 119.75) (size 0.6) (drill 0.25) (layers "F.Cu" "B.Cu") (net 1))
  (via (at 131.248363 84.586211) (size 0.6) (drill 0.25) (layers "F.Cu" "B.Cu") (net 1))
  (via (at 109 143.8) (size 0.6) (drill 0.25) (layers "F.Cu" "B.Cu") (net 1))
  (via (at 83.1 82.8) (size 0.6) (drill 0.25) (layers "F.Cu" "B.Cu") (net 1))
  (via (at 105.25 111.25) (size 0.6) (drill 0.25) (layers "F.Cu" "B.Cu") (net 1))
  (via (at 92.4 101.5) (size 0.6) (drill 0.25) (layers "F.Cu" "B.Cu") (net 1))
  (via (at 120.8 129.39999) (size 0.6) (drill 0.25) (layers "F.Cu" "B.Cu") (net 1))
  (via (at 83.7 90.9) (size 0.6) (drill 0.25) (layers "F.Cu" "B.Cu") (net 1))
  (via (at 141.6 127.3) (size 0.6) (drill 0.25) (layers "F.Cu" "B.Cu") (net 1))
  (via (at 95.8 141.2) (size 0.6) (drill 0.25) (layers "F.Cu" "B.Cu") (net 1))
  (via (at 74.75 123.4) (size 0.6) (drill 0.25) (layers "F.Cu" "B.Cu") (net 1))
  (via (at 92.25 120.05) (size 0.6) (drill 0.25) (layers "F.Cu" "B.Cu") (net 1))
  (via (at 138.4 123) (size 0.6) (drill 0.25) (layers "F.Cu" "B.Cu") (net 1))
  (via (at 118.25 90.675002) (size 0.6) (drill 0.25) (layers "F.Cu" "B.Cu") (net 1))
  (via (at 152.7 101.9) (size 0.6) (drill 0.25) (layers "F.Cu" "B.Cu") (net 1))
  (via (at 88.3 141.1) (size 0.6) (drill 0.25) (layers "F.Cu" "B.Cu") (free) (net 1))
  (via (at 143.6 127.5) (size 0.6) (drill 0.25) (layers "F.Cu" "B.Cu") (net 1))
  (via (at 132.9 123.6) (size 0.6) (drill 0.25) (layers "F.Cu" "B.Cu") (net 1))
  (via (at 152.9 95.9) (size 0.6) (drill 0.25) (layers "F.Cu" "B.Cu") (net 1))
  (via (at 103.75 111.25) (size 0.6) (drill 0.25) (layers "F.Cu" "B.Cu") (net 1))
  (via (at 145 143.3) (size 0.6) (drill 0.25) (layers "F.Cu" "B.Cu") (net 1))
  (via (at 83.7 89.7) (size 0.6) (drill 0.25) (layers "F.Cu" "B.Cu") (net 1))
  (via (at 75 112.9) (size 0.6) (drill 0.25) (layers "F.Cu" "B.Cu") (free) (net 1))
  (via (at 132.9 104.5) (size 0.6) (drill 0.25) (layers "F.Cu" "B.Cu") (net 1))
  (via (at 84.95 126.2) (size 0.6) (drill 0.25) (layers "F.Cu" "B.Cu") (net 1))
  (via (at 133.8 108.3875) (size 0.6) (drill 0.25) (layers "F.Cu" "B.Cu") (net 1))
  (via (at 128.388889 101.815) (size 0.6) (drill 0.25) (layers "F.Cu" "B.Cu") (net 1))
  (via (at 133.5 101.75) (size 0.6) (drill 0.25) (layers "F.Cu" "B.Cu") (net 1))
  (via (at 96.8 85.7) (size 0.6) (drill 0.25) (layers "F.Cu" "B.Cu") (net 1))
  (via (at 79.7 108.6) (size 0.6) (drill 0.25) (layers "F.Cu" "B.Cu") (net 1))
  (via (at 96.9 103.5) (size 0.6) (drill 0.25) (layers "F.Cu" "B.Cu") (net 1))
  (via (at 123.3 110.95) (size 0.6) (drill 0.25) (layers "F.Cu" "B.Cu") (net 1))
  (via (at 129.75 91.1) (size 0.6) (drill 0.25) (layers "F.Cu" "B.Cu") (net 1))
  (via (at 141.8 122.6) (size 0.6) (drill 0.25) (layers "F.Cu" "B.Cu") (net 1))
  (via (at 125.25 110.35) (size 0.6) (drill 0.25) (layers "F.Cu" "B.Cu") (net 1))
  (via (at 134 129.05) (size 0.6) (drill 0.25) (layers "F.Cu" "B.Cu") (net 1))
  (via (at 125.6 120.2) (size 0.6) (drill 0.25) (layers "F.Cu" "B.Cu") (net 1))
  (via (at 76.2 113.5) (size 0.6) (drill 0.25) (layers "F.Cu" "B.Cu") (free) (net 1))
  (via (at 122.25 111.3) (size 0.6) (drill 0.25) (layers "F.Cu" "B.Cu") (net 1))
  (via (at 81.05 121.9) (size 0.6) (drill 0.25) (layers "F.Cu" "B.Cu") (net 1))
  (via (at 115.4 131) (size 0.6) (drill 0.25) (layers "F.Cu" "B.Cu") (net 1))
  (via (at 105.75 88.3) (size 0.6) (drill 0.25) (layers "F.Cu" "B.Cu") (net 1))
  (via (at 83.7 89.1) (size 0.6) (drill 0.25) (layers "F.Cu" "B.Cu") (net 1))
  (via (at 79.2 114.4) (size 0.6) (drill 0.25) (layers "F.Cu" "B.Cu") (net 1))
  (via (at 125.25 90.75) (size 0.6) (drill 0.25) (layers "F.Cu" "B.Cu") (net 1))
  (via (at 129.75 119.75) (size 0.6) (drill 0.25) (layers "F.Cu" "B.Cu") (net 1))
  (via (at 139.4 123) (size 0.6) (drill 0.25) (layers "F.Cu" "B.Cu") (net 1))
  (via (at 81.05 125.9) (size 0.6) (drill 0.25) (layers "F.Cu" "B.Cu") (net 1))
  (via (at 109.6 143.8) (size 0.6) (drill 0.25) (layers "F.Cu" "B.Cu") (net 1))
  (via (at 87.2 141.1) (size 0.6) (drill 0.25) (layers "F.Cu" "B.Cu") (net 1))
  (via (at 98.25 88.3) (size 0.6) (drill 0.25) (layers "F.Cu" "B.Cu") (net 1))
  (via (at 148.29 109.63) (size 0.6) (drill 0.25) (layers "F.Cu" "B.Cu") (net 1))
  (via (at 113.7 137.7) (size 0.6) (drill 0.25) (layers "F.Cu" "B.Cu") (net 1))
  (via (at 139.35 131.75) (size 0.6) (drill 0.25) (layers "F.Cu" "B.Cu") (net 1))
  (via (at 140.2 108.3) (size 0.6) (drill 0.25) (layers "F.Cu" "B.Cu") (net 1))
  (via (at 144.6 131.7) (size 0.6) (drill 0.25) (layers "F.Cu" "B.Cu") (net 1))
  (via (at 125.3 97.45) (size 0.6) (drill 0.25) (layers "F.Cu" "B.Cu") (net 1))
  (via (at 101.75 139.75) (size 0.6) (drill 0.25) (layers "F.Cu" "B.Cu") (net 1))
  (via (at 75.6 92.9) (size 0.6) (drill 0.25) (layers "F.Cu" "B.Cu") (net 1))
  (via (at 150.4 132) (size 0.6) (drill 0.25) (layers "F.Cu" "B.Cu") (net 1))
  (via (at 123.8 84.9) (size 0.6) (drill 0.25) (layers "F.Cu" "B.Cu") (net 1))
  (via (at 108.25 111.25) (size 0.6) (drill 0.25) (layers "F.Cu" "B.Cu") (net 1))
  (via (at 83.1 83.6) (size 0.6) (drill 0.25) (layers "F.Cu" "B.Cu") (net 1))
  (via (at 111.2 85.65) (size 0.6) (drill 0.25) (layers "F.Cu" "B.Cu") (net 1))
  (via (at 83.55 83.2) (size 0.6) (drill 0.25) (layers "F.Cu" "B.Cu") (net 1))
  (via (at 93.25 111.25) (size 0.6) (drill 0.25) (layers "F.Cu" "B.Cu") (net 1))
  (via (at 73.4 127.2) (size 0.6) (drill 0.25) (layers "F.Cu" "B.Cu") (net 1))
  (via (at 91.95 138.4) (size 0.6) (drill 0.25) (layers "F.Cu" "B.Cu") (net 1))
  (via (at 121.25 117.35) (size 0.6) (drill 0.25) (layers "F.Cu" "B.Cu") (net 1))
  (via (at 74.6 99.8) (size 0.6) (drill 0.25) (layers "F.Cu" "B.Cu") (net 1))
  (via (at 116.5 94.5) (size 0.6) (drill 0.25) (layers "F.Cu" "B.Cu") (net 1))
  (via (at 112.6 133.925003) (size 0.6) (drill 0.25) (layers "F.Cu" "B.Cu") (net 1))
  (via (at 100.25 149.95) (size 0.6) (drill 0.25) (layers "F.Cu" "B.Cu") (net 1))
  (segment (start 102.034174 104.972734) (end 101.949174 105.057734) (width 0.23) (layer "B.Cu") (net 1))
  (segment (start 102.034174 104.257733) (end 102.034174 104.972734) (width 0.23) (layer "B.Cu") (net 1))
  (segment (start 101.549174 106.842734) (end 101.549174 107.557733) (width 0.23) (layer "B.Cu") (net 1))
  (segment (start 99 140.9875) (end 99 140.2125) (width 0.2) (layer "B.Cu") (net 1))
  (segment (start 104.5 140.2125) (end 104.5 139.6) (width 0.2) (layer "B.Cu") (net 1))
  (segment (start 104.5 140.9875) (end 104.5 140.2125) (width 0.2) (layer "B.Cu") (net 1))
  (segment (start 111.48 146.4) (end 111.48 145.09) (width 0.125) (layer "B.Cu") (net 1))
  (segment (start 110.065 138.7) (end 108.95 138.7) (width 0.155) (layer "B.Cu") (net 1))
  (segment (start 110.065 137.5) (end 108.9 137.5) (width 0.155) (layer "B.Cu") (net 1))
  (segment (start 108.9 137.5) (end 108.8 137.4) (width 0.155) (layer "B.Cu") (net 1))
  (segment (start 99 140.2125) (end 99 139.6) (width 0.2) (layer "B.Cu") (net 1))
  (segment (start 124.515 133.9) (end 123.3 133.9) (width 0.25) (layer "B.Cu") (net 1))
  (segment (start 132.3 143.9) (end 132.3 142.665) (width 0.2) (layer "B.Cu") (net 1))
  (segment (start 132.3 142.665) (end 131.885 142.25) (width 0.2) (layer "B.Cu") (net 1))
  (segment (start 94.9 110.225) (end 95.816354 110.225) (width 0.23) (layer "B.Cu") (net 1))
  (segment (start 85.1 98.8) (end 84.75 98.45) (width 0.155) (layer "B.Cu") (net 1))
  (segment (start 71.2 128.8) (end 72.8 127.2) (width 0.15) (layer "B.Cu") (net 1))
  (segment (start 137.75 134.465) (end 138.665 134.465) (width 0.2) (layer "B.Cu") (net 1))
  (segment (start 139.075 83.625) (end 139.1 83.6) (width 0.25) (layer "B.Cu") (net 1))
  (segment (start 148.614859 100.1) (end 148.609028 100.105831) (width 0.3) (layer "B.Cu") (net 1))
  (segment (start 150.39499 107.6) (end 152.25 107.6) (width 0.3) (layer "B.Cu") (net 1))
  (segment (start 70.5 85.5) (end 70.5 84.25) (width 0.15) (layer "B.Cu") (net 1))
  (segment (start 107.25 86.9) (end 107.25 88.3) (width 0.23) (layer "B.Cu") (net 1))
  (segment (start 120.6 133.985) (end 119.6 133.985) (width 0.2) (layer "B.Cu") (net 1))
  (segment (start 94.649999 141.619999) (end 94.844997 141.425001) (width 0.2) (layer "B.Cu") (net 1))
  (segment (start 149.3 135) (end 148.55 134.25) (width 0.2) (layer "B.Cu") (net 1))
  (segment (start 94.649999 142.650001) (end 94.649999 141.619999) (width 0.2) (layer "B.Cu") (net 1))
  (segment (start 151.59999 104.59999) (end 151.6 104.6) (width 0.3) (layer "B.Cu") (net 1))
  (segment (start 139.388164 128.227953) (end 139.388164 127.411836) (width 0.2) (layer "B.Cu") (net 1))
  (segment (start 76 112) (end 76 113.1) (width 0.15) (layer "B.Cu") (net 1))
  (segment (start 135.85 134.45) (end 135.9 134.5) (width 0.2) (layer "B.Cu") (net 1))
  (segment (start 149.5 132) (end 150.4 132) (width 0.25) (layer "B.Cu") (net 1))
  (segment (start 144.015 126.6) (end 144.015 125.6) (width 0.2) (layer "B.Cu") (net 1))
  (segment (start 72.8 127.2) (end 73.4 127.2) (width 0.15) (layer "B.Cu") (net 1))
  (segment (start 98.4 114.6) (end 98 114.6) (width 0.3) (layer "B.Cu") (net 1))
  (segment (start 94.6 107.8) (end 94.106441 107.8) (width 0.23) (layer "B.Cu") (net 1))
  (segment (start 109.05 144.75) (end 109.05 143.85) (width 0.25) (layer "B.Cu") (net 1))
  (segment (start 74.5 123.15) (end 74.75 123.4) (width 0.3) (layer "B.Cu") (net 1))
  (segment (start 95.4 142.9) (end 95.1125 142.9) (width 0.2) (layer "B.Cu") (net 1))
  (segment (start 99.549174 106.842734) (end 99.549174 107.775826) (width 0.23) (layer "B.Cu") (net 1))
  (segment (start 149.5 129) (end 151.4 129) (width 0.25) (layer "B.Cu") (net 1))
  (segment (start 114 132.700002) (end 114.799998 133.5) (width 0.2) (layer "B.Cu") (net 1))
  (segment (start 139.388164 127.411836) (end 139.4 127.4) (width 0.2) (layer "B.Cu") (net 1))
  (segment (start 99.75 88.05) (end 99.75 86.9) (width 0.23) (layer "B.Cu") (net 1))
  (segment (start 83.25 125.5) (end 83.35 125.6) (width 0.15) (layer "B.Cu") (net 1))
  (segment (start 137.39 128.225) (end 137.39 127.71) (width 0.2) (layer "B.Cu") (net 1))
  (segment (start 151.4 129) (end 151.8 128.6) (width 0.25) (layer "B.Cu") (net 1))
  (segment (start 81.85 121.55) (end 81.85 121.385) (width 0.2) (layer "B.Cu") (net 1))
  (segment (start 80.05 139.83) (end 80.05 140.4) (width 0.15) (layer "B.Cu") (net 1))
  (segment (start 133.5 101.085) (end 133.5 101.75) (width 0.25) (layer "B.Cu") (net 1))
  (segment (start 149.25 143.7) (end 148.95 144) (width 0.2) (layer "B.Cu") (net 1))
  (segment (start 127.07 142.795) (end 127.615 142.25) (width 0.2) (layer "B.Cu") (net 1))
  (segment (start 98.25 88.05) (end 98.25 86.9) (width 0.23) (layer "B.Cu") (net 1))
  (segment (start 118 133.75) (end 118.75 133.75) (width 0.25) (layer "B.Cu") (net 1))
  (segment (start 99.275 108.05) (end 98.491354 108.05) (width 0.23) (layer "B.Cu") (net 1))
  (segment (start 85.2 119.25) (end 85.95 120) (width 0.15) (layer "B.Cu") (net 1))
  (segment (start 139.86 105.6) (end 139.145 105.6) (width 0.3) (layer "B.Cu") (net 1))
  (segment (start 143.55 121.885) (end 143.55 122.55) (width 0.2) (layer "B.Cu") (net 1))
  (segment (start 134.115003 123.066848) (end 134.115003 122.066849) (width 0.25) (layer "B.Cu") (net 1))
  (segment (start 152.59999 95.59999) (end 152.9 95.9) (width 0.3) (layer "B.Cu") (net 1))
  (segment (start 139.65 91.646) (end 139.65 91.9) (width 0.25) (layer "B.Cu") (net 1))
  (segment (start 131.685 103.3) (end 132.35 103.3) (width 0.3) (layer "B.Cu") (net 1))
  (segment (start 146.05 138.65) (end 147.45 137.25) (width 0.2) (layer "B.Cu") (net 1))
  (segment (start 86.6 140.5) (end 84.9 140.5) (width 0.3) (layer "B.Cu") (net 1))
  (segment (start 151.59999 109.59999) (end 151.6 109.6) (width 0.3) (layer "B.Cu") (net 1))
  (segment (start 115.4 131) (end 115.4 130.485) (width 0.25) (layer "B.Cu") (net 1))
  (segment (start 118 133.75) (end 116 133.75) (width 0.25) (layer "B.Cu") (net 1))
  (segment (start 105.75 88.05) (end 105.75 86.9) (width 0.23) (layer "B.Cu") (net 1))
  (segment (start 138.665 134.465) (end 138.7 134.5) (width 0.2) (layer "B.Cu") (net 1))
  (segment (start 151.4 109.1) (end 151.6 109.3) (width 0.2) (layer "B.Cu") (net 1))
  (segment (start 97.6 114.6) (end 98 114.6) (width 0.3) (layer "B.Cu") (net 1))
  (segment (start 76 113.1) (end 75.6 113.5) (width 0.15) (layer "B.Cu") (net 1))
  (segment (start 144.35 131.95) (end 144.6 131.7) (width 0.2) (layer "B.Cu") (net 1))
  (segment (start 133.5 100.315) (end 133.5 101.085) (width 0.25) (layer "B.Cu") (net 1))
  (segment (start 137.8 127.3) (end 138.4 127.3) (width 0.2) (layer "B.Cu") (net 1))
  (segment (start 74.6 147.4) (end 75.2 146.8) (width 0.125) (layer "B.Cu") (net 1))
  (segment (start 87.2 140.7) (end 87 140.5) (width 0.3) (layer "B.Cu") (net 1))
  (segment (start 96.75 86.9) (end 96.75 85.75) (width 0.23) (layer "B.Cu") (net 1))
  (segment (start 85.1 99) (end 85.1 98.8) (width 0.155) (layer "B.Cu") (net 1))
  (segment (start 93.115 101.5) (end 92.4 101.5) (width 0.25) (layer "B.Cu") (net 1))
  (segment (start 138.388164 128.227953) (end 138.388164 127.311836) (width 0.2) (layer "B.Cu") (net 1))
  (segment (start 115.5 132.15) (end 115.5 133.25) (width 0.25) (layer "B.Cu") (net 1))
  (segment (start 135.575 99.982495) (end 135.6 100.007495) (width 0.25) (layer "B.Cu") (net 1))
  (segment (start 144.6 122.415) (end 144.115 122.9) (width 0.2) (layer "B.Cu") (net 1))
  (segment (start 94.844997 141.425001) (end 95.574999 141.425001) (width 0.2) (layer "B.Cu") (net 1))
  (segment (start 140.2 108.706) (end 140.2 108.3) (width 0.3) (layer "B.Cu") (net 1))
  (segment (start 83.25 124.05) (end 83.25 125.5) (width 0.15) (layer "B.Cu") (net 1))
  (segment (start 141.65 128.215) (end 141.65 127.35) (width 0.2) (layer "B.Cu") (net 1))
  (segment (start 149.61999 90) (end 151.4 90) (width 0.3) (layer "B.Cu") (net 1))
  (segment (start 124.2 84.9) (end 123.8 84.9) (width 0.125) (layer "B.Cu") (net 1))
  (segment (start 145.25 138.65) (end 146.05 138.65) (width 0.2) (layer "B.Cu") (net 1))
  (segment (start 75.6 93.615) (end 75.6 92.9) (width 0.15) (layer "B.Cu") (net 1))
  (segment (start 125.375 97.525) (end 125.3 97.45) (width 0.3) (layer "B.Cu") (net 1))
  (segment (start 138.258164 126.212952) (end 138.258164 127.158164) (width 0.23) (layer "B.Cu") (net 1))
  (segment (start 128.35 98.9) (end 128.525 98.725) (width 0.3) (layer "B.Cu") (net 1))
  (segment (start 99.549174 107.775826) (end 99.275 108.05) (width 0.23) (layer "B.Cu") (net 1))
  (segment (start 113.5 133.75) (end 112.775003 133.75) (width 0.2) (layer "B.Cu") (net 1))
  (segment (start 128.35 101.1375) (end 128.35 98.9) (width 0.3) (layer "B.Cu") (net 1))
  (segment (start 107.15 143.8) (end 106.9 143.55) (width 0.4) (layer "B.Cu") (net 1))
  (segment (start 114 132.15) (end 114 132.700002) (width 0.2) (layer "B.Cu") (net 1))
  (segment (start 109.3 143.8) (end 107.15 143.8) (width 0.4) (layer "B.Cu") (net 1))
  (segment (start 151.59999 97.09999) (end 151.6 97.1) (width 0.3) (layer "B.Cu") (net 1))
  (segment (start 139.65 131.95) (end 140.365 131.95) (width 0.2) (layer "B.Cu") (net 1))
  (segment (start 99.275 108.24355) (end 99.691694 108.660244) (width 0.23) (layer "B.Cu") (net 1))
  (segment (start 93.164174 101.5) (end 92.4 101.5) (width 0.125) (layer "B.Cu") (net 1))
  (segment (start 144.015 126.6) (end 143.2 126.6) (width 0.2) (layer "B.Cu") (net 1))
  (segment (start 144.015 125.6) (end 144.015 124.6) (width 0.2) (layer "B.Cu") (net 1))
  (segment (start 139.856 109.05) (end 140.2 108.706) (width 0.3) (layer "B.Cu") (net 1))
  (segment (start 149.7 143.7) (end 149.25 143.7) (width 0.2) (layer "B.Cu") (net 1))
  (segment (start 128.35 101.085) (end 128.35 101.776111) (width 0.3) (layer "B.Cu") (net 1))
  (segment (start 112.775003 133.75) (end 112.6 133.925003) (width 0.2) (layer "B.Cu") (net 1))
  (segment (start 115.5 131.1) (end 115.4 131) (width 0.25) (layer "B.Cu") (net 1))
  (segment (start 143.55 122.55) (end 143.2 122.9) (width 0.2) (layer "B.Cu") (net 1))
  (segment (start 101.75 140.3125) (end 101.75 139.75) (width 0.2) (layer "B.Cu") (net 1))
  (segment (start 149.5 123) (end 148.9 123) (width 0.25) (layer "B.Cu") (net 1))
  (segment (start 148.9 123) (end 148.7 122.8) (width 0.25) (layer "B.Cu") (net 1))
  (segment (start 124.425 92.525) (end 124.45 92.5) (width 0.3) (layer "B.Cu") (net 1))
  (segment (start 94.764174 107.635826) (end 94.6 107.8) (width 0.23) (layer "B.Cu") (net 1))
  (segment (start 132.2 104.5) (end 132.9 104.5) (width 0.3) (layer "B.Cu") (net 1))
  (segment (start 127.07 143.89) (end 127.07 142.795) (width 0.2) (layer "B.Cu") (net 1))
  (segment (start 94.9 110.071139) (end 94.459104 109.630243) (width 0.23) (layer "B.Cu") (net 1))
  (segment (start 143.615 128.15) (end 143.615 127.515) (width 0.2) (layer "B.Cu") (net 1))
  (segment (start 74.085 123.15) (end 74.5 123.15) (width 0.3) (layer "B.Cu") (net 1))
  (segment (start 152.4 101.6) (end 152.7 101.9) (width 0.3) (layer "B.Cu") (net 1))
  (segment (start 139.4 122.185) (end 139.4 123) (width 0.2) (layer "B.Cu") (net 1))
  (segment (start 94.764174 106.957733) (end 94.764174 107.635826) (width 0.23) (layer "B.Cu") (net 1))
  (segment (start 150.39499 97.09999) (end 151.59999 97.09999) (width 0.3) (layer "B.Cu") (net 1))
  (segment (start 66.8 100.4) (end 71.2 100.4) (width 0.2) (layer "B.Cu") (net 1))
  (segment (start 109.05 142.85) (end 109.05 143.75) (width 0.25) (layer "B.Cu") (net 1))
  (segment (start 147.515 83) (end 146 83) (width 0.23) (layer "B.Cu") (net 1))
  (segment (start 85.1 100.4) (end 85.1 99) (width 0.15) (layer "B.Cu") (net 1))
  (segment (start 105.75 88.3) (end 105.75 88.05) (width 0.23) (layer "B.Cu") (net 1))
  (segment (start 120.8 128.2) (end 120.8 129.39999) (width 0.15) (layer "B.Cu") (net 1))
  (segment (start 150.39999 109.1) (end 151.4 109.1) (width 0.2) (layer "B.Cu") (net 1))
  (segment (start 80.85 148.05) (end 79.85 148.05) (width 0.2) (layer "B.Cu") (net 1))
  (segment (start 135.25 134.45) (end 135.85 134.45) (width 0.2) (layer "B.Cu") (net 1))
  (segment (start 118.75 133.75) (end 118.9 133.9) (width 0.25) (layer "B.Cu") (net 1))
  (segment (start 125.375 98.725) (end 125.375 97.525) (width 0.3) (layer "B.Cu") (net 1))
  (segment (start 149.5 126) (end 151.3 126) (width 0.25) (layer "B.Cu") (net 1))
  (segment (start 137.39 127.71) (end 137.8 127.3) (width 0.2) (layer "B.Cu") (net 1))
  (segment (start 144.115 122.9) (end 143.2 122.9) (width 0.2) (layer "B.Cu") (net 1))
  (segment (start 80.45 122.5) (end 81.05 121.9) (width 0.125) (layer "B.Cu") (net 1))
  (segment (start 142.65 128.215) (end 141.65 128.215) (width 0.2) (layer "B.Cu") (net 1))
  (segment (start 137.925 83.625) (end 139.075 83.625) (width 0.25) (layer "B.Cu") (net 1))
  (segment (start 87 140.5) (end 86.6 140.5) (width 0.3) (layer "B.Cu") (net 1))
  (segment (start 128.35 101.776111) (end 128.388889 101.815) (width 0.3) (layer "B.Cu") (net 1))
  (segment (start 70.5 84.25) (end 70.25 84) (width 0.15) (layer "B.Cu") (net 1))
  (segment (start 135.575 98.725) (end 135.575 99.982495) (width 0.25) (layer "B.Cu") (net 1))
  (segment (start 138.4 122.185) (end 138.4 123) (width 0.2) (layer "B.Cu") (net 1))
  (segment (start 133.888164 124.527952) (end 133.327952 124.527952) (width 0.25) (layer "B.Cu") (net 1))
  (segment (start 149.5 117) (end 151.4 117) (width 0.25) (layer "B.Cu") (net 1))
  (segment (start 98.25 88.3) (end 98.25 88.05) (width 0.23) (layer "B.Cu") (net 1))
  (segment (start 101.35 88.3) (end 101.25 88.05) (width 0.23) (layer "B.Cu") (net 1))
  (segment (start 144.6 121.885) (end 144.6 122.415) (width 0.2) (layer "B.Cu") (net 1))
  (segment (start 150.39499 100.1) (end 148.614859 100.1) (width 0.3) (layer "B.Cu") (net 1))
  (segment (start 143.615 129.15) (end 143.615 128.15) (width 0.2) (layer "B.Cu") (net 1))
  (segment (start 136.75 134.465) (end 135.935 134.465) (width 0.2) (layer "B.Cu") (net 1))
  (segment (start 95.8 148.25) (end 96.85 148.25) (width 0.2) (layer "B.Cu") (net 1))
  (segment (start 151.4 117) (end 151.8 116.6) (width 0.25) (layer "B.Cu") (net 1))
  (segment (start 115.5 132.15) (end 115.5 131.1) (width 0.25) (layer "B.Cu") (net 1))
  (segment (start 142.515 121.885) (end 141.8 122.6) (width 0.2) (layer "B.Cu") (net 1))
  (segment (start 151.6 109.3) (end 151.6 109.6) (width 0.2) (layer "B.Cu") (net 1))
  (segment (start 81.85 121.385) (end 81.35 120.885) (width 0.2) (layer "B.Cu") (net 1))
  (segment (start 120.75 123.05) (end 120.7 123.1) (width 0.15) (layer "B.Cu") (net 1))
  (segment (start 112.6 133.925003) (end 111.859997 133.925003) (width 0.2) (layer "B.Cu") (net 1))
  (segment (start 133.327952 124.527952) (end 132.9 124.1) (width 0.25) (layer "B.Cu") (net 1))
  (segment (start 95.4 142.9) (end 94.899998 142.9) (width 0.2) (layer "B.Cu") (net 1))
  (segment (start 132.9 124.1) (end 132.9 123.6) (width 0.25) (layer "B.Cu") (net 1))
  (segment (start 134 129.05) (end 134 127.6) (width 0.125) (layer "B.Cu") (net 1))
  (segment (start 134.985 105.95) (end 135.65 105.95) (width 0.15) (layer "B.Cu") (net 1))
  (segment (start 95.574999 141.425001) (end 95.8 141.2) (width 0.2) (layer "B.Cu") (net 1))
  (segment (start 69.235 85.5) (end 70.5 85.5) (width 0.23) (layer "B.Cu") (net 1))
  (segment (start 133.8 107.895) (end 133.8 108.3875) (width 0.15) (layer "B.Cu") (net 1))
  (segment (start 151.3 126) (end 151.7 125.6) (width 0.25) (layer "B.Cu") (net 1))
  (segment (start 138.388164 127.311836) (end 138.4 127.3) (width 0.2) (layer "B.Cu") (net 1))
  (segment (start 148.55 134.25) (end 147.45 134.25) (width 0.2) (layer "B.Cu") (net 1))
  (segment (start 149.633791 120) (end 149.965099 120.331308) (width 0.25) (layer "B.Cu") (net 1))
  (segment (start 150.39499 106.1) (end 151.6 106.1) (width 0.3) (layer "B.Cu") (net 1))
  (segment (start 124.425 94.425) (end 124.425 92.525) (width 0.3) (layer "B.Cu") (net 1))
  (segment (start 94.106441 107.8) (end 93.749174 107.442733) (width 0.23) (layer "B.Cu") (net 1))
  (segment (start 74.085 125.15) (end 74.085 124.15) (width 0.2) (layer "B.Cu") (net 1))
  (segment (start 139.86 106.6) (end 139.145 106.6) (width 0.3) (layer "B.Cu") (net 1))
  (segment (start 148.614865 98.6) (end 148.609032 98.594167) (width 0.3) (layer "B.Cu") (net 1))
  (segment (start 150.39499 103.1) (end 151.6 103.1) (width 0.3) (layer "B.Cu") (net 1))
  (segment (start 92.75 105.425) (end 92.632933 105.432933) (width 0.2) (layer "B.Cu") (net 1))
  (segment (start 121.365 123.05) (end 120.75 123.05) (width 0.15) (layer "B.Cu") (net 1))
  (segment (start 94.899998 142.9) (end 94.649999 142.650001) (width 0.2) (layer "B.Cu") (net 1))
  (segment (start 138.258164 127.158164) (end 138.4 127.3) (width 0.23) (layer "B.Cu") (net 1))
  (segment (start 150.39499 98.6) (end 148.614865 98.6) (width 0.3) (layer "B.Cu") (net 1))
  (segment (start 99.8 88.3) (end 99.75 88.05) (width 0.23) (layer "B.Cu") (net 1))
  (segment (start 139.35 131.75) (end 139.65 131.95) (width 0.2) (layer "B.Cu") (net 1))
  (segment (start 150.39499 95.59999) (end 152.59999 95.59999) (width 0.3) (layer "B.Cu") (net 1))
  (segment (start 94.9 110.225) (end 94.9 110.071139) (width 0.23) (layer "B.Cu") (net 1))
  (segment (start 133.266849 122.066849) (end 133.1 121.9) (width 0.25) (layer "B.Cu") (net 1))
  (segment (start 154 144.265) (end 154 143.5) (width 0.23) (layer "B.Cu") (net 1))
  (segment (start 149.5 135) (end 150.4 135) (width 0.25) (layer "B.Cu") (net 1))
  (segment (start 150.4 135) (end 149.3 135) (width 0.2) (layer "B.Cu") (net 1))
  (segment (start 141.65 127.35) (end 141.6 127.3) (width 0.2) (layer "B.Cu") (net 1))
  (segment (start 99.275 108.05) (end 99.275 108.24355) (width 0.23) (layer "B.Cu") (net 1))
  (segment (start 96.75 85.75) (end 96.8 85.7) (width 0.23) (layer "B.Cu") (net 1))
  (segment (start 135.935 134.465) (end 135.9 134.5) (width 0.2) (layer "B.Cu") (net 1))
  (segment (start 101.25 88.05) (end 101.25 86.9) (width 0.23) (layer "B.Cu") (net 1))
  (segment (start 95.8875 142.9) (end 95.4 142.9) (width 0.2) (layer "B.Cu") (net 1))
  (segment (start 143.685 131.95) (end 144.35 131.95) (width 0.2) (layer "B.Cu") (net 1))
  (segment (start 75.2 146.8) (end 75.9 146.8) (width 0.125) (layer "B.Cu") (net 1))
  (segment (start 132.115 105.95) (end 132.115 104.585) (width 0.15) (layer "B.Cu") (net 1))
  (segment (start 139.856 91.44) (end 139.65 91.646) (width 0.25) (layer "B.Cu") (net 1))
  (segment (start 134.115003 122.066849) (end 133.266849 122.066849) (width 0.25) (layer "B.Cu") (net 1))
  (segment (start 150.39499 104.59999) (end 151.59999 104.59999) (width 0.3) (layer "B.Cu") (net 1))
  (segment (start 92.632933 105.432933) (end 93.443774 105.432933) (width 0.2) (layer "B.Cu") (net 1))
  (segment (start 150.39499 109.59999) (end 151.59999 109.59999) (width 0.3) (layer "B.Cu") (net 1))
  (segment (start 74.085 123.15) (end 74.085 124.15) (width 0.2) (layer "B.Cu") (net 1))
  (segment (start 118.9 133.9) (end 119.515 133.9) (width 0.25) (layer "B.Cu") (net 1))
  (segment (start 149.61999 110.7) (end 151.6 110.7) (width 0.3) (layer "B.Cu") (net 1))
  (segment (start 87.2 141.1) (end 87.2 140.7) (width 0.3) (layer "B.Cu") (net 1))
  (segment (start 143.615 127.515) (end 143.6 127.5) (width 0.2) (layer "B.Cu") (net 1))
  (segment (start 101.75 141.0875) (end 101.75 140.3125) (width 0.2) (layer "B.Cu") (net 1))
  (segment (start 152.25 107.6) (end 152.6 107.95) (width 0.3) (layer "B.Cu") (net 1))
  (segment (start 150.39499 101.6) (end 152.4 101.6) (width 0.3) (layer "B.Cu") (net 1))
  (segment (start 57.15 130.45) (end 62.8 130.45) (width 0.2) (layer "F.Cu") (net 2))
  (segment (start 56.8 130.8) (end 56.8 135.2) (width 0.2) (layer "F.Cu") (net 2))
  (segment (start 57.15 130.45) (end 56.8 130.8) (width 0.2) (layer "F.Cu") (net 2))
  (segment (start 56.8 135.2) (end 59.7 138.1) (width 0.2) (layer "F.Cu") (net 2))
  (segment (start 62.8 130.45) (end 63.75 129.5) (width 0.2) (layer "F.Cu") (net 2))
  (segment (start 69.2 138.1) (end 69.87 138.77) (width 0.2) (layer "F.Cu") (net 2))
  (segment (start 59.7 138.1) (end 69.2 138.1) (width 0.2) (layer "F.Cu") (net 2))
  (via (at 63.75 129.5) (size 0.6) (drill 0.25) (layers "F.Cu" "B.Cu") (net 2))
  (segment (start 63.75 129) (end 63.75 129.5) (width 0.2) (layer "B.Cu") (net 2))
  (segment (start 64.3 128.45) (end 63.75 129) (width 0.2) (layer "B.Cu") (net 2))
  (segment (start 64.925 128.45) (end 64.3 128.45) (width 0.2) (layer "B.Cu") (net 2))
  (via (at 60.75 129.5) (size 0.6) (drill 0.25) (layers "F.Cu" "B.Cu") (net 3))
  (segment (start 59.7 138.1) (end 57.2 135.6) (width 0.2) (layer "In4.Cu") (net 3))
  (segment (start 56.8 135.2) (end 56.8 130.8) (width 0.2) (layer "In4.Cu") (net 3))
  (segment (start 67.39 140.04) (end 65.45 138.1) (width 0.2) (layer "In4.Cu") (net 3))
  (segment (start 65.45 138.1) (end 59.7 138.1) (width 0.2) (layer "In4.Cu") (net 3))
  (segment (start 56.8 130.8) (end 58.1 129.5) (width 0.2) (layer "In4.Cu") (net 3))
  (segment (start 58.1 129.5) (end 60.75 129.5) (width 0.2) (layer "In4.Cu") (net 3))
  (segment (start 57.2 135.6) (end 56.8 135.2) (width 0.2) (layer "In4.Cu") (net 3))
  (segment (start 57.2 135.6) (end 56.9 135.3) (width 0.2) (layer "In4.Cu") (net 3))
  (segment (start 62.475 128.45) (end 61.8 128.45) (width 0.2) (layer "B.Cu") (net 3))
  (segment (start 61.8 128.45) (end 60.75 129.5) (width 0.2) (layer "B.Cu") (net 3))
  (via (at 63.5 140.1) (size 0.6) (drill 0.25) (layers "F.Cu" "B.Cu") (net 4))
  (via (at 59.75 151) (size 0.6) (drill 0.25) (layers "F.Cu" "B.Cu") (net 4))
  (segment (start 60.515 151) (end 59.75 151) (width 0.23) (layer "B.Cu") (net 4))
  (segment (start 63.5 139.385) (end 63.5 140.1) (width 0.25) (layer "B.Cu") (net 4))
  (segment (start 57.9 130.2) (end 58.8 130.2) (width 0.2) (layer "B.Cu") (net 5))
  (segment (start 57.4 130.2) (end 57.9 130.2) (width 0.2) (layer "B.Cu") (net 5))
  (segment (start 61.04 140.04) (end 61.04 139.44) (width 0.2) (layer "B.Cu") (net 5))
  (segment (start 56.8 130.8) (end 57.4 130.2) (width 0.2) (layer "B.Cu") (net 5))
  (segment (start 56.8 135.2) (end 56.8 130.8) (width 0.2) (layer "B.Cu") (net 5))
  (segment (start 59.325 129.675) (end 59.325 128.45) (width 0.2) (layer "B.Cu") (net 5))
  (segment (start 61.04 139.44) (end 56.8 135.2) (width 0.2) (layer "B.Cu") (net 5))
  (segment (start 58.8 130.2) (end 59.325 129.675) (width 0.2) (layer "B.Cu") (net 5))
  (segment (start 58.5 138.78) (end 55.75 136.03) (width 0.2) (layer "B.Cu") (net 6))
  (segment (start 55.75 136.03) (end 55.75 129.575) (width 0.2) (layer "B.Cu") (net 6))
  (segment (start 55.75 129.575) (end 56.875 128.45) (width 0.2) (layer "B.Cu") (net 6))
  (segment (start 67.95 117.85) (end 68.7 117.85) (width 0.15) (layer "F.Cu") (net 7))
  (via (at 67.95 117.85) (size 0.6) (drill 0.25) (layers "F.Cu" "B.Cu") (net 7))
  (via (at 55.75 105.5) (size 0.6) (drill 0.25) (layers "F.Cu" "B.Cu") (net 7))
  (via (at 57.25 105.5) (size 0.6) (drill 0.25) (layers "F.Cu" "B.Cu") (net 7))
  (via (at 58 105.5) (size 0.6) (drill 0.25) (layers "F.Cu" "B.Cu") (net 7))
  (via (at 56.1 117.9) (size 0.6) (drill 0.25) (layers "F.Cu" "B.Cu") (net 7))
  (via (at 58 106.25) (size 0.6) (drill 0.25) (layers "F.Cu" "B.Cu") (net 7))
  (via (at 61.75 104.25) (size 0.6) (drill 0.25) (layers "F.Cu" "B.Cu") (net 7))
  (via (at 56.5 105.5) (size 0.6) (drill 0.25) (layers "F.Cu" "B.Cu") (net 7))
  (via (at 57.25 106.25) (size 0.6) (drill 0.25) (layers "F.Cu" "B.Cu") (net 7))
  (via (at 55.75 106.25) (size 0.6) (drill 0.25) (layers "F.Cu" "B.Cu") (net 7))
  (via (at 56.5 106.25) (size 0.6) (drill 0.25) (layers "F.Cu" "B.Cu") (net 7))
  (via (at 56.5 107) (size 0.6) (drill 0.25) (layers "F.Cu" "B.Cu") (net 7))
  (via (at 55.75 107) (size 0.6) (drill 0.25) (layers "F.Cu" "B.Cu") (net 7))
  (via (at 57.25 107) (size 0.6) (drill 0.25) (layers "F.Cu" "B.Cu") (net 7))
  (via (at 58 107) (size 0.6) (drill 0.25) (layers "F.Cu" "B.Cu") (net 7))
  (segment (start 56.15 117.85) (end 56.1 117.9) (width 0.15) (layer "In3.Cu") (net 7))
  (segment (start 67.95 117.85) (end 56.15 117.85) (width 0.15) (layer "In3.Cu") (net 7))
  (segment (start 61.785 104.215) (end 61.75 104.25) (width 0.15) (layer "B.Cu") (net 7))
  (segment (start 56.5 105.5) (end 56.5 104) (width 0.25) (layer "B.Cu") (net 7))
  (segment (start 61.75 104.25) (end 61.75 103.335) (width 0.15) (layer "B.Cu") (net 7))
  (segment (start 68.7 117.85) (end 67.95 117.85) (width 0.2) (layer "B.Cu") (net 7))
  (segment (start 62.6 104.215) (end 61.785 104.215) (width 0.15) (layer "B.Cu") (net 7))
  (segment (start 105.75 90.750153) (end 105.647499 90.852654) (width 0.17) (layer "F.Cu") (net 8))
  (segment (start 105.6475 91.5625) (end 106 91.915) (width 0.17) (layer "F.Cu") (net 8))
  (segment (start 105.647499 90.852654) (end 105.6475 91.5625) (width 0.17) (layer "F.Cu") (net 8))
  (segment (start 105.75 89.550002) (end 105.75 90.750153) (width 0.17) (layer "F.Cu") (net 8))
  (segment (start 105.249999 89.550002) (end 105.249999 90.750153) (width 0.17) (layer "F.Cu") (net 9))
  (segment (start 105.3525 91.5625) (end 105 91.915) (width 0.17) (layer "F.Cu") (net 9))
  (segment (start 105.3525 90.852654) (end 105.3525 91.5625) (width 0.17) (layer "F.Cu") (net 9))
  (segment (start 105.249999 90.750153) (end 105.3525 90.852654) (width 0.17) (layer "F.Cu") (net 9))
  (segment (start 99.86 120.14201) (end 99.86 119.295) (width 0.155) (layer "F.Cu") (net 10))
  (segment (start 99.86 119.295) (end 99.75 119.185) (width 0.155) (layer "F.Cu") (net 10))
  (segment (start 94.46 138.955) (end 94.46 135.59201) (width 0.155) (layer "F.Cu") (net 10))
  (segment (start 95.060735 134.991275) (end 98.060735 134.991275) (width 0.155) (layer "F.Cu") (net 10))
  (segment (start 94.1 139.315) (end 94.46 138.955) (width 0.155) (layer "F.Cu") (net 10))
  (segment (start 94.46 135.59201) (end 95.060735 134.991275) (width 0.155) (layer "F.Cu") (net 10))
  (segment (start 98.060735 134.991275) (end 98.61 134.44201) (width 0.155) (layer "F.Cu") (net 10))
  (segment (start 98.61 134.44201) (end 98.61 121.39201) (width 0.155) (layer "F.Cu") (net 10))
  (segment (start 98.61 121.39201) (end 99.86 120.14201) (width 0.155) (layer "F.Cu") (net 10))
  (segment (start 95.176715 135.271275) (end 98.176715 135.271275) (width 0.155) (layer "F.Cu") (net 11))
  (segment (start 94.74 138.955) (end 94.74 135.70799) (width 0.155) (layer "F.Cu") (net 11))
  (segment (start 98.89 121.50799) (end 100.14 120.25799) (width 0.155) (layer "F.Cu") (net 11))
  (segment (start 95.1 139.315) (end 94.74 138.955) (width 0.155) (layer "F.Cu") (net 11))
  (segment (start 100.14 120.25799) (end 100.14 119.295) (width 0.155) (layer "F.Cu") (net 11))
  (segment (start 100.14 119.295) (end 100.25 119.185) (width 0.155) (layer "F.Cu") (net 11))
  (segment (start 94.74 135.70799) (end 95.176715 135.271275) (width 0.155) (layer "F.Cu") (net 11))
  (segment (start 98.176715 135.271275) (end 98.89 134.55799) (width 0.155) (layer "F.Cu") (net 11))
  (segment (start 98.89 134.55799) (end 98.89 121.50799) (width 0.155) (layer "F.Cu") (net 11))
  (segment (start 127.374999 84.9625) (end 127.137499 85.2) (width 0.125) (layer "F.Cu") (net 12))
  (segment (start 127.375 84.775151) (end 127.374999 84.9625) (width 0.125) (layer "F.Cu") (net 12))
  (segment (start 127.25 84.650151) (end 127.375 84.775151) (width 0.125) (layer "F.Cu") (net 12))
  (segment (start 127.25 83.45) (end 127.25 84.650151) (width 0.125) (layer "F.Cu") (net 12))
  (via (at 127.137499 85.2) (size 0.6) (drill 0.25) (layers "F.Cu" "B.Cu") (net 12))
  (via (at 106.393673 94.743673) (size 0.6) (drill 0.25) (layers "F.Cu" "B.Cu") (net 12))
  (segment (start 127.337499 85.4) (end 127.137499 85.2) (width 0.125) (layer "In2.Cu") (net 12))
  (segment (start 115.648229 96.817187) (end 115.670001 96.795415) (width 0.125) (layer "In2.Cu") (net 12))
  (segment (start 117.5783 94.97097) (end 117.660926 95.022887) (width 0.125) (layer "In2.Cu") (net 12))
  (segment (start 115.381844 96.284199) (end 115.414074 96.376306) (width 0.125) (layer "In2.Cu") (net 12))
  (segment (start 122.3783 94.92097) (end 122.460926 94.972887) (width 0.125) (layer "In2.Cu") (net 12))
  (segment (start 121.454998 96.795415) (end 121.47677 96.817187) (width 0.125) (layer "In2.Cu") (net 12))
  (segment (start 119.10284 96.833569) (end 119.131903 96.843738) (width 0.125) (layer "In2.Cu") (net 12))
  (segment (start 116.625 95.41359) (end 116.625 96.709686) (width 0.125) (layer "In2.Cu") (net 12))
  (segment (start 115.670001 96.795415) (end 115.686383 96.769345) (width 0.125) (layer "In2.Cu") (net 12))
  (segment (start 120.935775 94.877814) (end 120.989224 94.877814) (width 0.125) (layer "In2.Cu") (net 12))
  (segment (start 117.335775 94.927814) (end 117.389224 94.927814) (width 0.125) (layer "In2.Cu") (net 12))
  (segment (start 119.054998 96.795415) (end 119.07677 96.817187) (width 0.125) (layer "In2.Cu") (net 12))
  (segment (start 118.110925 95.216621) (end 118.143155 95.124514) (width 0.125) (layer "In2.Cu") (net 12))
  (segment (start 122.638616 95.95966) (end 122.654998 95.98573) (width 0.125) (layer "In2.Cu") (net 12))
  (segment (start 119.9783 94.92097) (end 120.060926 94.972887) (width 0.125) (layer "In2.Cu") (net 12))
  (segment (start 117.9625 96.847186) (end 117.993096 96.843738) (width 0.125) (layer "In2.Cu") (net 12))
  (segment (start 119.025 96.709686) (end 119.028447 96.740282) (width 0.125) (layer "In2.Cu") (net 12))
  (segment (start 118.981844 95.124514) (end 119.014074 95.216621) (width 0.125) (layer "In2.Cu") (net 12))
  (segment (start 118.929927 95.041888) (end 118.981844 95.124514) (width 0.125) (layer "In2.Cu") (net 12))
  (segment (start 117.486193 94.93874) (end 117.5783 94.97097) (width 0.125) (layer "In2.Cu") (net 12))
  (segment (start 120.5 95.31359) (end 120.510925 95.216621) (width 0.125) (layer "In2.Cu") (net 12))
  (segment (start 117.781844 95.174514) (end 117.814074 95.266621) (width 0.125) (layer "In2.Cu") (net 12))
  (segment (start 120.214074 95.216621) (end 120.225 95.31359) (width 0.125) (layer "In2.Cu") (net 12))
  (segment (start 119.735775 94.877814) (end 119.789224 94.877814) (width 0.125) (layer "In2.Cu") (net 12))
  (segment (start 115.7 95.41359) (end 115.710925 95.316621) (width 0.125) (layer "In2.Cu") (net 12))
  (segment (start 116.9 96.709686) (end 116.9 95.36359) (width 0.125) (layer "In2.Cu") (net 12))
  (segment (start 119.038616 96.769345) (end 119.054998 96.795415) (width 0.125) (layer "In2.Cu") (net 12))
  (segment (start 119.028447 96.740282) (end 119.038616 96.769345) (width 0.125) (layer "In2.Cu") (net 12))
  (segment (start 115.743155 95.224514) (end 115.795072 95.141888) (width 0.125) (layer "In2.Cu") (net 12))
  (segment (start 118.086383 96.769345) (end 118.096552 96.740282) (width 0.125) (layer "In2.Cu") (net 12))
  (segment (start 120.225 95.31359) (end 120.225 96.709686) (width 0.125) (layer "In2.Cu") (net 12))
  (segment (start 115.260926 96.132572) (end 115.329927 96.201573) (width 0.125) (layer "In2.Cu") (net 12))
  (segment (start 114.513272 96.0375) (end 114.989224 96.0375) (width 0.125) (layer "In2.Cu") (net 12))
  (segment (start 119.1625 96.847186) (end 119.193096 96.843738) (width 0.125) (layer "In2.Cu") (net 12))
  (segment (start 119.193096 96.843738) (end 119.222159 96.833569) (width 0.125) (layer "In2.Cu") (net 12))
  (segment (start 115.425 96.473275) (end 115.425 96.709686) (width 0.125) (layer "In2.Cu") (net 12))
  (segment (start 114.989224 96.0375) (end 115.086193 96.048425) (width 0.125) (layer "In2.Cu") (net 12))
  (segment (start 122.67677 96.007502) (end 122.70284 96.023884) (width 0.125) (layer "In2.Cu") (net 12))
  (segment (start 120.838806 94.88874) (end 120.935775 94.877814) (width 0.125) (layer "In2.Cu") (net 12))
  (segment (start 116.822159 96.833569) (end 116.848229 96.817187) (width 0.125) (layer "In2.Cu") (net 12))
  (segment (start 121.696552 96.740282) (end 121.7 96.709686) (width 0.125) (layer "In2.Cu") (net 12))
  (segment (start 106.393673 94.743673) (end 106.676517 94.743673) (width 0.125) (layer "In2.Cu") (net 12))
  (segment (start 121.743155 95.124514) (end 121.795072 95.041888) (width 0.125) (layer "In2.Cu") (net 12))
  (segment (start 117.146699 94.97097) (end 117.238806 94.93874) (width 0.125) (layer "In2.Cu") (net 12))
  (segment (start 117.828447 96.740282) (end 117.838616 96.769345) (width 0.125) (layer "In2.Cu") (net 12))
  (segment (start 115.428447 96.740282) (end 115.438616 96.769345) (width 0.125) (layer "In2.Cu") (net 12))
  (segment (start 117.825 96.709686) (end 117.828447 96.740282) (width 0.125) (layer "In2.Cu") (net 12))
  (segment (start 121.670001 96.795415) (end 121.686383 96.769345) (width 0.125) (layer "In2.Cu") (net 12))
  (segment (start 115.438616 96.769345) (end 115.454998 96.795415) (width 0.125) (layer "In2.Cu") (net 12))
  (segment (start 117.660926 95.022887) (end 117.729927 95.091888) (width 0.125) (layer "In2.Cu") (net 12))
  (segment (start 119.270001 96.795415) (end 119.286383 96.769345) (width 0.125) (layer "In2.Cu") (net 12))
  (segment (start 106.98269 94.4375) (end 107.66731 94.4375) (width 0.125) (layer "In2.Cu") (net 12))
  (segment (start 122.581844 95.124514) (end 122.614074 95.216621) (width 0.125) (layer "In2.Cu") (net 12))
  (segment (start 118.346699 94.92097) (end 118.438806 94.88874) (width 0.125) (layer "In2.Cu") (net 12))
  (segment (start 119.546699 94.92097) (end 119.638806 94.88874) (width 0.125) (layer "In2.Cu") (net 12))
  (segment (start 116.731903 96.843738) (end 116.7625 96.847186) (width 0.125) (layer "In2.Cu") (net 12))
  (segment (start 121.428447 96.740282) (end 121.438616 96.769345) (width 0.125) (layer "In2.Cu") (net 12))
  (segment (start 119.222159 96.833569) (end 119.248229 96.817187) (width 0.125) (layer "In2.Cu") (net 12))
  (segment (start 116.7625 96.847186) (end 116.793096 96.843738) (width 0.125) (layer "In2.Cu") (net 12))
  (segment (start 120.543155 95.124514) (end 120.595072 95.041888) (width 0.125) (layer "In2.Cu") (net 12))
  (segment (start 118.7783 94.92097) (end 118.860926 94.972887) (width 0.125) (layer "In2.Cu") (net 12))
  (segment (start 121.7 96.709686) (end 121.7 95.31359) (width 0.125) (layer "In2.Cu") (net 12))
  (segment (start 122.286193 94.88874) (end 122.3783 94.92097) (width 0.125) (layer "In2.Cu") (net 12))
  (segment (start 119.286383 96.769345) (end 119.296552 96.740282) (width 0.125) (layer "In2.Cu") (net 12))
  (segment (start 115.50284 96.833569) (end 115.531903 96.843738) (width 0.125) (layer "In2.Cu") (net 12))
  (segment (start 118.022159 96.833569) (end 118.048229 96.817187) (width 0.125) (layer "In2.Cu") (net 12))
  (segment (start 120.060926 94.972887) (end 120.129927 95.041888) (width 0.125) (layer "In2.Cu") (net 12))
  (segment (start 122.189224 94.877814) (end 122.286193 94.88874) (width 0.125) (layer "In2.Cu") (net 12))
  (segment (start 117.838616 96.769345) (end 117.854998 96.795415) (width 0.125) (layer "In2.Cu") (net 12))
  (segment (start 116.995072 95.091888) (end 117.064073 95.022887) (width 0.125) (layer "In2.Cu") (net 12))
  (segment (start 117.931903 96.843738) (end 117.9625 96.847186) (width 0.125) (layer "In2.Cu") (net 12))
  (segment (start 115.531903 96.843738) (end 115.5625 96.847186) (width 0.125) (layer "In2.Cu") (net 12))
  (segment (start 115.696552 96.740282) (end 115.7 96.709686) (width 0.125) (layer "In2.Cu") (net 12))
  (segment (start 119.014074 95.216621) (end 119.025 95.31359) (width 0.125) (layer "In2.Cu") (net 12))
  (segment (start 116.286193 94.98874) (end 116.3783 95.02097) (width 0.125) (layer "In2.Cu") (net 12))
  (segment (start 116.654998 96.795415) (end 116.67677 96.817187) (width 0.125) (layer "In2.Cu") (net 12))
  (segment (start 115.329927 96.201573) (end 115.381844 96.284199) (width 0.125) (layer "In2.Cu") (net 12))
  (segment (start 116.460926 95.072887) (end 116.529927 95.141888) (width 0.125) (layer "In2.Cu") (net 12))
  (segment (start 119.395072 95.041888) (end 119.464073 94.972887) (width 0.125) (layer "In2.Cu") (net 12))
  (segment (start 116.189224 94.977814) (end 116.286193 94.98874) (width 0.125) (layer "In2.Cu") (net 12))
  (segment (start 117.87677 96.817187) (end 117.90284 96.833569) (width 0.125) (layer "In2.Cu") (net 12))
  (segment (start 121.5625 96.847186) (end 121.593096 96.843738) (width 0.125) (layer "In2.Cu") (net 12))
  (segment (start 116.793096 96.843738) (end 116.822159 96.833569) (width 0.125) (layer "In2.Cu") (net 12))
  (segment (start 117.729927 95.091888) (end 117.781844 95.174514) (width 0.125) (layer "In2.Cu") (net 12))
  (segment (start 121.47677 96.817187) (end 121.50284 96.833569) (width 0.125) (layer "In2.Cu") (net 12))
  (segment (start 122.529927 95.041888) (end 122.581844 95.124514) (width 0.125) (layer "In2.Cu") (net 12))
  (segment (start 115.454998 96.795415) (end 115.47677 96.817187) (width 0.125) (layer "In2.Cu") (net 12))
  (segment (start 115.5625 96.847186) (end 115.593096 96.843738) (width 0.125) (layer "In2.Cu") (net 12))
  (segment (start 116.625 96.709686) (end 116.628447 96.740282) (width 0.125) (layer "In2.Cu") (net 12))
  (segment (start 119.3 96.709686) (end 119.3 95.31359) (width 0.125) (layer "In2.Cu") (net 12))
  (segment (start 115.086193 96.048425) (end 115.1783 96.080655) (width 0.125) (layer "In2.Cu") (net 12))
  (segment (start 117.064073 95.022887) (end 117.146699 94.97097) (width 0.125) (layer "In2.Cu") (net 12))
  (segment (start 119.248229 96.817187) (end 119.270001 96.795415) (width 0.125) (layer "In2.Cu") (net 12))
  (segment (start 120.393096 96.843738) (end 120.422159 96.833569) (width 0.125) (layer "In2.Cu") (net 12))
  (segment (start 122.731903 96.034053) (end 122.7625 96.0375) (width 0.125) (layer "In2.Cu") (net 12))
  (segment (start 127.3375 92.18269) (end 127.3375 85.4) (width 0.125) (layer "In2.Cu") (net 12))
  (segment (start 118.096552 96.740282) (end 118.1 96.709686) (width 0.125) (layer "In2.Cu") (net 12))
  (segment (start 115.1783 96.080655) (end 115.260926 96.132572) (width 0.125) (layer "In2.Cu") (net 12))
  (segment (start 119.343155 95.124514) (end 119.395072 95.041888) (width 0.125) (layer "In2.Cu") (net 12))
  (segment (start 117.825 95.36359) (end 117.825 96.709686) (width 0.125) (layer "In2.Cu") (net 12))
  (segment (start 119.3 95.31359) (end 119.310925 95.216621) (width 0.125) (layer "In2.Cu") (net 12))
  (segment (start 121.260926 94.972887) (end 121.329927 95.041888) (width 0.125) (layer "In2.Cu") (net 12))
  (segment (start 118.589224 94.877814) (end 118.686193 94.88874) (width 0.125) (layer "In2.Cu") (net 12))
  (segment (start 116.038806 94.98874) (end 116.135775 94.977814) (width 0.125) (layer "In2.Cu") (net 12))
  (segment (start 118.686193 94.88874) (end 118.7783 94.92097) (width 0.125) (layer "In2.Cu") (net 12))
  (segment (start 121.329927 95.041888) (end 121.381844 95.124514) (width 0.125) (layer "In2.Cu") (net 12))
  (segment (start 120.30284 96.833569) (end 120.331903 96.843738) (width 0.125) (layer "In2.Cu") (net 12))
  (segment (start 118.195072 95.041888) (end 118.264073 94.972887) (width 0.125) (layer "In2.Cu") (net 12))
  (segment (start 121.414074 95.216621) (end 121.425 95.31359) (width 0.125) (layer "In2.Cu") (net 12))
  (segment (start 116.70284 96.833569) (end 116.731903 96.843738) (width 0.125) (layer "In2.Cu") (net 12))
  (segment (start 115.686383 96.769345) (end 115.696552 96.740282) (width 0.125) (layer "In2.Cu") (net 12))
  (segment (start 118.438806 94.88874) (end 118.535775 94.877814) (width 0.125) (layer "In2.Cu") (net 12))
  (segment (start 120.181844 95.124514) (end 120.214074 95.216621) (width 0.125) (layer "In2.Cu") (net 12))
  (segment (start 118.1 95.31359) (end 118.110925 95.216621) (width 0.125) (layer "In2.Cu") (net 12))
  (segment (start 115.710925 95.316621) (end 115.743155 95.224514) (width 0.125) (layer "In2.Cu") (net 12))
  (segment (start 120.228447 96.740282) (end 120.238616 96.769345) (width 0.125) (layer "In2.Cu") (net 12))
  (segment (start 107.66731 94.4375) (end 108.1625 94.93269) (width 0.125) (layer "In2.Cu") (net 12))
  (segment (start 121.946699 94.92097) (end 122.038806 94.88874) (width 0.125) (layer "In2.Cu") (net 12))
  (segment (start 121.425 95.31359) (end 121.425 96.709686) (width 0.125) (layer "In2.Cu") (net 12))
  (segment (start 120.746699 94.92097) (end 120.838806 94.88874) (width 0.125) (layer "In2.Cu") (net 12))
  (segment (start 116.896552 96.740282) (end 116.9 96.709686) (width 0.125) (layer "In2.Cu") (net 12))
  (segment (start 120.225 96.709686) (end 120.228447 96.740282) (width 0.125) (layer "In2.Cu") (net 12))
  (segment (start 118.860926 94.972887) (end 118.929927 95.041888) (width 0.125) (layer "In2.Cu") (net 12))
  (segment (start 118.070001 96.795415) (end 118.086383 96.769345) (width 0.125) (layer "In2.Cu") (net 12))
  (segment (start 122.654998 95.98573) (end 122.67677 96.007502) (width 0.125) (layer "In2.Cu") (net 12))
  (segment (start 121.593096 96.843738) (end 121.622159 96.833569) (width 0.125) (layer "In2.Cu") (net 12))
  (segment (start 122.625 95.31359) (end 122.625 95.9) (width 0.125) (layer "In2.Cu") (net 12))
  (segment (start 108.1625 95.73269) (end 108.66731 96.2375) (width 0.125) (layer "In2.Cu") (net 12))
  (segment (start 119.789224 94.877814) (end 119.886193 94.88874) (width 0.125) (layer "In2.Cu") (net 12))
  (segment (start 120.496552 96.740282) (end 120.5 96.709686) (width 0.125) (layer "In2.Cu") (net 12))
  (segment (start 116.9 95.36359) (end 116.910925 95.266621) (width 0.125) (layer "In2.Cu") (net 12))
  (segment (start 116.886383 96.769345) (end 116.896552 96.740282) (width 0.125) (layer "In2.Cu") (net 12))
  (segment (start 120.3625 96.847186) (end 120.393096 96.843738) (width 0.125) (layer "In2.Cu") (net 12))
  (segment (start 119.025 95.31359) (end 119.025 96.709686) (width 0.125) (layer "In2.Cu") (net 12))
  (segment (start 116.3783 95.02097) (end 116.460926 95.072887) (width 0.125) (layer "In2.Cu") (net 12))
  (segment (start 120.595072 95.041888) (end 120.664073 94.972887) (width 0.125) (layer "In2.Cu") (net 12))
  (segment (start 122.614074 95.216621) (end 122.625 95.31359) (width 0.125) (layer "In2.Cu") (net 12))
  (segment (start 120.448229 96.817187) (end 120.470001 96.795415) (width 0.125) (layer "In2.Cu") (net 12))
  (segment (start 120.254998 96.795415) (end 120.27677 96.817187) (width 0.125) (layer "In2.Cu") (net 12))
  (segment (start 121.086193 94.88874) (end 121.1783 94.92097) (width 0.125) (layer "In2.Cu") (net 12))
  (segment (start 121.864073 94.972887) (end 121.946699 94.92097) (width 0.125) (layer "In2.Cu") (net 12))
  (segment (start 116.135775 94.977814) (end 116.189224 94.977814) (width 0.125) (layer "In2.Cu") (net 12))
  (segment (start 117.814074 95.266621) (end 117.825 95.36359) (width 0.125) (layer "In2.Cu") (net 12))
  (segment (start 120.664073 94.972887) (end 120.746699 94.92097) (width 0.125) (layer "In2.Cu") (net 12))
  (segment (start 119.464073 94.972887) (end 119.546699 94.92097) (width 0.125) (layer "In2.Cu") (net 12))
  (segment (start 116.67677 96.817187) (end 116.70284 96.833569) (width 0.125) (layer "In2.Cu") (net 12))
  (segment (start 122.460926 94.972887) (end 122.529927 95.041888) (width 0.125) (layer "In2.Cu") (net 12))
  (segment (start 121.531903 96.843738) (end 121.5625 96.847186) (width 0.125) (layer "In2.Cu") (net 12))
  (segment (start 118.264073 94.972887) (end 118.346699 94.92097) (width 0.125) (layer "In2.Cu") (net 12))
  (segment (start 122.628447 95.930597) (end 122.638616 95.95966) (width 0.125) (layer "In2.Cu") (net 12))
  (segment (start 120.5 96.709686) (end 120.5 95.31359) (width 0.125) (layer "In2.Cu") (net 12))
  (segment (start 120.510925 95.216621) (end 120.543155 95.124514) (width 0.125) (layer "In2.Cu") (net 12))
  (segment (start 116.943155 95.174514) (end 116.995072 95.091888) (width 0.125) (layer "In2.Cu") (net 12))
  (segment (start 114.313272 96.2375) (end 114.513272 96.0375) (width 0.125) (layer "In2.Cu") (net 12))
  (segment (start 122.625 95.9) (end 122.628447 95.930597) (width 0.125) (layer "In2.Cu") (net 12))
  (segment (start 117.389224 94.927814) (end 117.486193 94.93874) (width 0.125) (layer "In2.Cu") (net 12))
  (segment (start 115.795072 95.141888) (end 115.864073 95.072887) (width 0.125) (layer "In2.Cu") (net 12))
  (segment (start 116.638616 96.769345) (end 116.654998 96.795415) (width 0.125) (layer "In2.Cu") (net 12))
  (segment (start 115.414074 96.376306) (end 115.425 96.473275) (width 0.125) (layer "In2.Cu") (net 12))
  (segment (start 123.48269 96.0375) (end 127.3375 92.18269) (width 0.125) (layer "In2.Cu") (net 12))
  (segment (start 121.622159 96.833569) (end 121.648229 96.817187) (width 0.125) (layer "In2.Cu") (net 12))
  (segment (start 121.381844 95.124514) (end 121.414074 95.216621) (width 0.125) (layer "In2.Cu") (net 12))
  (segment (start 116.529927 95.141888) (end 116.581844 95.224514) (width 0.125) (layer "In2.Cu") (net 12))
  (segment (start 117.90284 96.833569) (end 117.931903 96.843738) (width 0.125) (layer "In2.Cu") (net 12))
  (segment (start 122.70284 96.023884) (end 122.731903 96.034053) (width 0.125) (layer "In2.Cu") (net 12))
  (segment (start 119.296552 96.740282) (end 119.3 96.709686) (width 0.125) (layer "In2.Cu") (net 12))
  (segment (start 120.486383 96.769345) (end 120.496552 96.740282) (width 0.125) (layer "In2.Cu") (net 12))
  (segment (start 118.048229 96.817187) (end 118.070001 96.795415) (width 0.125) (layer "In2.Cu") (net 12))
  (segment (start 122.038806 94.88874) (end 122.135775 94.877814) (width 0.125) (layer "In2.Cu") (net 12))
  (segment (start 116.581844 95.224514) (end 116.614074 95.316621) (width 0.125) (layer "In2.Cu") (net 12))
  (segment (start 115.593096 96.843738) (end 115.622159 96.833569) (width 0.125) (layer "In2.Cu") (net 12))
  (segment (start 115.7 96.709686) (end 115.7 95.41359) (width 0.125) (layer "In2.Cu") (net 12))
  (segment (start 122.135775 94.877814) (end 122.189224 94.877814) (width 0.125) (layer "In2.Cu") (net 12))
  (segment (start 121.648229 96.817187) (end 121.670001 96.795415) (width 0.125) (layer "In2.Cu") (net 12))
  (segment (start 119.07677 96.817187) (end 119.10284 96.833569) (width 0.125) (layer "In2.Cu") (net 12))
  (segment (start 121.50284 96.833569) (end 121.531903 96.843738) (width 0.125) (layer "In2.Cu") (net 12))
  (segment (start 116.848229 96.817187) (end 116.870001 96.795415) (width 0.125) (layer "In2.Cu") (net 12))
  (segment (start 119.886193 94.88874) (end 119.9783 94.92097) (width 0.125) (layer "In2.Cu") (net 12))
  (segment (start 115.622159 96.833569) (end 115.648229 96.817187) (width 0.125) (layer "In2.Cu") (net 12))
  (segment (start 121.795072 95.041888) (end 121.864073 94.972887) (width 0.125) (layer "In2.Cu") (net 12))
  (segment (start 121.425 96.709686) (end 121.428447 96.740282) (width 0.125) (layer "In2.Cu") (net 12))
  (segment (start 121.710925 95.216621) (end 121.743155 95.124514) (width 0.125) (layer "In2.Cu") (net 12))
  (segment (start 119.638806 94.88874) (end 119.735775 94.877814) (width 0.125) (layer "In2.Cu") (net 12))
  (segment (start 115.946699 95.02097) (end 116.038806 94.98874) (width 0.125) (layer "In2.Cu") (net 12))
  (segment (start 120.422159 96.833569) (end 120.448229 96.817187) (width 0.125) (layer "In2.Cu") (net 12))
  (segment (start 117.238806 94.93874) (end 117.335775 94.927814) (width 0.125) (layer "In2.Cu") (net 12))
  (segment (start 121.1783 94.92097) (end 121.260926 94.972887) (width 0.125) (layer "In2.Cu") (net 12))
  (segment (start 115.47677 96.817187) (end 115.50284 96.833569) (width 0.125) (layer "In2.Cu") (net 12))
  (segment (start 120.238616 96.769345) (end 120.254998 96.795415) (width 0.125) (layer "In2.Cu") (net 12))
  (segment (start 118.1 96.709686) (end 118.1 95.31359) (width 0.125) (layer "In2.Cu") (net 12))
  (segment (start 120.129927 95.041888) (end 120.181844 95.124514) (width 0.125) (layer "In2.Cu") (net 12))
  (segment (start 120.331903 96.843738) (end 120.3625 96.847186) (width 0.125) (layer "In2.Cu") (net 12))
  (segment (start 108.66731 96.2375) (end 114.313272 96.2375) (width 0.125) (layer "In2.Cu") (net 12))
  (segment (start 108.1625 94.93269) (end 108.1625 95.73269) (width 0.125) (layer "In2.Cu") (net 12))
  (segment (start 106.676517 94.743673) (end 106.98269 94.4375) (width 0.125) (layer "In2.Cu") (net 12))
  (segment (start 120.27677 96.817187) (end 120.30284 96.833569) (width 0.125) (layer "In2.Cu") (net 12))
  (segment (start 118.143155 95.124514) (end 118.195072 95.041888) (width 0.125) (layer "In2.Cu") (net 12))
  (segment (start 117.854998 96.795415) (end 117.87677 96.817187) (width 0.125) (layer "In2.Cu") (net 12))
  (segment (start 117.993096 96.843738) (end 118.022159 96.833569) (width 0.125) (layer "In2.Cu") (net 12))
  (segment (start 118.535775 94.877814) (end 118.589224 94.877814) (width 0.125) (layer "In2.Cu") (net 12))
  (segment (start 119.310925 95.216621) (end 119.343155 95.124514) (width 0.125) (layer "In2.Cu") (net 12))
  (segment (start 121.438616 96.769345) (end 121.454998 96.795415) (width 0.125) (layer "In2.Cu") (net 12))
  (segment (start 121.7 95.31359) (end 121.710925 95.216621) (width 0.125) (layer "In2.Cu") (net 12))
  (segment (start 115.425 96.709686) (end 115.428447 96.740282) (width 0.125) (layer "In2.Cu") (net 12))
  (segment (start 121.686383 96.769345) (end 121.696552 96.740282) (width 0.125) (layer "In2.Cu") (net 12))
  (segment (start 119.131903 96.843738) (end 119.1625 96.847186) (width 0.125) (layer "In2.Cu") (net 12))
  (segment (start 116.870001 96.795415) (end 116.886383 96.769345) (width 0.125) (layer "In2.Cu") (net 12))
  (segment (start 116.614074 95.316621) (end 116.625 95.41359) (width 0.125) (layer "In2.Cu") (net 12))
  (segment (start 116.628447 96.740282) (end 116.638616 96.769345) (width 0.125) (layer "In2.Cu") (net 12))
  (segment (start 122.7625 96.0375) (end 123.48269 96.0375) (width 0.125) (layer "In2.Cu") (net 12))
  (segment (start 115.864073 95.072887) (end 115.946699 95.02097) (width 0.125) (layer "In2.Cu") (net 12))
  (segment (start 120.470001 96.795415) (end 120.486383 96.769345) (width 0.125) (layer "In2.Cu") (net 12))
  (segment (start 116.910925 95.266621) (end 116.943155 95.174514) (width 0.125) (layer "In2.Cu") (net 12))
  (segment (start 120.989224 94.877814) (end 121.086193 94.88874) (width 0.125) (layer "In2.Cu") (net 12))
  (segment (start 106.72955 94.743673) (end 106.393673 94.743673) (width 0.125) (layer "B.Cu") (net 12))
  (segment (start 106.875 94.598223) (end 106.72955 94.743673) (width 0.125) (layer "B.Cu") (net 12))
  (segment (start 106.875 94.290001) (end 106.875 94.598223) (width 0.125) (layer "B.Cu") (net 12))
  (segment (start 106.76 93.95) (end 106.76 94.175001) (width 0.125) (layer "B.Cu") (net 12))
  (segment (start 106.76 94.175001) (end 106.875 94.290001) (width 0.125) (layer "B.Cu") (net 12))
  (segment (start 127.749999 83.45) (end 127.749999 84.650151) (width 0.125) (layer "F.Cu") (net 13))
  (segment (start 127.624999 84.9625) (end 127.862499 85.2) (width 0.125) (layer "F.Cu") (net 13))
  (segment (start 127.749999 84.650151) (end 127.624999 84.775151) (width 0.125) (layer "F.Cu") (net 13))
  (segment (start 127.624999 84.775151) (end 127.624999 84.9625) (width 0.125) (layer "F.Cu") (net 13))
  (via (at 127.862499 85.2) (size 0.6) (drill 0.25) (layers "F.Cu" "B.Cu") (net 13))
  (via (at 106.906327 95.256327) (size 0.6) (drill 0.25) (layers "F.Cu" "B.Cu") (net 13))
  (segment (start 127.862499 85.2) (end 127.662499 85.4) (width 0.125) (layer "In2.Cu") (net 13))
  (segment (start 122.3 95.926725) (end 122.310925 96.023694) (width 0.125) (layer "In2.Cu") (net 13))
  (segment (start 106.906327 94.973483) (end 107.11731 94.7625) (width 0.125) (layer "In2.Cu") (net 13))
  (segment (start 119.286193 97.16126) (end 119.3783 97.12903) (width 0.125) (layer "In2.Cu") (net 13))
  (segment (start 121.981844 96.925486) (end 122.014074 96.833379) (width 0.125) (layer "In2.Cu") (net 13))
  (segment (start 119.793096 95.206262) (end 119.822159 95.216431) (width 0.125) (layer "In2.Cu") (net 13))
  (segment (start 117.5 95.390314) (end 117.5 96.73641) (width 0.125) (layer "In2.Cu") (net 13))
  (segment (start 114.993096 96.365947) (end 115.022159 96.376116) (width 0.125) (layer "In2.Cu") (net 13))
  (segment (start 121.1 96.73641) (end 121.110925 96.833379) (width 0.125) (layer "In2.Cu") (net 13))
  (segment (start 116.025 96.73641) (end 116.025 95.440314) (width 0.125) (layer "In2.Cu") (net 13))
  (segment (start 116.054998 95.354585) (end 116.07677 95.332813) (width 0.125) (layer "In2.Cu") (net 13))
  (segment (start 115.535775 97.172186) (end 115.589224 97.172186) (width 0.125) (layer "In2.Cu") (net 13))
  (segment (start 120.9625 95.202814) (end 120.993096 95.206262) (width 0.125) (layer "In2.Cu") (net 13))
  (segment (start 117.238616 95.330655) (end 117.254998 95.304585) (width 0.125) (layer "In2.Cu") (net 13))
  (segment (start 121.195072 97.008112) (end 121.264073 97.077113) (width 0.125) (layer "In2.Cu") (net 13))
  (segment (start 117.225 96.73641) (end 117.225 95.390314) (width 0.125) (layer "In2.Cu") (net 13))
  (segment (start 118.329927 97.008112) (end 118.381844 96.925486) (width 0.125) (layer "In2.Cu") (net 13))
  (segment (start 116.270001 95.354585) (end 116.286383 95.380655) (width 0.125) (layer "In2.Cu") (net 13))
  (segment (start 119.038806 97.16126) (end 119.135775 97.172186) (width 0.125) (layer "In2.Cu") (net 13))
  (segment (start 118.710925 96.833379) (end 118.743155 96.925486) (width 0.125) (layer "In2.Cu") (net 13))
  (segment (start 117.331903 95.256262) (end 117.3625 95.252814) (width 0.125) (layer "In2.Cu") (net 13))
  (segment (start 116.9783 97.12903) (end 117.060926 97.077113) (width 0.125) (layer "In2.Cu") (net 13))
  (segment (start 119.67677 95.232813) (end 119.70284 95.216431) (width 0.125) (layer "In2.Cu") (net 13))
  (segment (start 117.838806 97.16126) (end 117.935775 97.172186) (width 0.125) (layer "In2.Cu") (net 13))
  (segment (start 107.8375 95.06731) (end 107.8375 95.86731) (width 0.125) (layer "In2.Cu") (net 13))
  (segment (start 119.460926 97.077113) (end 119.529927 97.008112) (width 0.125) (layer "In2.Cu") (net 13))
  (segment (start 122.638806 96.351575) (end 122.735775 96.3625) (width 0.125) (layer "In2.Cu") (net 13))
  (segment (start 106.906327 95.256327) (end 106.906327 94.973483) (width 0.125) (layer "In2.Cu") (net 13))
  (segment (start 117.181844 96.925486) (end 117.214074 96.833379) (width 0.125) (layer "In2.Cu") (net 13))
  (segment (start 115.346699 97.12903) (end 115.438806 97.16126) (width 0.125) (layer "In2.Cu") (net 13))
  (segment (start 118.425 95.340314) (end 118.428447 95.309718) (width 0.125) (layer "In2.Cu") (net 13))
  (segment (start 118.696552 95.309718) (end 118.7 95.340314) (width 0.125) (layer "In2.Cu") (net 13))
  (segment (start 116.222159 95.316431) (end 116.248229 95.332813) (width 0.125) (layer "In2.Cu") (net 13))
  (segment (start 122.296552 95.309718) (end 122.3 95.340314) (width 0.125) (layer "In2.Cu") (net 13))
  (segment (start 118.5625 95.202814) (end 118.593096 95.206262) (width 0.125) (layer "In2.Cu") (net 13))
  (segment (start 122.014074 96.833379) (end 122.025 96.73641) (width 0.125) (layer "In2.Cu") (net 13))
  (segment (start 116.638806 97.16126) (end 116.735775 97.172186) (width 0.125) (layer "In2.Cu") (net 13))
  (segment (start 117.470001 95.304585) (end 117.486383 95.330655) (width 0.125) (layer "In2.Cu") (net 13))
  (segment (start 117.496552 95.359718) (end 117.5 95.390314) (width 0.125) (layer "In2.Cu") (net 13))
  (segment (start 122.025 95.340314) (end 122.028447 95.309718) (width 0.125) (layer "In2.Cu") (net 13))
  (segment (start 117.510925 96.833379) (end 117.543155 96.925486) (width 0.125) (layer "In2.Cu") (net 13))
  (segment (start 117.060926 97.077113) (end 117.129927 97.008112) (width 0.125) (layer "In2.Cu") (net 13))
  (segment (start 121.346699 97.12903) (end 121.438806 97.16126) (width 0.125) (layer "In2.Cu") (net 13))
  (segment (start 117.214074 96.833379) (end 117.225 96.73641) (width 0.125) (layer "In2.Cu") (net 13))
  (segment (start 116.310925 96.833379) (end 116.343155 96.925486) (width 0.125) (layer "In2.Cu") (net 13))
  (segment (start 117.5 96.73641) (end 117.510925 96.833379) (width 0.125) (layer "In2.Cu") (net 13))
  (segment (start 121.929927 97.008112) (end 121.981844 96.925486) (width 0.125) (layer "In2.Cu") (net 13))
  (segment (start 116.014074 96.833379) (end 116.025 96.73641) (width 0.125) (layer "In2.Cu") (net 13))
  (segment (start 120.838616 95.280655) (end 120.854998 95.254585) (width 0.125) (layer "In2.Cu") (net 13))
  (segment (start 120.389224 97.172186) (end 120.486193 97.16126) (width 0.125) (layer "In2.Cu") (net 13))
  (segment (start 117.3625 95.252814) (end 117.393096 95.256262) (width 0.125) (layer "In2.Cu") (net 13))
  (segment (start 116.1625 95.302814) (end 116.193096 95.306262) (width 0.125) (layer "In2.Cu") (net 13))
  (segment (start 115.070001 96.41427) (end 115.086383 96.44034) (width 0.125) (layer "In2.Cu") (net 13))
  (segment (start 118.414074 96.833379) (end 118.425 96.73641) (width 0.125) (layer "In2.Cu") (net 13))
  (segment (start 107.53269 94.7625) (end 107.8375 95.06731) (width 0.125) (layer "In2.Cu") (net 13))
  (segment (start 118.086193 97.16126) (end 118.1783 97.12903) (width 0.125) (layer "In2.Cu") (net 13))
  (segment (start 115.7783 97.12903) (end 115.860926 97.077113) (width 0.125) (layer "In2.Cu") (net 13))
  (segment (start 121.143155 96.925486) (end 121.195072 97.008112) (width 0.125) (layer "In2.Cu") (net 13))
  (segment (start 122.038616 95.280655) (end 122.054998 95.254585) (width 0.125) (layer "In2.Cu") (net 13))
  (segment (start 119.529927 97.008112) (end 119.581844 96.925486) (width 0.125) (layer "In2.Cu") (net 13))
  (segment (start 122.10284 95.216431) (end 122.131903 95.206262) (width 0.125) (layer "In2.Cu") (net 13))
  (segment (start 117.27677 95.282813) (end 117.30284 95.266431) (width 0.125) (layer "In2.Cu") (net 13))
  (segment (start 118.946699 97.12903) (end 119.038806 97.16126) (width 0.125) (layer "In2.Cu") (net 13))
  (segment (start 119.638616 95.280655) (end 119.654998 95.254585) (width 0.125) (layer "In2.Cu") (net 13))
  (segment (start 122.464073 96.267428) (end 122.546699 96.319345) (width 0.125) (layer "In2.Cu") (net 13))
  (segment (start 117.543155 96.925486) (end 117.595072 97.008112) (width 0.125) (layer "In2.Cu") (net 13))
  (segment (start 119.9 96.73641) (end 119.910925 96.833379) (width 0.125) (layer "In2.Cu") (net 13))
  (segment (start 115.048229 96.392498) (end 115.070001 96.41427) (width 0.125) (layer "In2.Cu") (net 13))
  (segment (start 118.260926 97.077113) (end 118.329927 97.008112) (width 0.125) (layer "In2.Cu") (net 13))
  (segment (start 116.038616 95.380655) (end 116.054998 95.354585) (width 0.125) (layer "In2.Cu") (net 13))
  (segment (start 122.07677 95.232813) (end 122.10284 95.216431) (width 0.125) (layer "In2.Cu") (net 13))
  (segment (start 116.193096 95.306262) (end 116.222159 95.316431) (width 0.125) (layer "In2.Cu") (net 13))
  (segment (start 122.735775 96.3625) (end 123.61731 96.3625) (width 0.125) (layer "In2.Cu") (net 13))
  (segment (start 117.422159 95.266431) (end 117.448229 95.282813) (width 0.125) (layer "In2.Cu") (net 13))
  (segment (start 115.860926 97.077113) (end 115.929927 97.008112) (width 0.125) (layer "In2.Cu") (net 13))
  (segment (start 118.7 95.340314) (end 118.7 96.73641) (width 0.125) (layer "In2.Cu") (net 13))
  (segment (start 119.848229 95.232813) (end 119.870001 95.254585) (width 0.125) (layer "In2.Cu") (net 13))
  (segment (start 122.248229 95.232813) (end 122.270001 95.254585) (width 0.125) (layer "In2.Cu") (net 13))
  (segment (start 118.531903 95.206262) (end 118.5625 95.202814) (width 0.125) (layer "In2.Cu") (net 13))
  (segment (start 120.238806 97.16126) (end 120.335775 97.172186) (width 0.125) (layer "In2.Cu") (net 13))
  (segment (start 119.614074 96.833379) (end 119.625 96.73641) (width 0.125) (layer "In2.Cu") (net 13))
  (segment (start 122.054998 95.254585) (end 122.07677 95.232813) (width 0.125) (layer "In2.Cu") (net 13))
  (segment (start 119.7625 95.202814) (end 119.793096 95.206262) (width 0.125) (layer "In2.Cu") (net 13))
  (segment (start 115.086383 96.44034) (end 115.096552 96.469403) (width 0.125) (layer "In2.Cu") (net 13))
  (segment (start 119.628447 95.309718) (end 119.638616 95.280655) (width 0.125) (layer "In2.Cu") (net 13))
  (segment (start 121.070001 95.254585) (end 121.086383 95.280655) (width 0.125) (layer "In2.Cu") (net 13))
  (segment (start 117.254998 95.304585) (end 117.27677 95.282813) (width 0.125) (layer "In2.Cu") (net 13))
  (segment (start 120.825 96.73641) (end 120.825 95.340314) (width 0.125) (layer "In2.Cu") (net 13))
  (segment (start 122.3 95.340314) (end 122.3 95.926725) (width 0.125) (layer "In2.Cu") (net 13))
  (segment (start 122.222159 95.216431) (end 122.248229 95.232813) (width 0.125) (layer "In2.Cu") (net 13))
  (segment (start 121.086383 95.280655) (end 121.096552 95.309718) (width 0.125) (layer "In2.Cu") (net 13))
  (segment (start 120.781844 96.925486) (end 120.814074 96.833379) (width 0.125) (layer "In2.Cu") (net 13))
  (segment (start 120.854998 95.254585) (end 120.87677 95.232813) (width 0.125) (layer "In2.Cu") (net 13))
  (segment (start 115.686193 97.16126) (end 115.7783 97.12903) (width 0.125) (layer "In2.Cu") (net 13))
  (segment (start 122.546699 96.319345) (end 122.638806 96.351575) (width 0.125) (layer "In2.Cu") (net 13))
  (segment (start 118.381844 96.925486) (end 118.414074 96.833379) (width 0.125) (layer "In2.Cu") (net 13))
  (segment (start 117.486383 95.330655) (end 117.496552 95.359718) (width 0.125) (layer "In2.Cu") (net 13))
  (segment (start 107.11731 94.7625) (end 107.53269 94.7625) (width 0.125) (layer "In2.Cu") (net 13))
  (segment (start 120.931903 95.206262) (end 120.9625 95.202814) (width 0.125) (layer "In2.Cu") (net 13))
  (segment (start 120.828447 95.309718) (end 120.838616 95.280655) (width 0.125) (layer "In2.Cu") (net 13))
  (segment (start 119.9 95.340314) (end 119.9 96.73641) (width 0.125) (layer "In2.Cu") (net 13))
  (segment (start 121.110925 96.833379) (end 121.143155 96.925486) (width 0.125) (layer "In2.Cu") (net 13))
  (segment (start 115.929927 97.008112) (end 115.981844 96.925486) (width 0.125) (layer "In2.Cu") (net 13))
  (segment (start 117.595072 97.008112) (end 117.664073 97.077113) (width 0.125) (layer "In2.Cu") (net 13))
  (segment (start 115.022159 96.376116) (end 115.048229 96.392498) (width 0.125) (layer "In2.Cu") (net 13))
  (segment (start 119.70284 95.216431) (end 119.731903 95.206262) (width 0.125) (layer "In2.Cu") (net 13))
  (segment (start 116.464073 97.077113) (end 116.546699 97.12903) (width 0.125) (layer "In2.Cu") (net 13))
  (segment (start 118.864073 97.077113) (end 118.946699 97.12903) (width 0.125) (layer "In2.Cu") (net 13))
  (segment (start 119.3783 97.12903) (end 119.460926 97.077113) (width 0.125) (layer "In2.Cu") (net 13))
  (segment (start 117.30284 95.266431) (end 117.331903 95.256262) (width 0.125) (layer "In2.Cu") (net 13))
  (segment (start 117.228447 95.359718) (end 117.238616 95.330655) (width 0.125) (layer "In2.Cu") (net 13))
  (segment (start 114.447892 96.5625) (end 114.647892 96.3625) (width 0.125) (layer "In2.Cu") (net 13))
  (segment (start 121.1 95.340314) (end 121.1 96.73641) (width 0.125) (layer "In2.Cu") (net 13))
  (segment (start 122.343155 96.115801) (end 122.395072 96.198427) (width 0.125) (layer "In2.Cu") (net 13))
  (segment (start 120.5783 97.12903) (end 120.660926 97.077113) (width 0.125) (layer "In2.Cu") (net 13))
  (segment (start 120.146699 97.12903) (end 120.238806 97.16126) (width 0.125) (layer "In2.Cu") (net 13))
  (segment (start 117.989224 97.172186) (end 118.086193 97.16126) (width 0.125) (layer "In2.Cu") (net 13))
  (segment (start 120.335775 97.172186) (end 120.389224 97.172186) (width 0.125) (layer "In2.Cu") (net 13))
  (segment (start 116.3 96.73641) (end 116.310925 96.833379) (width 0.125) (layer "In2.Cu") (net 13))
  (segment (start 116.395072 97.008112) (end 116.464073 97.077113) (width 0.125) (layer "In2.Cu") (net 13))
  (segment (start 121.264073 97.077113) (end 121.346699 97.12903) (width 0.125) (layer "In2.Cu") (net 13))
  (segment (start 119.135775 97.172186) (end 119.189224 97.172186) (width 0.125) (layer "In2.Cu") (net 13))
  (segment (start 121.589224 97.172186) (end 121.686193 97.16126) (width 0.125) (layer "In2.Cu") (net 13))
  (segment (start 122.193096 95.206262) (end 122.222159 95.216431) (width 0.125) (layer "In2.Cu") (net 13))
  (segment (start 118.47677 95.232813) (end 118.50284 95.216431) (width 0.125) (layer "In2.Cu") (net 13))
  (segment (start 120.660926 97.077113) (end 120.729927 97.008112) (width 0.125) (layer "In2.Cu") (net 13))
  (segment (start 119.822159 95.216431) (end 119.848229 95.232813) (width 0.125) (layer "In2.Cu") (net 13))
  (segment (start 107.8375 95.86731) (end 108.53269 96.5625) (width 0.125) (layer "In2.Cu") (net 13))
  (segment (start 119.654998 95.254585) (end 119.67677 95.232813) (width 0.125) (layer "In2.Cu") (net 13))
  (segment (start 119.886383 95.280655) (end 119.896552 95.309718) (width 0.125) (layer "In2.Cu") (net 13))
  (segment (start 120.486193 97.16126) (end 120.5783 97.12903) (width 0.125) (layer "In2.Cu") (net 13))
  (segment (start 116.789224 97.172186) (end 116.886193 97.16126) (width 0.125) (layer "In2.Cu") (net 13))
  (segment (start 117.664073 97.077113) (end 117.746699 97.12903) (width 0.125) (layer "In2.Cu") (net 13))
  (segment (start 116.286383 95.380655) (end 116.296552 95.409718) (width 0.125) (layer "In2.Cu") (net 13))
  (segment (start 117.129927 97.008112) (end 117.181844 96.925486) (width 0.125) (layer "In2.Cu") (net 13))
  (segment (start 121.048229 95.232813) (end 121.070001 95.254585) (width 0.125) (layer "In2.Cu") (net 13))
  (segment (start 118.622159 95.216431) (end 118.648229 95.232813) (width 0.125) (layer "In2.Cu") (net 13))
  (segment (start 119.943155 96.925486) (end 119.995072 97.008112) (width 0.125) (layer "In2.Cu") (net 13))
  (segment (start 116.735775 97.172186) (end 116.789224 97.172186) (width 0.125) (layer "In2.Cu") (net 13))
  (segment (start 118.1783 97.12903) (end 118.260926 97.077113) (width 0.125) (layer "In2.Cu") (net 13))
  (segment (start 117.393096 95.256262) (end 117.422159 95.266431) (width 0.125) (layer "In2.Cu") (net 13))
  (segment (start 122.395072 96.198427) (end 122.464073 96.267428) (width 0.125) (layer "In2.Cu") (net 13))
  (segment (start 116.296552 95.409718) (end 116.3 95.440314) (width 0.125) (layer "In2.Cu") (net 13))
  (segment (start 119.581844 96.925486) (end 119.614074 96.833379) (width 0.125) (layer "In2.Cu") (net 13))
  (segment (start 118.454998 95.254585) (end 118.47677 95.232813) (width 0.125) (layer "In2.Cu") (net 13))
  (segment (start 120.814074 96.833379) (end 120.825 96.73641) (width 0.125) (layer "In2.Cu") (net 13))
  (segment (start 118.648229 95.232813) (end 118.670001 95.254585) (width 0.125) (layer "In2.Cu") (net 13))
  (segment (start 121.860926 97.077113) (end 121.929927 97.008112) (width 0.125) (layer "In2.Cu") (net 13))
  (segment (start 115.264073 97.077113) (end 115.346699 97.12903) (width 0.125) (layer "In2.Cu") (net 13))
  (segment (start 116.07677 95.332813) (end 116.10284 95.316431) (width 0.125) (layer "In2.Cu") (net 13))
  (segment (start 116.028447 95.409718) (end 116.038616 95.380655) (width 0.125) (layer "In2.Cu") (net 13))
  (segment (start 120.90284 95.216431) (end 120.931903 95.206262) (width 0.125) (layer "In2.Cu") (net 13))
  (segment (start 118.686383 95.280655) (end 118.696552 95.309718) (width 0.125) (layer "In2.Cu") (net 13))
  (segment (start 122.270001 95.254585) (end 122.286383 95.280655) (width 0.125) (layer "In2.Cu") (net 13))
  (segment (start 121.535775 97.172186) (end 121.589224 97.172186) (width 0.125) (layer "In2.Cu") (net 13))
  (segment (start 115.110925 96.833379) (end 115.143155 96.925486) (width 0.125) (layer "In2.Cu") (net 13))
  (segment (start 114.9625 96.3625) (end 114.993096 96.365947) (width 0.125) (layer "In2.Cu") (net 13))
  (segment (start 120.729927 97.008112) (end 120.781844 96.925486) (width 0.125) (layer "In2.Cu") (net 13))
  (segment (start 119.189224 97.172186) (end 119.286193 97.16126) (width 0.125) (layer "In2.Cu") (net 13))
  (segment (start 121.096552 95.309718) (end 121.1 95.340314) (width 0.125) (layer "In2.Cu") (net 13))
  (segment (start 116.886193 97.16126) (end 116.9783 97.12903) (width 0.125) (layer "In2.Cu") (net 13))
  (segment (start 118.428447 95.309718) (end 118.438616 95.280655) (width 0.125) (layer "In2.Cu") (net 13))
  (segment (start 117.935775 97.172186) (end 117.989224 97.172186) (width 0.125) (layer "In2.Cu") (net 13))
  (segment (start 121.438806 97.16126) (end 121.535775 97.172186) (width 0.125) (layer "In2.Cu") (net 13))
  (segment (start 116.546699 97.12903) (end 116.638806 97.16126) (width 0.125) (layer "In2.Cu") (net 13))
  (segment (start 115.1 96.73641) (end 115.110925 96.833379) (width 0.125) (layer "In2.Cu") (net 13))
  (segment (start 121.022159 95.216431) (end 121.048229 95.232813) (width 0.125) (layer "In2.Cu") (net 13))
  (segment (start 116.131903 95.306262) (end 116.1625 95.302814) (width 0.125) (layer "In2.Cu") (net 13))
  (segment (start 119.731903 95.206262) (end 119.7625 95.202814) (width 0.125) (layer "In2.Cu") (net 13))
  (segment (start 122.310925 96.023694) (end 122.343155 96.115801) (width 0.125) (layer "In2.Cu") (net 13))
  (segment (start 119.625 95.340314) (end 119.628447 95.309718) (width 0.125) (layer "In2.Cu") (net 13))
  (segment (start 115.1 96.5) (end 115.1 96.73641) (width 0.125) (layer "In2.Cu") (net 13))
  (segment (start 123.61731 96.3625) (end 127.6625 92.31731) (width 0.125) (layer "In2.Cu") (net 13))
  (segment (start 115.195072 97.008112) (end 115.264073 97.077113) (width 0.125) (layer "In2.Cu") (net 13))
  (segment (start 118.50284 95.216431) (end 118.531903 95.206262) (width 0.125) (layer "In2.Cu") (net 13))
  (segment (start 119.896552 95.309718) (end 119.9 95.340314) (width 0.125) (layer "In2.Cu") (net 13))
  (segment (start 118.670001 95.254585) (end 118.686383 95.280655) (width 0.125) (layer "In2.Cu") (net 13))
  (segment (start 119.870001 95.254585) (end 119.886383 95.280655) (width 0.125) (layer "In2.Cu") (net 13))
  (segment (start 117.448229 95.282813) (end 117.470001 95.304585) (width 0.125) (layer "In2.Cu") (net 13))
  (segment (start 116.025 95.440314) (end 116.028447 95.409718) (width 0.125) (layer "In2.Cu") (net 13))
  (segment (start 115.143155 96.925486) (end 115.195072 97.008112) (width 0.125) (layer "In2.Cu") (net 13))
  (segment (start 118.593096 95.206262) (end 118.622159 95.216431) (width 0.125) (layer "In2.Cu") (net 13))
  (segment (start 122.286383 95.280655) (end 122.296552 95.309718) (width 0.125) (layer "In2.Cu") (net 13))
  (segment (start 115.589224 97.172186) (end 115.686193 97.16126) (width 0.125) (layer "In2.Cu") (net 13))
  (segment (start 121.7783 97.12903) (end 121.860926 97.077113) (width 0.125) (layer "In2.Cu") (net 13))
  (segment (start 120.825 95.340314) (end 120.828447 95.309718) (width 0.125) (layer "In2.Cu") (net 13))
  (segment (start 120.064073 97.077113) (end 120.146699 97.12903) (width 0.125) (layer "In2.Cu") (net 13))
  (segment (start 116.10284 95.316431) (end 116.131903 95.306262) (width 0.125) (layer "In2.Cu") (net 13))
  (segment (start 122.1625 95.202814) (end 122.193096 95.206262) (width 0.125) (layer "In2.Cu") (net 13))
  (segment (start 114.647892 96.3625) (end 114.9625 96.3625) (width 0.125) (layer "In2.Cu") (net 13))
  (segment (start 118.7 96.73641) (end 118.710925 96.833379) (width 0.125) (layer "In2.Cu") (net 13))
  (segment (start 121.686193 97.16126) (end 121.7783 97.12903) (width 0.125) (layer "In2.Cu") (net 13))
  (segment (start 118.438616 95.280655) (end 118.454998 95.254585) (width 0.125) (layer "In2.Cu") (net 13))
  (segment (start 116.343155 96.925486) (end 116.395072 97.008112) (width 0.125) (layer "In2.Cu") (net 13))
  (segment (start 116.248229 95.332813) (end 116.270001 95.354585) (width 0.125) (layer "In2.Cu") (net 13))
  (segment (start 115.096552 96.469403) (end 115.1 96.5) (width 0.125) (layer "In2.Cu") (net 13))
  (segment (start 116.3 95.440314) (end 116.3 96.73641) (width 0.125) (layer "In2.Cu") (net 13))
  (segment (start 115.438806 97.16126) (end 115.535775 97.172186) (width 0.125) (layer "In2.Cu") (net 13))
  (segment (start 117.225 95.390314) (end 117.228447 95.359718) (width 0.125) (layer "In2.Cu") (net 13))
  (segment (start 119.625 96.73641) (end 119.625 95.340314) (width 0.125) (layer "In2.Cu") (net 13))
  (segment (start 120.993096 95.206262) (end 121.022159 95.216431) (width 0.125) (layer "In2.Cu") (net 13))
  (segment (start 127.6625 92.31731) (end 127.6625 85.4) (width 0.125) (layer "In2.Cu") (net 13))
  (segment (start 122.028447 95.309718) (end 122.038616 95.280655) (width 0.125) (layer "In2.Cu") (net 13))
  (segment (start 119.995072 97.008112) (end 120.064073 97.077113) (width 0.125) (layer "In2.Cu") (net 13))
  (segment (start 118.425 96.73641) (end 118.425 95.340314) (width 0.125) (layer "In2.Cu") (net 13))
  (segment (start 122.025 96.73641) (end 122.025 95.340314) (width 0.125) (layer "In2.Cu") (net 13))
  (segment (start 118.795072 97.008112) (end 118.864073 97.077113) (width 0.125) (layer "In2.Cu") (net 13))
  (segment (start 108.53269 96.5625) (end 114.447892 96.5625) (width 0.125) (layer "In2.Cu") (net 13))
  (segment (start 115.981844 96.925486) (end 116.014074 96.833379) (width 0.125) (layer "In2.Cu") (net 13))
  (segment (start 122.131903 95.206262) (end 122.1625 95.202814) (width 0.125) (layer "In2.Cu") (net 13))
  (segment (start 118.743155 96.925486) (end 118.795072 97.008112) (width 0.125) (layer "In2.Cu") (net 13))
  (segment (start 117.746699 97.12903) (end 117.838806 97.16126) (width 0.125) (layer "In2.Cu") (net 13))
  (segment (start 120.87677 95.232813) (end 120.90284 95.216431) (width 0.125) (layer "In2.Cu") (net 13))
  (segment (start 119.910925 96.833379) (end 119.943155 96.925486) (width 0.125) (layer "In2.Cu") (net 13))
  (segment (start 107.125 94.701777) (end 106.906327 94.92045) (width 0.125) (layer "B.Cu") (net 13))
  (segment (start 107.125 94.290001) (end 107.125 94.701777) (width 0.125) (layer "B.Cu") (net 13))
  (segment (start 107.24 94.175001) (end 107.125 94.290001) (width 0.125) (layer "B.Cu") (net 13))
  (segment (start 107.24 93.95) (end 107.24 94.175001) (width 0.125) (layer "B.Cu") (net 13))
  (segment (start 106.906327 94.92045) (end 106.906327 95.256327) (width 0.125) (layer "B.Cu") (net 13))
  (segment (start 106.25 83.45) (end 106.25 85.35) (width 0.15) (layer "F.Cu") (net 14))
  (segment (start 106.6 85.7) (end 108.15 85.7) (width 0.15) (layer "F.Cu") (net 14))
  (segment (start 106.25 85.35) (end 106.6 85.7) (width 0.15) (layer "F.Cu") (net 14))
  (via (at 108.15 85.7) (size 0.6) (drill 0.25) (layers "F.Cu" "B.Cu") (net 14))
  (segment (start 106.4 96.6) (end 106.2 96.8) (width 0.125) (layer "B.Cu") (net 14))
  (segment (start 107.67046 96.32954) (end 107.4 96.6) (width 0.125) (layer "B.Cu") (net 14))
  (segment (start 108.25 85.8) (end 108.15 85.7) (width 0.15) (layer "B.Cu") (net 14))
  (segment (start 108.25 86.9) (end 108.25 88.25) (width 0.125) (layer "B.Cu") (net 14))
  (segment (start 107.67046 88.82954) (end 107.67046 96.32954) (width 0.125) (layer "B.Cu") (net 14))
  (segment (start 108.25 86.9) (end 108.25 85.8) (width 0.15) (layer "B.Cu") (net 14))
  (segment (start 108.25 88.25) (end 107.67046 88.82954) (width 0.125) (layer "B.Cu") (net 14))
  (segment (start 107.4 96.6) (end 106.4 96.6) (width 0.125) (layer "B.Cu") (net 14))
  (segment (start 106.2 96.8) (end 106.2 97.2508) (width 0.125) (layer "B.Cu") (net 14))
  (segment (start 109.4 85.7) (end 108.9 85.7) (width 0.15) (layer "F.Cu") (net 15))
  (segment (start 109.75 83.45) (end 109.75 85.35) (width 0.15) (layer "F.Cu") (net 15))
  (segment (start 109.75 85.35) (end 109.4 85.7) (width 0.15) (layer "F.Cu") (net 15))
  (via (at 108.9 85.7) (size 0.6) (drill 0.25) (layers "F.Cu" "B.Cu") (net 15))
  (segment (start 107.962469 96.888331) (end 107.962469 88.937531) (width 0.125) (layer "B.Cu") (net 15))
  (segment (start 108.518741 87.865193) (end 108.75 87.633936) (width 0.125) (layer "B.Cu") (net 15))
  (segment (start 108.75 86.9) (end 108.75 85.85) (width 0.15) (layer "B.Cu") (net 15))
  (segment (start 108.75 87.633936) (end 108.75 86.9) (width 0.125) (layer "B.Cu") (net 15))
  (segment (start 108.518741 88.381259) (end 108.518741 87.865193) (width 0.125) (layer "B.Cu") (net 15))
  (segment (start 107.962469 88.937531) (end 108.518741 88.381259) (width 0.125) (layer "B.Cu") (net 15))
  (segment (start 107.6 97.2508) (end 107.962469 96.888331) (width 0.125) (layer "B.Cu") (net 15))
  (segment (start 108.75 85.85) (end 108.9 85.7) (width 0.15) (layer "B.Cu") (net 15))
  (segment (start 104.75 85.4) (end 104.5 85.65) (width 0.15) (layer "F.Cu") (net 16))
  (segment (start 104.75 83.45) (end 104.75 85.4) (width 0.15) (layer "F.Cu") (net 16))
  (via (at 104.5 85.65) (size 0.6) (drill 0.25) (layers "F.Cu" "B.Cu") (net 16))
  (segment (start 109 97.2508) (end 108.5508 97.2508) (width 0.125) (layer "B.Cu") (net 16))
  (segment (start 109.25 86.9) (end 109.25 86.090002) (width 0.15) (layer "B.Cu") (net 16))
  (segment (start 104.7 85) (end 104.5 85.2) (width 0.15) (layer "B.Cu") (net 16))
  (segment (start 108.5508 97.2508) (end 108.212479 96.912479) (width 0.125) (layer "B.Cu") (net 16))
  (segment (start 109.400001 85.940001) (end 109.400001 85.459999) (width 0.15) (layer "B.Cu") (net 16))
  (segment (start 109.25 87.487502) (end 109.25 86.9) (width 0.125) (layer "B.Cu") (net 16))
  (segment (start 108.940002 85) (end 104.7 85) (width 0.15) (layer "B.Cu") (net 16))
  (segment (start 108.768751 87.968751) (end 109.25 87.487502) (width 0.125) (layer "B.Cu") (net 16))
  (segment (start 109.25 86.090002) (end 109.400001 85.940001) (width 0.15) (layer "B.Cu") (net 16))
  (segment (start 108.768751 88.531249) (end 108.768751 87.968751) (width 0.125) (layer "B.Cu") (net 16))
  (segment (start 104.5 85.2) (end 104.5 85.65) (width 0.15) (layer "B.Cu") (net 16))
  (segment (start 108.212479 96.912479) (end 108.212479 89.087521) (width 0.125) (layer "B.Cu") (net 16))
  (segment (start 108.212479 89.087521) (end 108.768751 88.531249) (width 0.125) (layer "B.Cu") (net 16))
  (segment (start 109.400001 85.459999) (end 108.940002 85) (width 0.15) (layer "B.Cu") (net 16))
  (segment (start 125.750001 83.449998) (end 125.750001 84.650149) (width 0.125) (layer "F.Cu") (net 17))
  (segment (start 125.750001 84.650149) (end 125.875001 84.775149) (width 0.125) (layer "F.Cu") (net 17))
  (segment (start 125.875 84.9625) (end 125.6375 85.2) (width 0.125) (layer "F.Cu") (net 17))
  (segment (start 125.875001 84.775149) (end 125.875 84.9625) (width 0.125) (layer "F.Cu") (net 17))
  (via (at 125.6375 85.2) (size 0.6) (drill 0.25) (layers "F.Cu" "B.Cu") (net 17))
  (via (at 92.7625 96) (size 0.6) (drill 0.25) (layers "F.Cu" "B.Cu") (net 17))
  (segment (start 91.930691 90.8) (end 92.126724 90.8) (width 0.125) (layer "In2.Cu") (net 17))
  (segment (start 91.796638 90.693096) (end 91.806807 90.722159) (width 0.125) (layer "In2.Cu") (net 17))
  (segment (start 91.823189 90.57677) (end 91.806807 90.60284) (width 0.125) (layer "In2.Cu") (net 17))
  (segment (start 92.3158 90.481844) (end 92.223693 90.514074) (width 0.125) (layer "In2.Cu") (net 17))
  (segment (start 94.06731 83.1625) (end 93.1625 84.06731) (width 0.125) (layer "In2.Cu") (net 17))
  (segment (start 125.8375 84.06731) (end 124.93269 83.1625) (width 0.125) (layer "In2.Cu") (net 17))
  (segment (start 92.3158 90.843155) (end 92.398426 90.895072) (width 0.125) (layer "In2.Cu") (net 17))
  (segment (start 92.5625 87.31731) (end 92.5625 90.089224) (width 0.125) (layer "In2.Cu") (net 17))
  (segment (start 91.844961 90.770001) (end 91.871031 90.786383) (width 0.125) (layer "In2.Cu") (net 17))
  (segment (start 92.223693 90.514074) (end 92.126724 90.525) (width 0.125) (layer "In2.Cu") (net 17))
  (segment (start 92.126724 90.525) (end 91.930691 90.525) (width 0.125) (layer "In2.Cu") (net 17))
  (segment (start 91.900094 90.796552) (end 91.930691 90.8) (width 0.125) (layer "In2.Cu") (net 17))
  (segment (start 92.398426 90.895072) (end 92.467427 90.964073) (width 0.125) (layer "In2.Cu") (net 17))
  (segment (start 92.126724 90.8) (end 92.223693 90.810925) (width 0.125) (layer "In2.Cu") (net 17))
  (segment (start 91.900094 90.528447) (end 91.871031 90.538616) (width 0.125) (layer "In2.Cu") (net 17))
  (segment (start 91.930691 90.525) (end 91.900094 90.528447) (width 0.125) (layer "In2.Cu") (net 17))
  (segment (start 91.793191 90.6625) (end 91.796638 90.693096) (width 0.125) (layer "In2.Cu") (net 17))
  (segment (start 92.519344 91.046699) (end 92.551574 91.138806) (width 0.125) (layer "In2.Cu") (net 17))
  (segment (start 91.871031 90.786383) (end 91.900094 90.796552) (width 0.125) (layer "In2.Cu") (net 17))
  (segment (start 91.871031 90.538616) (end 91.844961 90.554998) (width 0.125) (layer "In2.Cu") (net 17))
  (segment (start 92.5625 95.8) (end 92.7625 96) (width 0.125) (layer "In2.Cu") (net 17))
  (segment (start 93.1625 84.06731) (end 93.1625 86.71731) (width 0.125) (layer "In2.Cu") (net 17))
  (segment (start 91.796638 90.631903) (end 91.793191 90.6625) (width 0.125) (layer "In2.Cu") (net 17))
  (segment (start 92.519344 90.2783) (end 92.467427 90.360926) (width 0.125) (layer "In2.Cu") (net 17))
  (segment (start 92.5625 90.089224) (end 92.551574 90.186193) (width 0.125) (layer "In2.Cu") (net 17))
  (segment (start 91.806807 90.60284) (end 91.796638 90.631903) (width 0.125) (layer "In2.Cu") (net 17))
  (segment (start 125.8375 85) (end 125.8375 84.06731) (width 0.125) (layer "In2.Cu") (net 17))
  (segment (start 91.806807 90.722159) (end 91.823189 90.748229) (width 0.125) (layer "In2.Cu") (net 17))
  (segment (start 91.844961 90.554998) (end 91.823189 90.57677) (width 0.125) (layer "In2.Cu") (net 17))
  (segment (start 93.1625 86.71731) (end 92.5625 87.31731) (width 0.125) (layer "In2.Cu") (net 17))
  (segment (start 92.398426 90.429927) (end 92.3158 90.481844) (width 0.125) (layer "In2.Cu") (net 17))
  (segment (start 92.551574 90.186193) (end 92.519344 90.2783) (width 0.125) (layer "In2.Cu") (net 17))
  (segment (start 91.823189 90.748229) (end 91.844961 90.770001) (width 0.125) (layer "In2.Cu") (net 17))
  (segment (start 92.5625 91.235775) (end 92.5625 95.8) (width 0.125) (layer "In2.Cu") (net 17))
  (segment (start 124.93269 83.1625) (end 94.06731 83.1625) (width 0.125) (layer "In2.Cu") (net 17))
  (segment (start 92.551574 91.138806) (end 92.5625 91.235775) (width 0.125) (layer "In2.Cu") (net 17))
  (segment (start 125.6375 85.2) (end 125.8375 85) (width 0.125) (layer "In2.Cu") (net 17))
  (segment (start 92.223693 90.810925) (end 92.3158 90.843155) (width 0.125) (layer "In2.Cu") (net 17))
  (segment (start 92.467427 90.964073) (end 92.519344 91.046699) (width 0.125) (layer "In2.Cu") (net 17))
  (segment (start 92.467427 90.360926) (end 92.398426 90.429927) (width 0.125) (layer "In2.Cu") (net 17))
  (segment (start 92.525 94.290001) (end 92.525 95.7625) (width 0.125) (layer "B.Cu") (net 17))
  (segment (start 92.64 94.175001) (end 92.525 94.290001) (width 0.125) (layer "B.Cu") (net 17))
  (segment (start 92.64 93.95) (end 92.64 94.175001) (width 0.125) (layer "B.Cu") (net 17))
  (segment (start 92.525 95.7625) (end 92.7625 96) (width 0.125) (layer "B.Cu") (net 17))
  (segment (start 126.25 84.650149) (end 126.125 84.775149) (width 0.125) (layer "F.Cu") (net 18))
  (segment (start 126.125 84.775149) (end 126.125 84.9625) (width 0.125) (layer "F.Cu") (net 18))
  (segment (start 126.25 83.449998) (end 126.25 84.650149) (width 0.125) (layer "F.Cu") (net 18))
  (segment (start 126.125 84.9625) (end 126.3625 85.2) (width 0.125) (layer "F.Cu") (net 18))
  (via (at 126.3625 85.2) (size 0.6) (drill 0.25) (layers "F.Cu" "B.Cu") (net 18))
  (via (at 92.0375 96) (size 0.6) (drill 0.25) (layers "F.Cu" "B.Cu") (net 18))
  (segment (start 92.159659 91.138616) (end 92.185729 91.154998) (width 0.125) (layer "In2.Cu") (net 18))
  (segment (start 91.806997 91.114074) (end 91.903966 91.125) (width 0.125) (layer "In2.Cu") (net 18))
  (segment (start 91.511346 90.446699) (end 91.479116 90.538806) (width 0.125) (layer "In2.Cu") (net 18))
  (segment (start 92.8375 86.58269) (end 92.2375 87.18269) (width 0.125) (layer "In2.Cu") (net 18))
  (segment (start 92.2375 87.18269) (end 92.2375 90.0625) (width 0.125) (layer "In2.Cu") (net 18))
  (segment (start 92.185729 90.170001) (end 92.159659 90.186383) (width 0.125) (layer "In2.Cu") (net 18))
  (segment (start 91.903966 90.2) (end 91.806997 90.210925) (width 0.125) (layer "In2.Cu") (net 18))
  (segment (start 91.563263 90.960926) (end 91.632264 91.029927) (width 0.125) (layer "In2.Cu") (net 18))
  (segment (start 92.207501 90.148229) (end 92.185729 90.170001) (width 0.125) (layer "In2.Cu") (net 18))
  (segment (start 92.185729 91.154998) (end 92.207501 91.17677) (width 0.125) (layer "In2.Cu") (net 18))
  (segment (start 91.903966 91.125) (end 92.1 91.125) (width 0.125) (layer "In2.Cu") (net 18))
  (segment (start 92.2375 90.0625) (end 92.234052 90.093096) (width 0.125) (layer "In2.Cu") (net 18))
  (segment (start 92.207501 91.17677) (end 92.223883 91.20284) (width 0.125) (layer "In2.Cu") (net 18))
  (segment (start 92.1 90.2) (end 91.903966 90.2) (width 0.125) (layer "In2.Cu") (net 18))
  (segment (start 91.479116 90.786193) (end 91.511346 90.8783) (width 0.125) (layer "In2.Cu") (net 18))
  (segment (start 92.234052 91.231903) (end 92.2375 91.2625) (width 0.125) (layer "In2.Cu") (net 18))
  (segment (start 93.93269 82.8375) (end 92.8375 83.93269) (width 0.125) (layer "In2.Cu") (net 18))
  (segment (start 125.06731 82.8375) (end 93.93269 82.8375) (width 0.125) (layer "In2.Cu") (net 18))
  (segment (start 92.159659 90.186383) (end 92.130596 90.196552) (width 0.125) (layer "In2.Cu") (net 18))
  (segment (start 91.468191 90.635775) (end 91.468191 90.689224) (width 0.125) (layer "In2.Cu") (net 18))
  (segment (start 92.223883 90.122159) (end 92.207501 90.148229) (width 0.125) (layer "In2.Cu") (net 18))
  (segment (start 126.1625 83.93269) (end 125.06731 82.8375) (width 0.125) (layer "In2.Cu") (net 18))
  (segment (start 92.8375 83.93269) (end 92.8375 86.58269) (width 0.125) (layer "In2.Cu") (net 18))
  (segment (start 92.130596 90.196552) (end 92.1 90.2) (width 0.125) (layer "In2.Cu") (net 18))
  (segment (start 92.234052 90.093096) (end 92.223883 90.122159) (width 0.125) (layer "In2.Cu") (net 18))
  (segment (start 91.468191 90.689224) (end 91.479116 90.786193) (width 0.125) (layer "In2.Cu") (net 18))
  (segment (start 92.223883 91.20284) (end 92.234052 91.231903) (width 0.125) (layer "In2.Cu") (net 18))
  (segment (start 91.479116 90.538806) (end 91.468191 90.635775) (width 0.125) (layer "In2.Cu") (net 18))
  (segment (start 91.632264 90.295072) (end 91.563263 90.364073) (width 0.125) (layer "In2.Cu") (net 18))
  (segment (start 91.632264 91.029927) (end 91.71489 91.081844) (width 0.125) (layer "In2.Cu") (net 18))
  (segment (start 91.563263 90.364073) (end 91.511346 90.446699) (width 0.125) (layer "In2.Cu") (net 18))
  (segment (start 126.3625 85.2) (end 126.1625 85) (width 0.125) (layer "In2.Cu") (net 18))
  (segment (start 92.1 91.125) (end 92.130596 91.128447) (width 0.125) (layer "In2.Cu") (net 18))
  (segment (start 126.1625 85) (end 126.1625 83.93269) (width 0.125) (layer "In2.Cu") (net 18))
  (segment (start 91.71489 90.243155) (end 91.632264 90.295072) (width 0.125) (layer "In2.Cu") (net 18))
  (segment (start 92.130596 91.128447) (end 92.159659 91.138616) (width 0.125) (layer "In2.Cu") (net 18))
  (segment (start 92.2375 91.2625) (end 92.2375 95.8) (width 0.125) (layer "In2.Cu") (net 18))
  (segment (start 91.511346 90.8783) (end 91.563263 90.960926) (width 0.125) (layer "In2.Cu") (net 18))
  (segment (start 92.2375 95.8) (end 92.0375 96) (width 0.125) (layer "In2.Cu") (net 18))
  (segment (start 91.806997 90.210925) (end 91.71489 90.243155) (width 0.125) (layer "In2.Cu") (net 18))
  (segment (start 91.71489 91.081844) (end 91.806997 91.114074) (width 0.125) (layer "In2.Cu") (net 18))
  (segment (start 92.275 95.7625) (end 92.0375 96) (width 0.125) (layer "B.Cu") (net 18))
  (segment (start 92.16 94.175001) (end 92.275 94.290001) (width 0.125) (layer "B.Cu") (net 18))
  (segment (start 92.275 94.290001) (end 92.275 95.7625) (width 0.125) (layer "B.Cu") (net 18))
  (segment (start 92.16 93.95) (end 92.16 94.175001) (width 0.125) (layer "B.Cu") (net 18))
  (segment (start 124.625 86.151778) (end 123.725 87.051778) (width 0.125) (layer "F.Cu") (net 19))
  (segment (start 124.548222 87.875) (end 124.816195 87.607027) (width 0.125) (layer "F.Cu") (net 19))
  (segment (start 123.725 87.051778) (end 123.725 87.548222) (width 0.125) (layer "F.Cu") (net 19))
  (segment (start 124.75 84.650001) (end 124.625 84.775001) (width 0.125) (layer "F.Cu") (net 19))
  (segment (start 124.816195 87.607027) (end 124.816195 87.275166) (width 0.125) (layer "F.Cu") (net 19))
  (segment (start 124.625 84.775001) (end 124.625 86.151778) (width 0.125) (layer "F.Cu") (net 19))
  (segment (start 124.816195 87.275166) (end 124.578695 87.037666) (width 0.125) (layer "F.Cu") (net 19))
  (segment (start 123.725 87.548222) (end 124.051778 87.875) (width 0.125) (layer "F.Cu") (net 19))
  (segment (start 124.75 83.45) (end 124.75 84.650001) (width 0.125) (layer "F.Cu") (net 19))
  (segment (start 124.051778 87.875) (end 124.548222 87.875) (width 0.125) (layer "F.Cu") (net 19))
  (via (at 94.0625 95) (size 0.6) (drill 0.25) (layers "F.Cu" "B.Cu") (net 19))
  (via (at 124.578695 87.037666) (size 0.6) (drill 0.25) (layers "F.Cu" "B.Cu") (net 19))
  (segment (start 93.8625 87.86731) (end 94.1625 87.56731) (width 0.125) (layer "In2.Cu") (net 19))
  (segment (start 124.778695 86.837666) (end 124.578695 87.037666) (width 0.125) (layer "In2.Cu") (net 19))
  (segment (start 93.8625 94.8) (end 93.8625 87.86731) (width 0.125) (layer "In2.Cu") (net 19))
  (segment (start 94.1625 85.06731) (end 95.06731 84.1625) (width 0.125) (layer "In2.Cu") (net 19))
  (segment (start 94.1625 87.56731) (end 94.1625 85.06731) (width 0.125) (layer "In2.Cu") (net 19))
  (segment (start 123.93269 84.1625) (end 124.778695 85.008505) (width 0.125) (layer "In2.Cu") (net 19))
  (segment (start 94.0625 95) (end 93.8625 94.8) (width 0.125) (layer "In2.Cu") (net 19))
  (segment (start 124.778695 85.008505) (end 124.778695 86.837666) (width 0.125) (layer "In2.Cu") (net 19))
  (segment (start 95.06731 84.1625) (end 123.93269 84.1625) (width 0.125) (layer "In2.Cu") (net 19))
  (segment (start 93.825 94.7625) (end 94.0625 95) (width 0.125) (layer "B.Cu") (net 19))
  (segment (start 93.94 94.175001) (end 93.825 94.290001) (width 0.125) (layer "B.Cu") (net 19))
  (segment (start 93.94 93.95) (end 93.94 94.175001) (width 0.125) (layer "B.Cu") (net 19))
  (segment (start 93.825 94.290001) (end 93.825 94.7625) (width 0.125) (layer "B.Cu") (net 19))
  (segment (start 123.948222 88.125) (end 124.651778 88.125) (width 0.125) (layer "F.Cu") (net 20))
  (segment (start 124.25 84.650001) (end 124.375 84.775001) (width 0.125) (layer "F.Cu") (net 20))
  (segment (start 124.375 84.775001) (end 124.375 86.048222) (width 0.125) (layer "F.Cu") (net 20))
  (segment (start 123.475 87.651778) (end 123.948222 88.125) (width 0.125) (layer "F.Cu") (net 20))
  (segment (start 123.475 86.948222) (end 123.475 87.651778) (width 0.125) (layer "F.Cu") (net 20))
  (segment (start 125.066195 87.275166) (end 125.303695 87.037666) (width 0.125) (layer "F.Cu") (net 20))
  (segment (start 124.25 83.45) (end 124.25 84.650001) (width 0.125) (layer "F.Cu") (net 20))
  (segment (start 125.066195 87.710583) (end 125.066195 87.275166) (width 0.125) (layer "F.Cu") (net 20))
  (segment (start 124.375 86.048222) (end 123.475 86.948222) (width 0.125) (layer "F.Cu") (net 20))
  (segment (start 124.651778 88.125) (end 125.066195 87.710583) (width 0.125) (layer "F.Cu") (net 20))
  (via (at 93.3375 95) (size 0.6) (drill 0.25) (layers "F.Cu" "B.Cu") (net 20))
  (via (at 125.303695 87.037666) (size 0.6) (drill 0.25) (layers "F.Cu" "B.Cu") (net 20))
  (segment (start 94.93269 83.8375) (end 124.06731 83.8375) (width 0.125) (layer "In2.Cu") (net 20))
  (segment (start 93.5375 87.73269) (end 93.8375 87.43269) (width 0.125) (layer "In2.Cu") (net 20))
  (segment (start 124.06731 83.8375) (end 125.103695 84.873885) (width 0.125) (layer "In2.Cu") (net 20))
  (segment (start 93.5375 94.8) (end 93.5375 87.73269) (width 0.125) (layer "In2.Cu") (net 20))
  (segment (start 125.103695 86.837666) (end 125.303695 87.037666) (width 0.125) (layer "In2.Cu") (net 20))
  (segment (start 93.8375 87.43269) (end 93.8375 84.93269) (width 0.125) (layer "In2.Cu") (net 20))
  (segment (start 93.3375 95) (end 93.5375 94.8) (width 0.125) (layer "In2.Cu") (net 20))
  (segment (start 93.8375 84.93269) (end 94.93269 83.8375) (width 0.125) (layer "In2.Cu") (net 20))
  (segment (start 125.103695 84.873885) (end 125.103695 86.837666) (width 0.125) (layer "In2.Cu") (net 20))
  (segment (start 93.46 93.95) (end 93.46 94.175001) (width 0.125) (layer "B.Cu") (net 20))
  (segment (start 93.46 94.175001) (end 93.575 94.290001) (width 0.125) (layer "B.Cu") (net 20))
  (segment (start 93.575 94.290001) (end 93.575 94.7625) (width 0.125) (layer "B.Cu") (net 20))
  (segment (start 93.575 94.7625) (end 93.3375 95) (width 0.125) (layer "B.Cu") (net 20))
  (segment (start 122.75 83.45) (end 122.75 84.650001) (width 0.125) (layer "F.Cu") (net 21))
  (segment (start 122.875 84.775001) (end 122.875 85.851777) (width 0.125) (layer "F.Cu") (net 21))
  (segment (start 122.75 84.650001) (end 122.875 84.775001) (width 0.125) (layer "F.Cu") (net 21))
  (segment (start 122.875 85.851777) (end 123.043673 86.02045) (width 0.125) (layer "F.Cu") (net 21))
  (segment (start 123.043673 86.02045) (end 123.043673 86.356327) (width 0.125) (layer "F.Cu") (net 21))
  (via (at 95.3625 96) (size 0.6) (drill 0.25) (layers "F.Cu" "B.Cu") (net 21))
  (via (at 123.043673 86.356327) (size 0.6) (drill 0.25) (layers "F.Cu" "B.Cu") (net 21))
  (segment (start 94.537467 91.95282) (end 94.5625 91.95) (width 0.125) (layer "In2.Cu") (net 21))
  (segment (start 95.165947 87.606903) (end 95.176116 87.57784) (width 0.125) (layer "In2.Cu") (net 21))
  (segment (start 94.537467 92.222179) (end 94.513689 92.213858) (width 0.125) (layer "In2.Cu") (net 21))
  (segment (start 94.474544 90.792357) (end 94.492358 90.774543) (width 0.125) (layer "In2.Cu") (net 21))
  (segment (start 95.3 86.575) (end 95.269403 86.571552) (width 0.125) (layer "In2.Cu") (net 21))
  (segment (start 95.275 94.35) (end 95.46278 94.35) (width 0.125) (layer "In2.Cu") (net 21))
  (segment (start 95.1625 85.56731) (end 95.56731 85.1625) (width 0.125) (layer "In2.Cu") (net 21))
  (segment (start 95.880922 86.739073) (end 95.811921 86.670072) (width 0.125) (layer "In2.Cu") (net 21))
  (segment (start 95.729295 86.618155) (end 95.637188 86.585925) (width 0.125) (layer "In2.Cu") (net 21))
  (segment (start 94.45 93.2625) (end 94.452821 93.237466) (width 0.125) (layer "In2.Cu") (net 21))
  (segment (start 95.554507 93.139664) (end 95.641635 93.109177) (width 0.125) (layer "In2.Cu") (net 21))
  (segment (start 95.554507 91.035335) (end 95.46278 91.025) (width 0.125) (layer "In2.Cu") (net 21))
  (segment (start 95.637188 86.585925) (end 95.540219 86.575) (width 0.125) (layer "In2.Cu") (net 21))
  (segment (start 95.187043 94.392357) (end 95.204857 94.374543) (width 0.125) (layer "In2.Cu") (net 21))
  (segment (start 95.1625 94.4625) (end 95.16532 94.437466) (width 0.125) (layer "In2.Cu") (net 21))
  (segment (start 95.641635 93.465822) (end 95.554507 93.435335) (width 0.125) (layer "In2.Cu") (net 21))
  (segment (start 94.5625 93.425) (end 94.537467 93.422179) (width 0.125) (layer "In2.Cu") (net 21))
  (segment (start 95.834177 92.916635) (end 95.864664 92.829507) (width 0.125) (layer "In2.Cu") (net 21))
  (segment (start 95.46278 91.025) (end 94.5625 91.025) (width 0.125) (layer "In2.Cu") (net 21))
  (segment (start 94.5625 92.225) (end 94.537467 92.222179) (width 0.125) (layer "In2.Cu") (net 21))
  (segment (start 94.537467 91.022179) (end 94.513689 91.013858) (width 0.125) (layer "In2.Cu") (net 21))
  (segment (start 95.785066 94.194795) (end 95.834177 94.116635) (width 0.125) (layer "In2.Cu") (net 21))
  (segment (start 94.537467 93.422179) (end 94.513689 93.413858) (width 0.125) (layer "In2.Cu") (net 21))
  (segment (start 95.880922 87.335926) (end 95.932839 87.2533) (width 0.125) (layer "In2.Cu") (net 21))
  (segment (start 94.45 93.3125) (end 94.45 93.2625) (width 0.125) (layer "In2.Cu") (net 21))
  (segment (start 95.834177 92.458364) (end 95.785066 92.380204) (width 0.125) (layer "In2.Cu") (net 21))
  (segment (start 94.45 90.9125) (end 94.45 90.8625) (width 0.125) (layer "In2.Cu") (net 21))
  (segment (start 95.875 93.837219) (end 95.864664 93.745492) (width 0.125) (layer "In2.Cu") (net 21))
  (segment (start 95.719795 93.060066) (end 95.785066 92.994795) (width 0.125) (layer "In2.Cu") (net 21))
  (segment (start 95.864664 91.345492) (end 95.834177 91.258364) (width 0.125) (layer "In2.Cu") (net 21))
  (segment (start 94.492358 91.000456) (end 94.474544 90.982642) (width 0.125) (layer "In2.Cu") (net 21))
  (segment (start 95.641635 91.065822) (end 95.554507 91.035335) (width 0.125) (layer "In2.Cu") (net 21))
  (segment (start 95.932839 87.2533) (end 95.965069 87.161193) (width 0.125) (layer "In2.Cu") (net 21))
  (segment (start 122.8375 85.511549) (end 122.8375 85.86731) (width 0.125) (layer "In2.Cu") (net 21))
  (segment (start 94.513689 90.761141) (end 94.537467 90.75282) (width 0.125) (layer "In2.Cu") (net 21))
  (segment (start 95.24034 87.513616) (end 95.269403 87.503447) (width 0.125) (layer "In2.Cu") (net 21))
  (segment (start 95.204857 94.374543) (end 95.226188 94.361141) (width 0.125) (layer "In2.Cu") (net 21))
  (segment (start 95.46278 92.225) (end 94.5625 92.225) (width 0.125) (layer "In2.Cu") (net 21))
  (segment (start 95.719795 92.314933) (end 95.641635 92.265822) (width 0.125) (layer "In2.Cu") (net 21))
  (segment (start 95.875 92.73778) (end 95.875 92.637219) (width 0.125) (layer "In2.Cu") (net 21))
  (segment (start 94.537467 93.15282) (end 94.5625 93.15) (width 0.125) (layer "In2.Cu") (net 21))
  (segment (start 95.641635 91.909177) (end 95.719795 91.860066) (width 0.125) (layer "In2.Cu") (net 21))
  (segment (start 94.513689 92.213858) (end 94.492358 92.200456) (width 0.125) (layer "In2.Cu") (net 21))
  (segment (start 95.269403 87.503447) (end 95.3 87.5) (width 0.125) (layer "In2.Cu") (net 21))
  (segment (start 94.5625 91.025) (end 94.537467 91.022179) (width 0.125) (layer "In2.Cu") (net 21))
  (segment (start 94.474544 93.382642) (end 94.461142 93.361311) (width 0.125) (layer "In2.Cu") (net 21))
  (segment (start 95.1625 87.6375) (end 95.165947 87.606903) (width 0.125) (layer "In2.Cu") (net 21))
  (segment (start 94.474544 90.982642) (end 94.461142 90.961311) (width 0.125) (layer "In2.Cu") (net 21))
  (segment (start 95.46278 91.95) (end 95.554507 91.939664) (width 0.125) (layer "In2.Cu") (net 21))
  (segment (start 95.152165 90.429507) (end 95.1625 90.33778) (width 0.125) (layer "In2.Cu") (net 21))
  (segment (start 95.46278 94.35) (end 95.554507 94.339664) (width 0.125) (layer "In2.Cu") (net 21))
  (segment (start 95.1625 86.4375) (end 95.1625 85.56731) (width 0.125) (layer "In2.Cu") (net 21))
  (segment (start 95.24034 86.561383) (end 95.21427 86.545001) (width 0.125) (layer "In2.Cu") (net 21))
  (segment (start 95.3625 96) (end 95.1625 95.8) (width 0.125) (layer "In2.Cu") (net 21))
  (segment (start 95.864664 92.545492) (end 95.834177 92.458364) (width 0.125) (layer "In2.Cu") (net 21))
  (segment (start 95.176116 87.57784) (end 95.192498 87.55177) (width 0.125) (layer "In2.Cu") (net 21))
  (segment (start 94.492358 91.974543) (end 94.513689 91.961141) (width 0.125) (layer "In2.Cu") (net 21))
  (segment (start 95.176116 86.497159) (end 95.165947 86.468096) (width 0.125) (layer "In2.Cu") (net 21))
  (segment (start 95.21427 87.529998) (end 95.24034 87.513616) (width 0.125) (layer "In2.Cu") (net 21))
  (segment (start 94.474544 93.192357) (end 94.492358 93.174543) (width 0.125) (layer "In2.Cu") (net 21))
  (segment (start 95.1625 90.33778) (end 95.1625 87.6375) (width 0.125) (layer "In2.Cu") (net 21))
  (segment (start 94.461142 93.361311) (end 94.452821 93.337533) (width 0.125) (layer "In2.Cu") (net 21))
  (segment (start 95.965069 87.161193) (end 95.975995 87.064224) (width 0.125) (layer "In2.Cu") (net 21))
  (segment (start 94.452821 93.237466) (end 94.461142 93.213688) (width 0.125) (layer "In2.Cu") (net 21))
  (segment (start 95.875 93.93778) (end 95.875 93.837219) (width 0.125) (layer "In2.Cu") (net 21))
  (segment (start 95.719795 93.514933) (end 95.641635 93.465822) (width 0.125) (layer "In2.Cu") (net 21))
  (segment (start 95.554507 91.939664) (end 95.641635 91.909177) (width 0.125) (layer "In2.Cu") (net 21))
  (segment (start 95.540219 86.575) (end 95.3 86.575) (width 0.125) (layer "In2.Cu") (net 21))
  (segment (start 94.513689 91.013858) (end 94.492358 91.000456) (width 0.125) (layer "In2.Cu") (net 21))
  (segment (start 122.488451 85.1625) (end 122.8375 85.511549) (width 0.125) (layer "In2.Cu") (net 21))
  (segment (start 94.452821 90.937533) (end 94.45 90.9125) (width 0.125) (layer "In2.Cu") (net 21))
  (segment (start 95.072567 90.594795) (end 95.121678 90.516635) (width 0.125) (layer "In2.Cu") (net 21))
  (segment (start 95.729295 87.456844) (end 95.811921 87.404927) (width 0.125) (layer "In2.Cu") (net 21))
  (segment (start 95.121678 90.516635) (end 95.152165 90.429507) (width 0.125) (layer "In2.Cu") (net 21))
  (segment (start 94.474544 91.992357) (end 94.492358 91.974543) (width 0.125) (layer "In2.Cu") (net 21))
  (segment (start 94.461142 90.813688) (end 94.474544 90.792357) (width 0.125) (layer "In2.Cu") (net 21))
  (segment (start 94.492358 93.400456) (end 94.474544 93.382642) (width 0.125) (layer "In2.Cu") (net 21))
  (segment (start 94.5625 93.15) (end 95.46278 93.15) (width 0.125) (layer "In2.Cu") (net 21))
  (segment (start 94.750281 90.75) (end 94.842008 90.739664) (width 0.125) (layer "In2.Cu") (net 21))
  (segment (start 95.249966 94.35282) (end 95.275 94.35) (width 0.125) (layer "In2.Cu") (net 21))
  (segment (start 95.226188 94.361141) (end 95.249966 94.35282) (width 0.125) (layer "In2.Cu") (net 21))
  (segment (start 94.513689 93.413858) (end 94.492358 93.400456) (width 0.125) (layer "In2.Cu") (net 21))
  (segment (start 94.492358 90.774543) (end 94.513689 90.761141) (width 0.125) (layer "In2.Cu") (net 21))
  (segment (start 95.719795 94.260066) (end 95.785066 94.194795) (width 0.125) (layer "In2.Cu") (net 21))
  (segment (start 95.165947 86.468096) (end 95.1625 86.4375) (width 0.125) (layer "In2.Cu") (net 21))
  (segment (start 95.21427 86.545001) (end 95.192498 86.523229) (width 0.125) (layer "In2.Cu") (net 21))
  (segment (start 95.637188 87.489074) (end 95.729295 87.456844) (width 0.125) (layer "In2.Cu") (net 21))
  (segment (start 95.864664 93.745492) (end 95.834177 93.658364) (width 0.125) (layer "In2.Cu") (net 21))
  (segment (start 122.8375 85.86731) (end 123.043673 86.073483) (width 0.125) (layer "In2.Cu") (net 21))
  (segment (start 94.513689 91.961141) (end 94.537467 91.95282) (width 0.125) (layer "In2.Cu") (net 21))
  (segment (start 95.785066 91.180204) (end 95.719795 91.114933) (width 0.125) (layer "In2.Cu") (net 21))
  (segment (start 95.875 91.437219) (end 95.864664 91.345492) (width 0.125) (layer "In2.Cu") (net 21))
  (segment (start 95.864664 94.029507) (end 95.875 93.93778) (width 0.125) (layer "In2.Cu") (net 21))
  (segment (start 95.641635 92.265822) (end 95.554507 92.235335) (width 0.125) (layer "In2.Cu") (net 21))
  (segment (start 95.785066 91.794795) (end 95.834177 91.716635) (width 0.125) (layer "In2.Cu") (net 21))
  (segment (start 95.16532 94.437466) (end 95.173641 94.413688) (width 0.125) (layer "In2.Cu") (net 21))
  (segment (start 94.513689 93.161141) (end 94.537467 93.15282) (width 0.125) (layer "In2.Cu") (net 21))
  (segment (start 123.043673 86.073483) (end 123.043673 86.356327) (width 0.125) (layer "In2.Cu") (net 21))
  (segment (start 94.5625 90.75) (end 94.750281 90.75) (width 0.125) (layer "In2.Cu") (net 21))
  (segment (start 95.932839 86.821699) (end 95.880922 86.739073) (width 0.125) (layer "In2.Cu") (net 21))
  (segment (start 95.554507 92.235335) (end 95.46278 92.225) (width 0.125) (layer "In2.Cu") (net 21))
  (segment (start 95.719795 91.114933) (end 95.641635 91.065822) (width 0.125) (layer "In2.Cu") (net 21))
  (segment (start 95.811921 87.404927) (end 95.880922 87.335926) (width 0.125) (layer "In2.Cu") (net 21))
  (segment (start 95.875 92.637219) (end 95.864664 92.545492) (width 0.125) (layer "In2.Cu") (net 21))
  (segment (start 94.492358 93.174543) (end 94.513689 93.161141) (width 0.125) (layer "In2.Cu") (net 21))
  (segment (start 95.173641 94.413688) (end 95.187043 94.392357) (width 0.125) (layer "In2.Cu") (net 21))
  (segment (start 94.537467 90.75282) (end 94.5625 90.75) (width 0.125) (layer "In2.Cu") (net 21))
  (segment (start 95.554507 93.435335) (end 95.46278 93.425) (width 0.125) (layer "In2.Cu") (net 21))
  (segment (start 95.975995 87.010775) (end 95.965069 86.913806) (width 0.125) (layer "In2.Cu") (net 21))
  (segment (start 95.46278 93.425) (end 94.5625 93.425) (width 0.125) (layer "In2.Cu") (net 21))
  (segment (start 94.5625 91.95) (end 95.46278 91.95) (width 0.125) (layer "In2.Cu") (net 21))
  (segment (start 95.641635 93.109177) (end 95.719795 93.060066) (width 0.125) (layer "In2.Cu") (net 21))
  (segment (start 95.269403 86.571552) (end 95.24034 86.561383) (width 0.125) (layer "In2.Cu") (net 21))
  (segment (start 95.785066 92.994795) (end 95.834177 92.916635) (width 0.125) (layer "In2.Cu") (net 21))
  (segment (start 95.540219 87.5) (end 95.637188 87.489074) (width 0.125) (layer "In2.Cu") (net 21))
  (segment (start 95.965069 86.913806) (end 95.932839 86.821699) (width 0.125) (layer "In2.Cu") (net 21))
  (segment (start 95.46278 93.15) (end 95.554507 93.139664) (width 0.125) (layer "In2.Cu") (net 21))
  (segment (start 95.875 91.53778) (end 95.875 91.437219) (width 0.125) (layer "In2.Cu") (net 21))
  (segment (start 95.834177 94.116635) (end 95.864664 94.029507) (width 0.125) (layer "In2.Cu") (net 21))
  (segment (start 94.45 92.0625) (end 94.452821 92.037466) (width 0.125) (layer "In2.Cu") (net 21))
  (segment (start 95.834177 93.658364) (end 95.785066 93.580204) (width 0.125) (layer "In2.Cu") (net 21))
  (segment (start 95.975995 87.064224) (end 95.975995 87.010775) (width 0.125) (layer "In2.Cu") (net 21))
  (segment (start 95.785066 93.580204) (end 95.719795 93.514933) (width 0.125) (layer "In2.Cu") (net 21))
  (segment (start 95.007296 90.660066) (end 95.072567 90.594795) (width 0.125) (layer "In2.Cu") (net 21))
  (segment (start 95.785066 92.380204) (end 95.719795 92.314933) (width 0.125) (layer "In2.Cu") (net 21))
  (segment (start 94.452821 90.837466) (end 94.461142 90.813688) (width 0.125) (layer "In2.Cu") (net 21))
  (segment (start 95.641635 94.309177) (end 95.719795 94.260066) (width 0.125) (layer "In2.Cu") (net 21))
  (segment (start 95.56731 85.1625) (end 122.488451 85.1625) (width 0.125) (layer "In2.Cu") (net 21))
  (segment (start 94.45 90.8625) (end 94.452821 90.837466) (width 0.125) (layer "In2.Cu") (net 21))
  (segment (start 94.842008 90.739664) (end 94.929136 90.709177) (width 0.125) (layer "In2.Cu") (net 21))
  (segment (start 94.45 92.1125) (end 94.45 92.0625) (width 0.125) (layer "In2.Cu") (net 21))
  (segment (start 94.461142 90.961311) (end 94.452821 90.937533) (width 0.125) (layer "In2.Cu") (net 21))
  (segment (start 94.492358 92.200456) (end 94.474544 92.182642) (width 0.125) (layer "In2.Cu") (net 21))
  (segment (start 95.719795 91.860066) (end 95.785066 91.794795) (width 0.125) (layer "In2.Cu") (net 21))
  (segment (start 94.461142 93.213688) (end 94.474544 93.192357) (width 0.125) (layer "In2.Cu") (net 21))
  (segment (start 94.452821 92.137533) (end 94.45 92.1125) (width 0.125) (layer "In2.Cu") (net 21))
  (segment (start 94.452821 92.037466) (end 94.461142 92.013688) (width 0.125) (layer "In2.Cu") (net 21))
  (segment (start 95.864664 91.629507) (end 95.875 91.53778) (width 0.125) (layer "In2.Cu") (net 21))
  (segment (start 95.1625 95.8) (end 95.1625 94.4625) (width 0.125) (layer "In2.Cu") (net 21))
  (segment (start 94.452821 93.337533) (end 94.45 93.3125) (width 0.125) (layer "In2.Cu") (net 21))
  (segment (start 94.474544 92.182642) (end 94.461142 92.161311) (width 0.125) (layer "In2.Cu") (net 21))
  (segment (start 95.834177 91.258364) (end 95.785066 91.180204) (width 0.125) (layer "In2.Cu") (net 21))
  (segment (start 95.864664 92.829507) (end 95.875 92.73778) (width 0.125) (layer "In2.Cu") (net 21))
  (segment (start 94.461142 92.161311) (end 94.452821 92.137533) (width 0.125) (layer "In2.Cu") (net 21))
  (segment (start 95.3 87.5) (end 95.540219 87.5) (width 0.125) (layer "In2.Cu") (net 21))
  (segment (start 95.811921 86.670072) (end 95.729295 86.618155) (width 0.125) (layer "In2.Cu") (net 21))
  (segment (start 94.929136 90.709177) (end 95.007296 90.660066) (width 0.125) (layer "In2.Cu") (net 21))
  (segment (start 94.461142 92.013688) (end 94.474544 91.992357) (width 0.125) (layer "In2.Cu") (net 21))
  (segment (start 95.554507 94.339664) (end 95.641635 94.309177) (width 0.125) (layer "In2.Cu") (net 21))
  (segment (start 95.192498 87.55177) (end 95.21427 87.529998) (width 0.125) (layer "In2.Cu") (net 21))
  (segment (start 95.192498 86.523229) (end 95.176116 86.497159) (width 0.125) (layer "In2.Cu") (net 21))
  (segment (start 95.834177 91.716635) (end 95.864664 91.629507) (width 0.125) (layer "In2.Cu") (net 21))
  (segment (start 95.24 93.95) (end 95.24 94.175001) (width 0.125) (layer "B.Cu") (net 21))
  (segment (start 95.125 95.7625) (end 95.3625 96) (width 0.125) (layer "B.Cu") (net 21))
  (segment (start 95.24 94.175001) (end 95.125 94.290001) (width 0.125) (layer "B.Cu") (net 21))
  (segment (start 95.125 94.290001) (end 95.125 95.7625) (width 0.125) (layer "B.Cu") (net 21))
  (segment (start 123.25 83.45) (end 123.25 84.650001) (width 0.125) (layer "F.Cu") (net 22))
  (segment (start 123.22045 85.843673) (end 123.556327 85.843673) (width 0.125) (layer "F.Cu") (net 22))
  (segment (start 123.125 85.748223) (end 123.22045 85.843673) (width 0.125) (layer "F.Cu") (net 22))
  (segment (start 123.125 84.775001) (end 123.125 85.748223) (width 0.125) (layer "F.Cu") (net 22))
  (segment (start 123.25 84.650001) (end 123.125 84.775001) (width 0.125) (layer "F.Cu") (net 22))
  (via (at 123.556327 85.843673) (size 0.6) (drill 0.25) (layers "F.Cu" "B.Cu") (net 22))
  (via (at 94.6375 96) (size 0.6) (drill 0.25) (layers "F.Cu" "B.Cu") (net 22))
  (segment (start 95.4375 91.625) (end 95.462533 91.622179) (width 0.125) (layer "In2.Cu") (net 22))
  (segment (start 95.513495 87.175) (end 95.544091 87.171552) (width 0.125) (layer "In2.Cu") (net 22))
  (segment (start 94.135336 90.745492) (end 94.165823 90.658364) (width 0.125) (layer "In2.Cu") (net 22))
  (segment (start 95.637378 87.097159) (end 95.647547 87.068096) (width 0.125) (layer "In2.Cu") (net 22))
  (segment (start 95.547179 92.737533) (end 95.55 92.7125) (width 0.125) (layer "In2.Cu") (net 22))
  (segment (start 94.214934 90.580204) (end 94.280205 90.514933) (width 0.125) (layer "In2.Cu") (net 22))
  (segment (start 123.273483 85.843673) (end 123.556327 85.843673) (width 0.125) (layer "In2.Cu") (net 22))
  (segment (start 94.214934 93.594795) (end 94.165823 93.516635) (width 0.125) (layer "In2.Cu") (net 22))
  (segment (start 94.445493 91.635335) (end 94.53722 91.625) (width 0.125) (layer "In2.Cu") (net 22))
  (segment (start 95.538858 91.561311) (end 95.547179 91.537533) (width 0.125) (layer "In2.Cu") (net 22))
  (segment (start 95.4375 92.825) (end 95.462533 92.822179) (width 0.125) (layer "In2.Cu") (net 22))
  (segment (start 94.795143 90.400456) (end 94.812957 90.382642) (width 0.125) (layer "In2.Cu") (net 22))
  (segment (start 94.932572 87.339073) (end 95.001573 87.270072) (width 0.125) (layer "In2.Cu") (net 22))
  (segment (start 95.525456 91.582642) (end 95.538858 91.561311) (width 0.125) (layer "In2.Cu") (net 22))
  (segment (start 95.55 93.9125) (end 95.55 93.8625) (width 0.125) (layer "In2.Cu") (net 22))
  (segment (start 94.812957 90.382642) (end 94.826359 90.361311) (width 0.125) (layer "In2.Cu") (net 22))
  (segment (start 94.214934 91.194795) (end 94.165823 91.116635) (width 0.125) (layer "In2.Cu") (net 22))
  (segment (start 95.637378 86.97784) (end 95.620996 86.95177) (width 0.125) (layer "In2.Cu") (net 22))
  (segment (start 95.55 93.8625) (end 95.547179 93.837466) (width 0.125) (layer "In2.Cu") (net 22))
  (segment (start 95.462533 91.622179) (end 95.486311 91.613858) (width 0.125) (layer "In2.Cu") (net 22))
  (segment (start 94.8375 90.3125) (end 94.8375 87.610775) (width 0.125) (layer "In2.Cu") (net 22))
  (segment (start 95.486311 92.561141) (end 95.462533 92.55282) (width 0.125) (layer "In2.Cu") (net 22))
  (segment (start 95.599224 86.929998) (end 95.573154 86.913616) (width 0.125) (layer "In2.Cu") (net 22))
  (segment (start 95.176306 86.889074) (end 95.084199 86.856844) (width 0.125) (layer "In2.Cu") (net 22))
  (segment (start 95.573154 86.913616) (end 95.544091 86.903447) (width 0.125) (layer "In2.Cu") (net 22))
  (segment (start 95.462533 94.022179) (end 95.486311 94.013858) (width 0.125) (layer "In2.Cu") (net 22))
  (segment (start 94.53722 91.625) (end 95.4375 91.625) (width 0.125) (layer "In2.Cu") (net 22))
  (segment (start 94.165823 91.116635) (end 94.135336 91.029507) (width 0.125) (layer "In2.Cu") (net 22))
  (segment (start 94.214934 92.394795) (end 94.165823 92.316635) (width 0.125) (layer "In2.Cu") (net 22))
  (segment (start 95.249719 94.025) (end 95.4375 94.025) (width 0.125) (layer "In2.Cu") (net 22))
  (segment (start 95.55 91.4625) (end 95.547179 91.437466) (width 0.125) (layer "In2.Cu") (net 22))
  (segment (start 94.165823 93.058364) (end 94.214934 92.980204) (width 0.125) (layer "In2.Cu") (net 22))
  (segment (start 94.880655 87.421699) (end 94.932572 87.339073) (width 0.125) (layer "In2.Cu") (net 22))
  (segment (start 95.462533 91.35282) (end 95.4375 91.35) (width 0.125) (layer "In2.Cu") (net 22))
  (segment (start 95.43269 84.8375) (end 122.623071 84.8375) (width 0.125) (layer "In2.Cu") (net 22))
  (segment (start 95.525456 93.792357) (end 95.507642 93.774543) (width 0.125) (layer "In2.Cu") (net 22))
  (segment (start 123.1625 85.73269) (end 123.273483 85.843673) (width 0.125) (layer "In2.Cu") (net 22))
  (segment (start 95.486311 93.761141) (end 95.462533 93.75282) (width 0.125) (layer "In2.Cu") (net 22))
  (segment (start 94.165823 93.516635) (end 94.135336 93.429507) (width 0.125) (layer "In2.Cu") (net 22))
  (segment (start 94.445493 90.435335) (end 94.53722 90.425) (width 0.125) (layer "In2.Cu") (net 22))
  (segment (start 94.135336 93.429507) (end 94.125 93.33778) (width 0.125) (layer "In2.Cu") (net 22))
  (segment (start 95.55 92.7125) (end 95.55 92.6625) (width 0.125) (layer "In2.Cu") (net 22))
  (segment (start 94.165823 90.658364) (end 94.214934 90.580204) (width 0.125) (layer "In2.Cu") (net 22))
  (segment (start 94.135336 91.945492) (end 94.165823 91.858364) (width 0.125) (layer "In2.Cu") (net 22))
  (segment (start 94.280205 92.460066) (end 94.214934 92.394795) (width 0.125) (layer "In2.Cu") (net 22))
  (segment (start 95.55 91.5125) (end 95.55 91.4625) (width 0.125) (layer "In2.Cu") (net 22))
  (segment (start 94.214934 91.780204) (end 94.280205 91.714933) (width 0.125) (layer "In2.Cu") (net 22))
  (segment (start 95.547179 91.437466) (end 95.538858 91.413688) (width 0.125) (layer "In2.Cu") (net 22))
  (segment (start 94.6375 96) (end 94.8375 95.8) (width 0.125) (layer "In2.Cu") (net 22))
  (segment (start 123.1625 85.376929) (end 123.1625 85.73269) (width 0.125) (layer "In2.Cu") (net 22))
  (segment (start 94.53722 92.825) (end 95.4375 92.825) (width 0.125) (layer "In2.Cu") (net 22))
  (segment (start 94.125 93.237219) (end 94.135336 93.145492) (width 0.125) (layer "In2.Cu") (net 22))
  (segment (start 95.486311 91.361141) (end 95.462533 91.35282) (width 0.125) (layer "In2.Cu") (net 22))
  (segment (start 94.135336 91.029507) (end 94.125 90.93778) (width 0.125) (layer "In2.Cu") (net 22))
  (segment (start 94.280205 92.914933) (end 94.358365 92.865822) (width 0.125) (layer "In2.Cu") (net 22))
  (segment (start 94.750034 90.422179) (end 94.773812 90.413858) (width 0.125) (layer "In2.Cu") (net 22))
  (segment (start 95.4375 91.35) (end 94.53722 91.35) (width 0.125) (layer "In2.Cu") (net 22))
  (segment (start 95.507642 92.800456) (end 95.525456 92.782642) (width 0.125) (layer "In2.Cu") (net 22))
  (segment (start 95.507642 94.000456) (end 95.525456 93.982642) (width 0.125) (layer "In2.Cu") (net 22))
  (segment (start 94.358365 91.309177) (end 94.280205 91.260066) (width 0.125) (layer "In2.Cu") (net 22))
  (segment (start 95.001573 86.804927) (end 94.932572 86.735926) (width 0.125) (layer "In2.Cu") (net 22))
  (segment (start 94.280205 91.714933) (end 94.358365 91.665822) (width 0.125) (layer "In2.Cu") (net 22))
  (segment (start 95.486311 94.013858) (end 95.507642 94.000456) (width 0.125) (layer "In2.Cu") (net 22))
  (segment (start 95.507642 91.600456) (end 95.525456 91.582642) (width 0.125) (layer "In2.Cu") (net 22))
  (segment (start 94.280205 93.660066) (end 94.214934 93.594795) (width 0.125) (layer "In2.Cu") (net 22))
  (segment (start 94.280205 90.514933) (end 94.358365 90.465822) (width 0.125) (layer "In2.Cu") (net 22))
  (segment (start 95.070864 94.065822) (end 95.157992 94.035335) (width 0.125) (layer "In2.Cu") (net 22))
  (segment (start 94.8375 85.43269) (end 95.43269 84.8375) (width 0.125) (layer "In2.Cu") (net 22))
  (segment (start 95.620996 86.95177) (end 95.599224 86.929998) (width 0.125) (layer "In2.Cu") (net 22))
  (segment (start 94.165823 92.316635) (end 94.135336 92.229507) (width 0.125) (layer "In2.Cu") (net 22))
  (segment (start 94.848425 87.513806) (end 94.880655 87.421699) (width 0.125) (layer "In2.Cu") (net 22))
  (segment (start 94.847835 94.345492) (end 94.878322 94.258364) (width 0.125) (layer "In2.Cu") (net 22))
  (segment (start 94.725 90.425) (end 94.750034 90.422179) (width 0.125) (layer "In2.Cu") (net 22))
  (segment (start 95.538858 91.413688) (end 95.525456 91.392357) (width 0.125) (layer "In2.Cu") (net 22))
  (segment (start 95.507642 92.574543) (end 95.486311 92.561141) (width 0.125) (layer "In2.Cu") (net 22))
  (segment (start 95.507642 91.374543) (end 95.486311 91.361141) (width 0.125) (layer "In2.Cu") (net 22))
  (segment (start 94.445493 92.539664) (end 94.358365 92.509177) (width 0.125) (layer "In2.Cu") (net 22))
  (segment (start 94.8375 87.610775) (end 94.848425 87.513806) (width 0.125) (layer "In2.Cu") (net 22))
  (segment (start 95.513495 86.9) (end 95.273275 86.9) (width 0.125) (layer "In2.Cu") (net 22))
  (segment (start 94.358365 90.465822) (end 94.445493 90.435335) (width 0.125) (layer "In2.Cu") (net 22))
  (segment (start 95.599224 87.145001) (end 95.620996 87.123229) (width 0.125) (layer "In2.Cu") (net 22))
  (segment (start 94.135336 92.229507) (end 94.125 92.13778) (width 0.125) (layer "In2.Cu") (net 22))
  (segment (start 94.53722 93.75) (end 94.445493 93.739664) (width 0.125) (layer "In2.Cu") (net 22))
  (segment (start 95.525456 93.982642) (end 95.538858 93.961311) (width 0.125) (layer "In2.Cu") (net 22))
  (segment (start 95.647547 87.006903) (end 95.637378 86.97784) (width 0.125) (layer "In2.Cu") (net 22))
  (segment (start 95.538858 93.961311) (end 95.547179 93.937533) (width 0.125) (layer "In2.Cu") (net 22))
  (segment (start 95.525456 92.592357) (end 95.507642 92.574543) (width 0.125) (layer "In2.Cu") (net 22))
  (segment (start 95.573154 87.161383) (end 95.599224 87.145001) (width 0.125) (layer "In2.Cu") (net 22))
  (segment (start 94.878322 94.258364) (end 94.927433 94.180204) (width 0.125) (layer "In2.Cu") (net 22))
  (segment (start 94.125 93.33778) (end 94.125 93.237219) (width 0.125) (layer "In2.Cu") (net 22))
  (segment (start 94.880655 86.6533) (end 94.848425 86.561193) (width 0.125) (layer "In2.Cu") (net 22))
  (segment (start 95.462533 93.75282) (end 95.4375 93.75) (width 0.125) (layer "In2.Cu") (net 22))
  (segment (start 95.486311 92.813858) (end 95.507642 92.800456) (width 0.125) (layer "In2.Cu") (net 22))
  (segment (start 94.53722 90.425) (end 94.725 90.425) (width 0.125) (layer "In2.Cu") (net 22))
  (segment (start 95.547179 91.537533) (end 95.55 91.5125) (width 0.125) (layer "In2.Cu") (net 22))
  (segment (start 95.176306 87.185925) (end 95.273275 87.175) (width 0.125) (layer "In2.Cu") (net 22))
  (segment (start 94.53722 92.55) (end 94.445493 92.539664) (width 0.125) (layer "In2.Cu") (net 22))
  (segment (start 95.544091 87.171552) (end 95.573154 87.161383) (width 0.125) (layer "In2.Cu") (net 22))
  (segment (start 95.525456 91.392357) (end 95.507642 91.374543) (width 0.125) (layer "In2.Cu") (net 22))
  (segment (start 95.084199 86.856844) (end 95.001573 86.804927) (width 0.125) (layer "In2.Cu") (net 22))
  (segment (start 122.623071 84.8375) (end 123.1625 85.376929) (width 0.125) (layer "In2.Cu") (net 22))
  (segment (start 95.084199 87.218155) (end 95.176306 87.185925) (width 0.125) (layer "In2.Cu") (net 22))
  (segment (start 94.125 90.93778) (end 94.125 90.837219) (width 0.125) (layer "In2.Cu") (net 22))
  (segment (start 94.125 92.037219) (end 94.135336 91.945492) (width 0.125) (layer "In2.Cu") (net 22))
  (segment (start 95.486311 91.613858) (end 95.507642 91.600456) (width 0.125) (layer "In2.Cu") (net 22))
  (segment (start 94.358365 93.709177) (end 94.280205 93.660066) (width 0.125) (layer "In2.Cu") (net 22))
  (segment (start 95.001573 87.270072) (end 95.084199 87.218155) (width 0.125) (layer "In2.Cu") (net 22))
  (segment (start 94.165823 91.858364) (end 94.214934 91.780204) (width 0.125) (layer "In2.Cu") (net 22))
  (segment (start 94.8375 94.437219) (end 94.847835 94.345492) (width 0.125) (layer "In2.Cu") (net 22))
  (segment (start 94.280205 91.260066) (end 94.214934 91.194795) (width 0.125) (layer "In2.Cu") (net 22))
  (segment (start 95.507642 93.774543) (end 95.486311 93.761141) (width 0.125) (layer "In2.Cu") (net 22))
  (segment (start 95.4375 94.025) (end 95.462533 94.022179) (width 0.125) (layer "In2.Cu") (net 22))
  (segment (start 95.547179 92.637466) (end 95.538858 92.613688) (width 0.125) (layer "In2.Cu") (net 22))
  (segment (start 94.848425 86.561193) (end 94.8375 86.464224) (width 0.125) (layer "In2.Cu") (net 22))
  (segment (start 94.214934 92.980204) (end 94.280205 92.914933) (width 0.125) (layer "In2.Cu") (net 22))
  (segment (start 94.135336 93.145492) (end 94.165823 93.058364) (width 0.125) (layer "In2.Cu") (net 22))
  (segment (start 95.462533 92.55282) (end 95.4375 92.55) (width 0.125) (layer "In2.Cu") (net 22))
  (segment (start 94.445493 93.739664) (end 94.358365 93.709177) (width 0.125) (layer "In2.Cu") (net 22))
  (segment (start 95.647547 87.068096) (end 95.650995 87.0375) (width 0.125) (layer "In2.Cu") (net 22))
  (segment (start 94.125 92.13778) (end 94.125 92.037219) (width 0.125) (layer "In2.Cu") (net 22))
  (segment (start 95.273275 86.9) (end 95.176306 86.889074) (width 0.125) (layer "In2.Cu") (net 22))
  (segment (start 94.53722 91.35) (end 94.445493 91.339664) (width 0.125) (layer "In2.Cu") (net 22))
  (segment (start 94.932572 86.735926) (end 94.880655 86.6533) (width 0.125) (layer "In2.Cu") (net 22))
  (segment (start 95.620996 87.123229) (end 95.637378 87.097159) (width 0.125) (layer "In2.Cu") (net 22))
  (segment (start 94.992704 94.114933) (end 95.070864 94.065822) (width 0.125) (layer "In2.Cu") (net 22))
  (segment (start 94.358365 92.509177) (end 94.280205 92.460066) (width 0.125) (layer "In2.Cu") (net 22))
  (segment (start 95.650995 87.0375) (end 95.647547 87.006903) (width 0.125) (layer "In2.Cu") (net 22))
  (segment (start 94.445493 91.339664) (end 94.358365 91.309177) (width 0.125) (layer "In2.Cu") (net 22))
  (segment (start 94.773812 90.413858) (end 94.795143 90.400456) (width 0.125) (layer "In2.Cu") (net 22))
  (segment (start 95.4375 92.55) (end 94.53722 92.55) (width 0.125) (layer "In2.Cu") (net 22))
  (segment (start 95.547179 93.937533) (end 95.55 93.9125) (width 0.125) (layer "In2.Cu") (net 22))
  (segment (start 95.538858 93.813688) (end 95.525456 93.792357) (width 0.125) (layer "In2.Cu") (net 22))
  (segment (start 95.538858 92.761311) (end 95.547179 92.737533) (width 0.125) (layer "In2.Cu") (net 22))
  (segment (start 95.544091 86.903447) (end 95.513495 86.9) (width 0.125) (layer "In2.Cu") (net 22))
  (segment (start 94.8375 95.8) (end 94.8375 94.437219) (width 0.125) (layer "In2.Cu") (net 22))
  (segment (start 94.826359 90.361311) (end 94.83468 90.337533) (width 0.125) (layer "In2.Cu") (net 22))
  (segment (start 95.55 92.6625) (end 95.547179 92.637466) (width 0.125) (layer "In2.Cu") (net 22))
  (segment (start 94.358365 92.865822) (end 94.445493 92.835335) (width 0.125) (layer "In2.Cu") (net 22))
  (segment (start 95.273275 87.175) (end 95.513495 87.175) (width 0.125) (layer "In2.Cu") (net 22))
  (segment (start 95.4375 93.75) (end 94.53722 93.75) (width 0.125) (layer "In2.Cu") (net 22))
  (segment (start 94.8375 86.464224) (end 94.8375 85.43269) (width 0.125) (layer "In2.Cu") (net 22))
  (segment (start 94.125 90.837219) (end 94.135336 90.745492) (width 0.125) (layer "In2.Cu") (net 22))
  (segment (start 95.157992 94.035335) (end 95.249719 94.025) (width 0.125) (layer "In2.Cu") (net 22))
  (segment (start 94.927433 94.180204) (end 94.992704 94.114933) (width 0.125) (layer "In2.Cu") (net 22))
  (segment (start 95.462533 92.822179) (end 95.486311 92.813858) (width 0.125) (layer "In2.Cu") (net 22))
  (segment (start 95.525456 92.782642) (end 95.538858 92.761311) (width 0.125) (layer "In2.Cu") (net 22))
  (segment (start 94.358365 91.665822) (end 94.445493 91.635335) (width 0.125) (layer "In2.Cu") (net 22))
  (segment (start 94.445493 92.835335) (end 94.53722 92.825) (width 0.125) (layer "In2.Cu") (net 22))
  (segment (start 94.83468 90.337533) (end 94.8375 90.3125) (width 0.125) (layer "In2.Cu") (net 22))
  (segment (start 95.547179 93.837466) (end 95.538858 93.813688) (width 0.125) (layer "In2.Cu") (net 22))
  (segment (start 95.538858 92.613688) (end 95.525456 92.592357) (width 0.125) (layer "In2.Cu") (net 22))
  (segment (start 94.76 94.175001) (end 94.875 94.290001) (width 0.125) (layer "B.Cu") (net 22))
  (segment (start 94.76 93.95) (end 94.76 94.175001) (width 0.125) (layer "B.Cu") (net 22))
  (segment (start 94.875 94.290001) (end 94.875 95.7625) (width 0.125) (layer "B.Cu") (net 22))
  (segment (start 94.875 95.7625) (end 94.6375 96) (width 0.125) (layer "B.Cu") (net 22))
  (segment (start 121.625 84.775001) (end 121.625 86.427977) (width 0.125) (layer "F.Cu") (net 23))
  (segment (start 121.625 86.427977) (end 121.691509 86.494486) (width 0.125) (layer "F.Cu") (net 23))
  (segment (start 121.75 84.650001) (end 121.625 84.775001) (width 0.125) (layer "F.Cu") (net 23))
  (segment (start 121.75 83.45) (end 121.75 84.650001) (width 0.125) (layer "F.Cu") (net 23))
  (segment (start 121.691509 86.494486) (end 122.027386 86.494486) (width 0.125) (layer "F.Cu") (net 23))
  (via (at 95.9375 95) (size 0.6) (drill 0.25) (layers "F.Cu" "B.Cu") (net 23))
  (via (at 122.027386 86.494486) (size 0.6) (drill 0.25) (layers "F.Cu" "B.Cu") (net 23))
  (segment (start 102.948229 86.807502) (end 102.970001 86.78573) (width 0.125) (layer "In2.Cu") (net 23))
  (segment (start 103.164073 85.570073) (end 103.246699 85.518156) (width 0.125) (layer "In2.Cu") (net 23))
  (segment (start 105.296552 86.730597) (end 105.3 86.7) (width 0.125) (layer "In2.Cu") (net 23))
  (segment (start 106.254998 86.78573) (end 106.27677 86.807502) (width 0.125) (layer "In2.Cu") (net 23))
  (segment (start 99.286193 85.485926) (end 99.3783 85.518156) (width 0.125) (layer "In2.Cu") (net 23))
  (segment (start 109.617191 86.809615) (end 109.637429 86.789377) (width 0.125) (layer "In2.Cu") (net 23))
  (segment (start 103.914074 85.813807) (end 103.925 85.910776) (width 0.125) (layer "In2.Cu") (net 23))
  (segment (start 99.460926 85.570073) (end 99.529927 85.639074) (width 0.125) (layer "In2.Cu") (net 23))
  (segment (start 100.87677 86.807502) (end 100.90284 86.823884) (width 0.125) (layer "In2.Cu") (net 23))
  (segment (start 100.854998 86.78573) (end 100.87677 86.807502) (width 0.125) (layer "In2.Cu") (net 23))
  (segment (start 106.595072 85.639074) (end 106.664073 85.570073) (width 0.125) (layer "In2.Cu") (net 23))
  (segment (start 103.043155 85.7217) (end 103.095072 85.639074) (width 0.125) (layer "In2.Cu") (net 23))
  (segment (start 106.935775 85.475) (end 106.989224 85.475) (width 0.125) (layer "In2.Cu") (net 23))
  (segment (start 100.825 86.7) (end 100.828447 86.730597) (width 0.125) (layer "In2.Cu") (net 23))
  (segment (start 105.343155 85.7217) (end 105.395072 85.639074) (width 0.125) (layer "In2.Cu") (net 23))
  (segment (start 102.738616 86.75966) (end 102.754998 86.78573) (width 0.125) (layer "In2.Cu") (net 23))
  (segment (start 98.686383 86.75966) (end 98.696552 86.730597) (width 0.125) (layer "In2.Cu") (net 23))
  (segment (start 103 86.7) (end 103 85.910776) (width 0.125) (layer "In2.Cu") (net 23))
  (segment (start 102.725 86.7) (end 102.728447 86.730597) (width 0.125) (layer "In2.Cu") (net 23))
  (segment (start 110.71813 86.8375) (end 118.68269 86.8375) (width 0.125) (layer "In2.Cu") (net 23))
  (segment (start 121.744542 86.494486) (end 122.027386 86.494486) (width 0.125) (layer "In2.Cu") (net 23))
  (segment (start 110.638438 86.809615) (end 110.662673 86.824843) (width 0.125) (layer "In2.Cu") (net 23))
  (segment (start 105.222159 86.823884) (end 105.248229 86.807502) (width 0.125) (layer "In2.Cu") (net 23))
  (segment (start 102.629927 85.639074) (end 102.681844 85.7217) (width 0.125) (layer "In2.Cu") (net 23))
  (segment (start 106.393096 86.834053) (end 106.422159 86.823884) (width 0.125) (layer "In2.Cu") (net 23))
  (segment (start 118.68269 86.8375) (end 119.68269 85.8375) (width 0.125) (layer "In2.Cu") (net 23))
  (segment (start 105.9783 85.518156) (end 106.060926 85.570073) (width 0.125) (layer "In2.Cu") (net 23))
  (segment (start 121.087556 85.8375) (end 121.744542 86.494486) (width 0.125) (layer "In2.Cu") (net 23))
  (segment (start 99.67677 86.807502) (end 99.70284 86.823884) (width 0.125) (layer "In2.Cu") (net 23))
  (segment (start 107.1783 85.518156) (end 107.260926 85.570073) (width 0.125) (layer "In2.Cu") (net 23))
  (segment (start 103.938616 86.75966) (end 103.954998 86.78573) (width 0.125) (layer "In2.Cu") (net 23))
  (segment (start 107.260926 85.570073) (end 107.329927 85.639074) (width 0.125) (layer "In2.Cu") (net 23))
  (segment (start 99.7625 86.8375) (end 99.793096 86.834053) (width 0.125) (layer "In2.Cu") (net 23))
  (segment (start 109.997026 86.105067) (end 110.091964 86.094369) (width 0.125) (layer "In2.Cu") (net 23))
  (segment (start 106.129927 85.639074) (end 106.181844 85.7217) (width 0.125) (layer "In2.Cu") (net 23))
  (segment (start 106.5 85.910776) (end 106.510925 85.813807) (width 0.125) (layer "In2.Cu") (net 23))
  (segment (start 100.146699 85.518156) (end 100.238806 85.485926) (width 0.125) (layer "In2.Cu") (net 23))
  (segment (start 98.593096 86.834053) (end 98.622159 86.823884) (width 0.125) (layer "In2.Cu") (net 23))
  (segment (start 110.548063 86.335903) (end 110.579617 86.426081) (width 0.125) (layer "In2.Cu") (net 23))
  (segment (start 100.729927 85.639074) (end 100.781844 85.7217) (width 0.125) (layer "In2.Cu") (net 23))
  (segment (start 106.543155 85.7217) (end 106.595072 85.639074) (width 0.125) (layer "In2.Cu") (net 23))
  (segment (start 100.238806 85.485926) (end 100.335775 85.475) (width 0.125) (layer "In2.Cu") (net 23))
  (segment (start 100.660926 85.570073) (end 100.729927 85.639074) (width 0.125) (layer "In2.Cu") (net 23))
  (segment (start 106.486383 86.75966) (end 106.496552 86.730597) (width 0.125) (layer "In2.Cu") (net 23))
  (segment (start 98.7 85.910776) (end 98.710925 85.813807) (width 0.125) (layer "In2.Cu") (net 23))
  (segment (start 104.031903 86.834053) (end 104.0625 86.8375) (width 0.125) (layer "In2.Cu") (net 23))
  (segment (start 103 85.910776) (end 103.010925 85.813807) (width 0.125) (layer "In2.Cu") (net 23))
  (segment (start 106.181844 85.7217) (end 106.214074 85.813807) (width 0.125) (layer "In2.Cu") (net 23))
  (segment (start 110.662673 86.824843) (end 110.689688 86.834296) (width 0.125) (layer "In2.Cu") (net 23))
  (segment (start 106.225 86.7) (end 106.228447 86.730597) (width 0.125) (layer "In2.Cu") (net 23))
  (segment (start 110.497233 86.255008) (end 110.548063 86.335903) (width 0.125) (layer "In2.Cu") (net 23))
  (segment (start 106.664073 85.570073) (end 106.746699 85.518156) (width 0.125) (layer "In2.Cu") (net 23))
  (segment (start 102.80284 86.823884) (end 102.831903 86.834053) (width 0.125) (layer "In2.Cu") (net 23))
  (segment (start 105.1625 86.8375) (end 105.193096 86.834053) (width 0.125) (layer "In2.Cu") (net 23))
  (segment (start 103.338806 85.485926) (end 103.435775 85.475) (width 0.125) (layer "In2.Cu") (net 23))
  (segment (start 103.010925 85.813807) (end 103.043155 85.7217) (width 0.125) (layer "In2.Cu") (net 23))
  (segment (start 109.665315 86.521019) (end 109.676012 86.426081) (width 0.125) (layer "In2.Cu") (net 23))
  (segment (start 109.592956 86.824843) (end 109.617191 86.809615) (width 0.125) (layer "In2.Cu") (net 23))
  (segment (start 110.6182 86.789377) (end 110.638438 86.809615) (width 0.125) (layer "In2.Cu") (net 23))
  (segment (start 103.489224 85.475) (end 103.586193 85.485926) (width 0.125) (layer "In2.Cu") (net 23))
  (segment (start 106.838806 85.485926) (end 106.935775 85.475) (width 0.125) (layer "In2.Cu") (net 23))
  (segment (start 101.964073 85.570073) (end 102.046699 85.518156) (width 0.125) (layer "In2.Cu") (net 23))
  (segment (start 110.429676 86.187451) (end 110.497233 86.255008) (width 0.125) (layer "In2.Cu") (net 23))
  (segment (start 100.9625 86.8375) (end 101.6625 86.8375) (width 0.125) (layer "In2.Cu") (net 23))
  (segment (start 105.464073 85.570073) (end 105.546699 85.518156) (width 0.125) (layer "In2.Cu") (net 23))
  (segment (start 107.414074 85.813807) (end 107.425 85.910776) (width 0.125) (layer "In2.Cu") (net 23))
  (segment (start 109.5375 86.8375) (end 109.565941 86.834296) (width 0.125) (layer "In2.Cu") (net 23))
  (segment (start 102.138806 85.485926) (end 102.235775 85.475) (width 0.125) (layer "In2.Cu") (net 23))
  (segment (start 98.864073 85.570073) (end 98.946699 85.518156) (width 0.125) (layer "In2.Cu") (net 23))
  (segment (start 107.381844 85.7217) (end 107.414074 85.813807) (width 0.125) (layer "In2.Cu") (net 23))
  (segment (start 105.248229 86.807502) (end 105.270001 86.78573) (width 0.125) (layer "In2.Cu") (net 23))
  (segment (start 97.18269 86.8375) (end 98.5625 86.8375) (width 0.125) (layer "In2.Cu") (net 23))
  (segment (start 99.896552 86.730597) (end 99.9 86.7) (width 0.125) (layer "In2.Cu") (net 23))
  (segment (start 99.995072 85.639074) (end 100.064073 85.570073) (width 0.125) (layer "In2.Cu") (net 23))
  (segment (start 101.693096 86.834053) (end 101.722159 86.823884) (width 0.125) (layer "In2.Cu") (net 23))
  (segment (start 102.77677 86.807502) (end 102.80284 86.823884) (width 0.125) (layer "In2.Cu") (net 23))
  (segment (start 101.843155 85.7217) (end 101.895072 85.639074) (width 0.125) (layer "In2.Cu") (net 23))
  (segment (start 99.038806 85.485926) (end 99.135775 85.475) (width 0.125) (layer "In2.Cu") (net 23))
  (segment (start 98.670001 86.78573) (end 98.686383 86.75966) (width 0.125) (layer "In2.Cu") (net 23))
  (segment (start 98.696552 86.730597) (end 98.7 86.7) (width 0.125) (layer "In2.Cu") (net 23))
  (segment (start 103.928447 86.730597) (end 103.938616 86.75966) (width 0.125) (layer "In2.Cu") (net 23))
  (segment (start 105.886193 85.485926) (end 105.9783 85.518156) (width 0.125) (layer "In2.Cu") (net 23))
  (segment (start 99.943155 85.7217) (end 99.995072 85.639074) (width 0.125) (layer "In2.Cu") (net 23))
  (segment (start 101.748229 86.807502) (end 101.770001 86.78573) (width 0.125) (layer "In2.Cu") (net 23))
  (segment (start 119.68269 85.8375) (end 121.087556 85.8375) (width 0.125) (layer "In2.Cu") (net 23))
  (segment (start 98.743155 85.7217) (end 98.795072 85.639074) (width 0.125) (layer "In2.Cu") (net 23))
  (segment (start 100.838616 86.75966) (end 100.854998 86.78573) (width 0.125) (layer "In2.Cu") (net 23))
  (segment (start 99.625 86.7) (end 99.628447 86.730597) (width 0.125) (layer "In2.Cu") (net 23))
  (segment (start 107.47677 86.807502) (end 107.50284 86.823884) (width 0.125) (layer "In2.Cu") (net 23))
  (segment (start 106.510925 85.813807) (end 106.543155 85.7217) (width 0.125) (layer "In2.Cu") (net 23))
  (segment (start 102.289224 85.475) (end 102.386193 85.485926) (width 0.125) (layer "In2.Cu") (net 23))
  (segment (start 110.258603 86.105067) (end 110.348781 86.136621) (width 0.125) (layer "In2.Cu") (net 23))
  (segment (start 107.425 85.910776) (end 107.425 86.7) (width 0.125) (layer "In2.Cu") (net 23))
  (segment (start 103.829927 85.639074) (end 103.881844 85.7217) (width 0.125) (layer "In2.Cu") (net 23))
  (segment (start 105.310925 85.813807) (end 105.343155 85.7217) (width 0.125) (layer "In2.Cu") (net 23))
  (segment (start 100.828447 86.730597) (end 100.838616 86.75966) (width 0.125) (layer "In2.Cu") (net 23))
  (segment (start 100.931903 86.834053) (end 100.9625 86.8375) (width 0.125) (layer "In2.Cu") (net 23))
  (segment (start 102.8625 86.8375) (end 102.893096 86.834053) (width 0.125) (layer "In2.Cu") (net 23))
  (segment (start 105.286383 86.75966) (end 105.296552 86.730597) (width 0.125) (layer "In2.Cu") (net 23))
  (segment (start 98.795072 85.639074) (end 98.864073 85.570073) (width 0.125) (layer "In2.Cu") (net 23))
  (segment (start 102.386193 85.485926) (end 102.4783 85.518156) (width 0.125) (layer "In2.Cu") (net 23))
  (segment (start 109.637429 86.789377) (end 109.652657 86.765142) (width 0.125) (layer "In2.Cu") (net 23))
  (segment (start 110.091964 86.094369) (end 110.163665 86.094369) (width 0.125) (layer "In2.Cu") (net 23))
  (segment (start 99.848229 86.807502) (end 99.870001 86.78573) (width 0.125) (layer "In2.Cu") (net 23))
  (segment (start 103.760926 85.570073) (end 103.829927 85.639074) (width 0.125) (layer "In2.Cu") (net 23))
  (segment (start 100.5783 85.518156) (end 100.660926 85.570073) (width 0.125) (layer "In2.Cu") (net 23))
  (segment (start 99.581844 85.7217) (end 99.614074 85.813807) (width 0.125) (layer "In2.Cu") (net 23))
  (segment (start 109.825953 86.187451) (end 109.906848 86.136621) (width 0.125) (layer "In2.Cu") (net 23))
  (segment (start 99.529927 85.639074) (end 99.581844 85.7217) (width 0.125) (layer "In2.Cu") (net 23))
  (segment (start 106.214074 85.813807) (end 106.225 85.910776) (width 0.125) (layer "In2.Cu") (net 23))
  (segment (start 105.735775 85.475) (end 105.789224 85.475) (width 0.125) (layer "In2.Cu") (net 23))
  (segment (start 100.90284 86.823884) (end 100.931903 86.834053) (width 0.125) (layer "In2.Cu") (net 23))
  (segment (start 104.00284 86.823884) (end 104.031903 86.834053) (width 0.125) (layer "In2.Cu") (net 23))
  (segment (start 105.789224 85.475) (end 105.886193 85.485926) (width 0.125) (layer "In2.Cu") (net 23))
  (segment (start 103.954998 86.78573) (end 103.97677 86.807502) (width 0.125) (layer "In2.Cu") (net 23))
  (segment (start 103.435775 85.475) (end 103.489224 85.475) (width 0.125) (layer "In2.Cu") (net 23))
  (segment (start 105.395072 85.639074) (end 105.464073 85.570073) (width 0.125) (layer "In2.Cu") (net 23))
  (segment (start 102.996552 86.730597) (end 103 86.7) (width 0.125) (layer "In2.Cu") (net 23))
  (segment (start 106.228447 86.730597) (end 106.238616 86.75966) (width 0.125) (layer "In2.Cu") (net 23))
  (segment (start 106.989224 85.475) (end 107.086193 85.485926) (width 0.125) (layer "In2.Cu") (net 23))
  (segment (start 106.060926 85.570073) (end 106.129927 85.639074) (width 0.125) (layer "In2.Cu") (net 23))
  (segment (start 101.770001 86.78573) (end 101.786383 86.75966) (width 0.125) (layer "In2.Cu") (net 23))
  (segment (start 98.648229 86.807502) (end 98.670001 86.78573) (width 0.125) (layer "In2.Cu") (net 23))
  (segment (start 101.8 86.7) (end 101.8 85.910776) (width 0.125) (layer "In2.Cu") (net 23))
  (segment (start 102.970001 86.78573) (end 102.986383 86.75966) (width 0.125) (layer "In2.Cu") (net 23))
  (segment (start 102.235775 85.475) (end 102.289224 85.475) (width 0.125) (layer "In2.Cu") (net 23))
  (segment (start 98.7 86.7) (end 98.7 85.910776) (width 0.125) (layer "In2.Cu") (net 23))
  (segment (start 106.746699 85.518156) (end 106.838806 85.485926) (width 0.125) (layer "In2.Cu") (net 23))
  (segment (start 99.189224 85.475) (end 99.286193 85.485926) (width 0.125) (layer "In2.Cu") (net 23))
  (segment (start 106.470001 86.78573) (end 106.486383 86.75966) (width 0.125) (layer "In2.Cu") (net 23))
  (segment (start 102.922159 86.823884) (end 102.948229 86.807502) (width 0.125) (layer "In2.Cu") (net 23))
  (segment (start 100.781844 85.7217) (end 100.814074 85.813807) (width 0.125) (layer "In2.Cu") (net 23))
  (segment (start 99.654998 86.78573) (end 99.67677 86.807502) (width 0.125) (layer "In2.Cu") (net 23))
  (segment (start 103.246699 85.518156) (end 103.338806 85.485926) (width 0.125) (layer "In2.Cu") (net 23))
  (segment (start 102.714074 85.813807) (end 102.725 85.910776) (width 0.125) (layer "In2.Cu") (net 23))
  (segment (start 106.331903 86.834053) (end 106.3625 86.8375) (width 0.125) (layer "In2.Cu") (net 23))
  (segment (start 109.707566 86.335903) (end 109.758396 86.255008) (width 0.125) (layer "In2.Cu") (net 23))
  (segment (start 99.886383 86.75966) (end 99.896552 86.730597) (width 0.125) (layer "In2.Cu") (net 23))
  (segment (start 99.614074 85.813807) (end 99.625 85.910776) (width 0.125) (layer "In2.Cu") (net 23))
  (segment (start 106.27677 86.807502) (end 106.30284 86.823884) (width 0.125) (layer "In2.Cu") (net 23))
  (segment (start 107.329927 85.639074) (end 107.381844 85.7217) (width 0.125) (layer "In2.Cu") (net 23))
  (segment (start 101.786383 86.75966) (end 101.796552 86.730597) (width 0.125) (layer "In2.Cu") (net 23))
  (segment (start 107.50284 86.823884) (end 107.531903 86.834053) (width 0.125) (layer "In2.Cu") (net 23))
  (segment (start 103.095072 85.639074) (end 103.164073 85.570073) (width 0.125) (layer "In2.Cu") (net 23))
  (segment (start 106.422159 86.823884) (end 106.448229 86.807502) (width 0.125) (layer "In2.Cu") (net 23))
  (segment (start 96.1375 87.88269) (end 97.18269 86.8375) (width 0.125) (layer "In2.Cu") (net 23))
  (segment (start 103.6783 85.518156) (end 103.760926 85.570073) (width 0.125) (layer "In2.Cu") (net 23))
  (segment (start 110.593519 86.738127) (end 110.602972 86.765142) (width 0.125) (layer "In2.Cu") (net 23))
  (segment (start 101.8 85.910776) (end 101.810925 85.813807) (width 0.125) (layer "In2.Cu") (net 23))
  (segment (start 110.602972 86.765142) (end 110.6182 86.789377) (width 0.125) (layer "In2.Cu") (net 23))
  (segment (start 101.796552 86.730597) (end 101.8 86.7) (width 0.125) (layer "In2.Cu") (net 23))
  (segment (start 99.793096 86.834053) (end 99.822159 86.823884) (width 0.125) (layer "In2.Cu") (net 23))
  (segment (start 110.689688 86.834296) (end 110.71813 86.8375) (width 0.125) (layer "In2.Cu") (net 23))
  (segment (start 98.710925 85.813807) (end 98.743155 85.7217) (width 0.125) (layer "In2.Cu") (net 23))
  (segment (start 102.681844 85.7217) (end 102.714074 85.813807) (width 0.125) (layer "In2.Cu") (net 23))
  (segment (start 109.565941 86.834296) (end 109.592956 86.824843) (width 0.125) (layer "In2.Cu") (net 23))
  (segment (start 106.225 85.910776) (end 106.225 86.7) (width 0.125) (layer "In2.Cu") (net 23))
  (segment (start 107.438616 86.75966) (end 107.454998 86.78573) (width 0.125) (layer "In2.Cu") (net 23))
  (segment (start 102.046699 85.518156) (end 102.138806 85.485926) (width 0.125) (layer "In2.Cu") (net 23))
  (segment (start 106.5 86.7) (end 106.5 85.910776) (width 0.125) (layer "In2.Cu") (net 23))
  (segment (start 98.946699 85.518156) (end 99.038806 85.485926) (width 0.125) (layer "In2.Cu") (net 23))
  (segment (start 109.66211 86.738127) (end 109.665315 86.709685) (width 0.125) (layer "In2.Cu") (net 23))
  (segment (start 102.728447 86.730597) (end 102.738616 86.75966) (width 0.125) (layer "In2.Cu") (net 23))
  (segment (start 109.758396 86.255008) (end 109.825953 86.187451) (width 0.125) (layer "In2.Cu") (net 23))
  (segment (start 101.6625 86.8375) (end 101.693096 86.834053) (width 0.125) (layer "In2.Cu") (net 23))
  (segment (start 109.665315 86.709685) (end 109.665315 86.521019) (width 0.125) (layer "In2.Cu") (net 23))
  (segment (start 98.622159 86.823884) (end 98.648229 86.807502) (width 0.125) (layer "In2.Cu") (net 23))
  (segment (start 105.270001 86.78573) (end 105.286383 86.75966) (width 0.125) (layer "In2.Cu") (net 23))
  (segment (start 106.238616 86.75966) (end 106.254998 86.78573) (width 0.125) (layer "In2.Cu") (net 23))
  (segment (start 100.486193 85.485926) (end 100.5783 85.518156) (width 0.125) (layer "In2.Cu") (net 23))
  (segment (start 100.064073 85.570073) (end 100.146699 85.518156) (width 0.125) (layer "In2.Cu") (net 23))
  (segment (start 103.97677 86.807502) (end 104.00284 86.823884) (width 0.125) (layer "In2.Cu") (net 23))
  (segment (start 105.193096 86.834053) (end 105.222159 86.823884) (width 0.125) (layer "In2.Cu") (net 23))
  (segment (start 105.638806 85.485926) (end 105.735775 85.475) (width 0.125) (layer "In2.Cu") (net 23))
  (segment (start 103.925 86.7) (end 103.928447 86.730597) (width 0.125) (layer "In2.Cu") (net 23))
  (segment (start 110.590315 86.709685) (end 110.593519 86.738127) (width 0.125) (layer "In2.Cu") (net 23))
  (segment (start 103.881844 85.7217) (end 103.914074 85.813807) (width 0.125) (layer "In2.Cu") (net 23))
  (segment (start 99.628447 86.730597) (end 99.638616 86.75966) (width 0.125) (layer "In2.Cu") (net 23))
  (segment (start 109.652657 86.765142) (end 109.66211 86.738127) (width 0.125) (layer "In2.Cu") (net 23))
  (segment (start 102.831903 86.834053) (end 102.8625 86.8375) (width 0.125) (layer "In2.Cu") (net 23))
  (segment (start 105.3 86.7) (end 105.3 85.910776) (width 0.125) (layer "In2.Cu") (net 23))
  (segment (start 107.425 86.7) (end 107.428447 86.730597) (width 0.125) (layer "In2.Cu") (net 23))
  (segment (start 99.3783 85.518156) (end 99.460926 85.570073) (width 0.125) (layer "In2.Cu") (net 23))
  (segment (start 101.722159 86.823884) (end 101.748229 86.807502) (width 0.125) (layer "In2.Cu") (net 23))
  (segment (start 98.5625 86.8375) (end 98.593096 86.834053) (width 0.125) (layer "In2.Cu") (net 23))
  (segment (start 100.814074 85.813807) (end 100.825 85.910776) (width 0.125) (layer "In2.Cu") (net 23))
  (segment (start 103.925 85.910776) (end 103.925 86.7) (width 0.125) (layer "In2.Cu") (net 23))
  (segment (start 99.9 85.910776) (end 99.910925 85.813807) (width 0.125) (layer "In2.Cu") (net 23))
  (segment (start 107.428447 86.730597) (end 107.438616 86.75966) (width 0.125) (layer "In2.Cu") (net 23))
  (segment (start 107.454998 86.78573) (end 107.47677 86.807502) (width 0.125) (layer "In2.Cu") (net 23))
  (segment (start 102.4783 85.518156) (end 102.560926 85.570073) (width 0.125) (layer "In2.Cu") (net 23))
  (segment (start 106.3625 86.8375) (end 106.393096 86.834053) (width 0.125) (layer "In2.Cu") (net 23))
  (segment (start 102.725 85.910776) (end 102.725 86.7) (width 0.125) (layer "In2.Cu") (net 23))
  (segment (start 103.586193 85.485926) (end 103.6783 85.518156) (width 0.125) (layer "In2.Cu") (net 23))
  (segment (start 106.448229 86.807502) (end 106.470001 86.78573) (width 0.125) (layer "In2.Cu") (net 23))
  (segment (start 100.389224 85.475) (end 100.486193 85.485926) (width 0.125) (layer "In2.Cu") (net 23))
  (segment (start 105.3 85.910776) (end 105.310925 85.813807) (width 0.125) (layer "In2.Cu") (net 23))
  (segment (start 109.676012 86.426081) (end 109.707566 86.335903) (width 0.125) (layer "In2.Cu") (net 23))
  (segment (start 101.810925 85.813807) (end 101.843155 85.7217) (width 0.125) (layer "In2.Cu") (net 23))
  (segment (start 99.822159 86.823884) (end 99.848229 86.807502) (width 0.125) (layer "In2.Cu") (net 23))
  (segment (start 101.895072 85.639074) (end 101.964073 85.570073) (width 0.125) (layer "In2.Cu") (net 23))
  (segment (start 99.870001 86.78573) (end 99.886383 86.75966) (width 0.125) (layer "In2.Cu") (net 23))
  (segment (start 105.546699 85.518156) (end 105.638806 85.485926) (width 0.125) (layer "In2.Cu") (net 23))
  (segment (start 99.9 86.7) (end 99.9 85.910776) (width 0.125) (layer "In2.Cu") (net 23))
  (segment (start 99.638616 86.75966) (end 99.654998 86.78573) (width 0.125) (layer "In2.Cu") (net 23))
  (segment (start 99.731903 86.834053) (end 99.7625 86.8375) (width 0.125) (layer "In2.Cu") (net 23))
  (segment (start 107.531903 86.834053) (end 107.5625 86.8375) (width 0.125) (layer "In2.Cu") (net 23))
  (segment (start 110.163665 86.094369) (end 110.258603 86.105067) (width 0.125) (layer "In2.Cu") (net 23))
  (segment (start 96.1375 94.8) (end 96.1375 87.88269) (width 0.125) (layer "In2.Cu") (net 23))
  (segment (start 102.986383 86.75966) (end 102.996552 86.730597) (width 0.125) (layer "In2.Cu") (net 23))
  (segment (start 106.30284 86.823884) (end 106.331903 86.834053) (width 0.125) (layer "In2.Cu") (net 23))
  (segment (start 110.579617 86.426081) (end 110.590315 86.521019) (width 0.125) (layer "In2.Cu") (net 23))
  (segment (start 110.590315 86.521019) (end 110.590315 86.709685) (width 0.125) (layer "In2.Cu") (net 23))
  (segment (start 100.825 85.910776) (end 100.825 86.7) (width 0.125) (layer "In2.Cu") (net 23))
  (segment (start 99.70284 86.823884) (end 99.731903 86.834053) (width 0.125) (layer "In2.Cu") (net 23))
  (segment (start 102.560926 85.570073) (end 102.629927 85.639074) (width 0.125) (layer "In2.Cu") (net 23))
  (segment (start 102.754998 86.78573) (end 102.77677 86.807502) (width 0.125) (layer "In2.Cu") (net 23))
  (segment (start 107.5625 86.8375) (end 109.5375 86.8375) (width 0.125) (layer "In2.Cu") (net 23))
  (segment (start 106.496552 86.730597) (end 106.5 86.7) (width 0.125) (layer "In2.Cu") (net 23))
  (segment (start 99.625 85.910776) (end 99.625 86.7) (width 0.125) (layer "In2.Cu") (net 23))
  (segment (start 107.086193 85.485926) (end 107.1783 85.518156) (width 0.125) (layer "In2.Cu") (net 23))
  (segment (start 110.348781 86.136621) (end 110.429676 86.187451) (width 0.125) (layer "In2.Cu") (net 23))
  (segment (start 100.335775 85.475) (end 100.389224 85.475) (width 0.125) (layer "In2.Cu") (net 23))
  (segment (start 104.0625 86.8375) (end 105.1625 86.8375) (width 0.125) (layer "In2.Cu") (net 23))
  (segment (start 109.906848 86.136621) (end 109.997026 86.105067) (width 0.125) (layer "In2.Cu") (net 23))
  (segment (start 95.9375 95) (end 96.1375 94.8) (width 0.125) (layer "In2.Cu") (net 23))
  (segment (start 102.893096 86.834053) (end 102.922159 86.823884) (width 0.125) (layer "In2.Cu") (net 23))
  (segment (start 99.135775 85.475) (end 99.189224 85.475) (width 0.125) (layer "In2.Cu") (net 23))
  (segment (start 99.910925 85.813807) (end 99.943155 85.7217) (width 0.125) (layer "In2.Cu") (net 23))
  (segment (start 96.06 93.95) (end 96.06 94.175001) (width 0.125) (layer "B.Cu") (net 23))
  (segment (start 96.175 94.290001) (end 96.175 94.7625) (width 0.125) (layer "B.Cu") (net 23))
  (segment (start 96.06 94.175001) (end 96.175 94.290001) (width 0.125) (layer "B.Cu") (net 23))
  (segment (start 96.175 94.7625) (end 95.9375 95) (width 0.125) (layer "B.Cu") (net 23))
  (segment (start 121.25 84.650001) (end 121.375 84.775001) (width 0.125) (layer "F.Cu") (net 24))
  (segment (start 121.375 84.775001) (end 121.375 86.531531) (width 0.125) (layer "F.Cu") (net 24))
  (segment (start 121.25 83.45) (end 121.25 84.650001) (width 0.125) (layer "F.Cu") (net 24))
  (segment (start 121.514732 86.671263) (end 121.514732 87.00714) (width 0.125) (layer "F.Cu") (net 24))
  (segment (start 121.375 86.531531) (end 121.514732 86.671263) (width 0.125) (layer "F.Cu") (net 24))
  (via (at 96.6625 95) (size 0.6) (drill 0.25) (layers "F.Cu" "B.Cu") (net 24))
  (via (at 121.514732 87.00714) (size 0.6) (drill 0.25) (layers "F.Cu" "B.Cu") (net 24))
  (segment (start 102.2625 85.8) (end 102.293096 85.803448) (width 0.125) (layer "In2.Cu") (net 24))
  (segment (start 103.6 85.9375) (end 103.6 86.726725) (width 0.125) (layer "In2.Cu") (net 24))
  (segment (start 100.3625 85.8) (end 100.393096 85.803448) (width 0.125) (layer "In2.Cu") (net 24))
  (segment (start 110.089688 86.422574) (end 110.11813 86.419369) (width 0.125) (layer "In2.Cu") (net 24))
  (segment (start 102.443155 86.915801) (end 102.495072 86.998427) (width 0.125) (layer "In2.Cu") (net 24))
  (segment (start 99.395072 86.998427) (end 99.464073 87.067428) (width 0.125) (layer "In2.Cu") (net 24))
  (segment (start 106.146699 87.119345) (end 106.238806 87.151575) (width 0.125) (layer "In2.Cu") (net 24))
  (segment (start 96.4625 94.8) (end 96.4625 88.01731) (width 0.125) (layer "In2.Cu") (net 24))
  (segment (start 106.931903 85.803448) (end 106.9625 85.8) (width 0.125) (layer "In2.Cu") (net 24))
  (segment (start 106.9625 85.8) (end 106.993096 85.803448) (width 0.125) (layer "In2.Cu") (net 24))
  (segment (start 110.038438 86.447255) (end 110.062673 86.432027) (width 0.125) (layer "In2.Cu") (net 24))
  (segment (start 107.022159 85.813617) (end 107.048229 85.829999) (width 0.125) (layer "In2.Cu") (net 24))
  (segment (start 106.993096 85.803448) (end 107.022159 85.813617) (width 0.125) (layer "In2.Cu") (net 24))
  (segment (start 103.610925 86.823694) (end 103.643155 86.915801) (width 0.125) (layer "In2.Cu") (net 24))
  (segment (start 110.597026 87.151803) (end 110.691964 87.1625) (width 0.125) (layer "In2.Cu") (net 24))
  (segment (start 102.835775 87.1625) (end 102.889224 87.1625) (width 0.125) (layer "In2.Cu") (net 24))
  (segment (start 101.689224 87.1625) (end 101.786193 87.151575) (width 0.125) (layer "In2.Cu") (net 24))
  (segment (start 99.10284 85.813617) (end 99.131903 85.803448) (width 0.125) (layer "In2.Cu") (net 24))
  (segment (start 103.328447 85.906904) (end 103.338616 85.877841) (width 0.125) (layer "In2.Cu") (net 24))
  (segment (start 121.514732 86.724296) (end 121.514732 87.00714) (width 0.125) (layer "In2.Cu") (net 24))
  (segment (start 100.838806 87.151575) (end 100.935775 87.1625) (width 0.125) (layer "In2.Cu") (net 24))
  (segment (start 100.664073 87.067428) (end 100.746699 87.119345) (width 0.125) (layer "In2.Cu") (net 24))
  (segment (start 100.129927 86.998427) (end 100.181844 86.915801) (width 0.125) (layer "In2.Cu") (net 24))
  (segment (start 105.7625 85.8) (end 105.793096 85.803448) (width 0.125) (layer "In2.Cu") (net 24))
  (segment (start 109.990315 86.547184) (end 109.993519 86.518743) (width 0.125) (layer "In2.Cu") (net 24))
  (segment (start 107.048229 85.829999) (end 107.070001 85.851771) (width 0.125) (layer "In2.Cu") (net 24))
  (segment (start 105.625 86.726725) (end 105.625 85.9375) (width 0.125) (layer "In2.Cu") (net 24))
  (segment (start 99.1625 85.8) (end 99.193096 85.803448) (width 0.125) (layer "In2.Cu") (net 24))
  (segment (start 99.028447 85.906904) (end 99.038616 85.877841) (width 0.125) (layer "In2.Cu") (net 24))
  (segment (start 100.543155 86.915801) (end 100.595072 86.998427) (width 0.125) (layer "In2.Cu") (net 24))
  (segment (start 99.735775 87.1625) (end 99.789224 87.1625) (width 0.125) (layer "In2.Cu") (net 24))
  (segment (start 109.897233 87.001862) (end 109.948063 86.920967) (width 0.125) (layer "In2.Cu") (net 24))
  (segment (start 105.460926 87.067428) (end 105.529927 86.998427) (width 0.125) (layer "In2.Cu") (net 24))
  (segment (start 103.522159 85.813617) (end 103.548229 85.829999) (width 0.125) (layer "In2.Cu") (net 24))
  (segment (start 103.338616 85.877841) (end 103.354998 85.851771) (width 0.125) (layer "In2.Cu") (net 24))
  (segment (start 103.160926 87.067428) (end 103.229927 86.998427) (width 0.125) (layer "In2.Cu") (net 24))
  (segment (start 102.410925 86.823694) (end 102.443155 86.915801) (width 0.125) (layer "In2.Cu") (net 24))
  (segment (start 106.838616 85.877841) (end 106.854998 85.851771) (width 0.125) (layer "In2.Cu") (net 24))
  (segment (start 105.614074 86.823694) (end 105.625 86.726725) (width 0.125) (layer "In2.Cu") (net 24))
  (segment (start 103.6 86.726725) (end 103.610925 86.823694) (width 0.125) (layer "In2.Cu") (net 24))
  (segment (start 98.686193 87.151575) (end 98.7783 87.119345) (width 0.125) (layer "In2.Cu") (net 24))
  (segment (start 98.589224 87.1625) (end 98.686193 87.151575) (width 0.125) (layer "In2.Cu") (net 24))
  (segment (start 98.981844 86.915801) (end 99.014074 86.823694) (width 0.125) (layer "In2.Cu") (net 24))
  (segment (start 99.286383 85.877841) (end 99.296552 85.906904) (width 0.125) (layer "In2.Cu") (net 24))
  (segment (start 100.470001 85.851771) (end 100.486383 85.877841) (width 0.125) (layer "In2.Cu") (net 24))
  (segment (start 96.4625 88.01731) (end 97.31731 87.1625) (width 0.125) (layer "In2.Cu") (net 24))
  (segment (start 110.425953 87.069419) (end 110.506848 87.120249) (width 0.125) (layer "In2.Cu") (net 24))
  (segment (start 105.581844 86.915801) (end 105.614074 86.823694) (width 0.125) (layer "In2.Cu") (net 24))
  (segment (start 105.886383 85.877841) (end 105.896552 85.906904) (width 0.125) (layer "In2.Cu") (net 24))
  (segment (start 100.935775 87.1625) (end 101.689224 87.1625) (width 0.125) (layer "In2.Cu") (net 24))
  (segment (start 100.496552 85.906904) (end 100.5 85.9375) (width 0.125) (layer "In2.Cu") (net 24))
  (segment (start 99.343155 86.915801) (end 99.395072 86.998427) (width 0.125) (layer "In2.Cu") (net 24))
  (segment (start 105.943155 86.915801) (end 105.995072 86.998427) (width 0.125) (layer "In2.Cu") (net 24))
  (segment (start 105.70284 85.813617) (end 105.731903 85.803448) (width 0.125) (layer "In2.Cu") (net 24))
  (segment (start 103.325 85.9375) (end 103.328447 85.906904) (width 0.125) (layer "In2.Cu") (net 24))
  (segment (start 110.062673 86.432027) (end 110.089688 86.422574) (width 0.125) (layer "In2.Cu") (net 24))
  (segment (start 105.793096 85.803448) (end 105.822159 85.813617) (width 0.125) (layer "In2.Cu") (net 24))
  (segment (start 107.110925 86.823694) (end 107.143155 86.915801) (width 0.125) (layer "In2.Cu") (net 24))
  (segment (start 110.691964 87.1625) (end 118.81731 87.1625) (width 0.125) (layer "In2.Cu") (net 24))
  (segment (start 100.5 85.9375) (end 100.5 86.726725) (width 0.125) (layer "In2.Cu") (net 24))
  (segment (start 102.322159 85.813617) (end 102.348229 85.829999) (width 0.125) (layer "In2.Cu") (net 24))
  (segment (start 103.4625 85.8) (end 103.493096 85.803448) (width 0.125) (layer "In2.Cu") (net 24))
  (segment (start 110.265315 86.735851) (end 110.276012 86.830789) (width 0.125) (layer "In2.Cu") (net 24))
  (segment (start 107.195072 86.998427) (end 107.264073 87.067428) (width 0.125) (layer "In2.Cu") (net 24))
  (segment (start 102.738806 87.151575) (end 102.835775 87.1625) (width 0.125) (layer "In2.Cu") (net 24))
  (segment (start 105.625 85.9375) (end 105.628447 85.906904) (width 0.125) (layer "In2.Cu") (net 24))
  (segment (start 105.896552 85.906904) (end 105.9 85.9375) (width 0.125) (layer "In2.Cu") (net 24))
  (segment (start 107.070001 85.851771) (end 107.086383 85.877841) (width 0.125) (layer "In2.Cu") (net 24))
  (segment (start 99.546699 87.119345) (end 99.638806 87.151575) (width 0.125) (layer "In2.Cu") (net 24))
  (segment (start 96.6625 95) (end 96.4625 94.8) (width 0.125) (layer "In2.Cu") (net 24))
  (segment (start 106.729927 86.998427) (end 106.781844 86.915801) (width 0.125) (layer "In2.Cu") (net 24))
  (segment (start 100.746699 87.119345) (end 100.838806 87.151575) (width 0.125) (layer "In2.Cu") (net 24))
  (segment (start 106.660926 87.067428) (end 106.729927 86.998427) (width 0.125) (layer "In2.Cu") (net 24))
  (segment (start 100.225 85.9375) (end 100.228447 85.906904) (width 0.125) (layer "In2.Cu") (net 24))
  (segment (start 105.189224 87.1625) (end 105.286193 87.151575) (width 0.125) (layer "In2.Cu") (net 24))
  (segment (start 106.825 85.9375) (end 106.828447 85.906904) (width 0.125) (layer "In2.Cu") (net 24))
  (segment (start 106.064073 87.067428) (end 106.146699 87.119345) (width 0.125) (layer "In2.Cu") (net 24))
  (segment (start 103.938806 87.151575) (end 104.035775 87.1625) (width 0.125) (layer "In2.Cu") (net 24))
  (segment (start 105.822159 85.813617) (end 105.848229 85.829999) (width 0.125) (layer "In2.Cu") (net 24))
  (segment (start 99.038616 85.877841) (end 99.054998 85.851771) (width 0.125) (layer "In2.Cu") (net 24))
  (segment (start 102.154998 85.851771) (end 102.17677 85.829999) (width 0.125) (layer "In2.Cu") (net 24))
  (segment (start 106.87677 85.829999) (end 106.90284 85.813617) (width 0.125) (layer "In2.Cu") (net 24))
  (segment (start 99.193096 85.803448) (end 99.222159 85.813617) (width 0.125) (layer "In2.Cu") (net 24))
  (segment (start 107.096552 85.906904) (end 107.1 85.9375) (width 0.125) (layer "In2.Cu") (net 24))
  (segment (start 99.3 86.726725) (end 99.310925 86.823694) (width 0.125) (layer "In2.Cu") (net 24))
  (segment (start 99.886193 87.151575) (end 99.9783 87.119345) (width 0.125) (layer "In2.Cu") (net 24))
  (segment (start 107.264073 87.067428) (end 107.346699 87.119345) (width 0.125) (layer "In2.Cu") (net 24))
  (segment (start 100.225 86.726725) (end 100.225 85.9375) (width 0.125) (layer "In2.Cu") (net 24))
  (segment (start 98.7783 87.119345) (end 98.860926 87.067428) (width 0.125) (layer "In2.Cu") (net 24))
  (segment (start 102.17677 85.829999) (end 102.20284 85.813617) (width 0.125) (layer "In2.Cu") (net 24))
  (segment (start 106.825 86.726725) (end 106.825 85.9375) (width 0.125) (layer "In2.Cu") (net 24))
  (segment (start 102.348229 85.829999) (end 102.370001 85.851771) (width 0.125) (layer "In2.Cu") (net 24))
  (segment (start 103.0783 87.119345) (end 103.160926 87.067428) (width 0.125) (layer "In2.Cu") (net 24))
  (segment (start 102.20284 85.813617) (end 102.231903 85.803448) (width 0.125) (layer "In2.Cu") (net 24))
  (segment (start 103.695072 86.998427) (end 103.764073 87.067428) (width 0.125) (layer "In2.Cu") (net 24))
  (segment (start 103.229927 86.998427) (end 103.281844 86.915801) (width 0.125) (layer "In2.Cu") (net 24))
  (segment (start 102.386383 85.877841) (end 102.396552 85.906904) (width 0.125) (layer "In2.Cu") (net 24))
  (segment (start 102.293096 85.803448) (end 102.322159 85.813617) (width 0.125) (layer "In2.Cu") (net 24))
  (segment (start 103.354998 85.851771) (end 103.37677 85.829999) (width 0.125) (layer "In2.Cu") (net 24))
  (segment (start 110.252657 86.491728) (end 110.26211 86.518743) (width 0.125) (layer "In2.Cu") (net 24))
  (segment (start 100.486383 85.877841) (end 100.496552 85.906904) (width 0.125) (layer "In2.Cu") (net 24))
  (segment (start 102.138616 85.877841) (end 102.154998 85.851771) (width 0.125) (layer "In2.Cu") (net 24))
  (segment (start 99.464073 87.067428) (end 99.546699 87.119345) (width 0.125) (layer "In2.Cu") (net 24))
  (segment (start 119.81731 86.1625) (end 120.952936 86.1625) (width 0.125) (layer "In2.Cu") (net 24))
  (segment (start 104.035775 87.1625) (end 105.189224 87.1625) (width 0.125) (layer "In2.Cu") (net 24))
  (segment (start 100.448229 85.829999) (end 100.470001 85.851771) (width 0.125) (layer "In2.Cu") (net 24))
  (segment (start 100.238616 85.877841) (end 100.254998 85.851771) (width 0.125) (layer "In2.Cu") (net 24))
  (segment (start 105.654998 85.851771) (end 105.67677 85.829999) (width 0.125) (layer "In2.Cu") (net 24))
  (segment (start 109.748781 87.120249) (end 109.829676 87.069419) (width 0.125) (layer "In2.Cu") (net 24))
  (segment (start 110.276012 86.830789) (end 110.307566 86.920967) (width 0.125) (layer "In2.Cu") (net 24))
  (segment (start 102.646699 87.119345) (end 102.738806 87.151575) (width 0.125) (layer "In2.Cu") (net 24))
  (segment (start 105.848229 85.829999) (end 105.870001 85.851771) (width 0.125) (layer "In2.Cu") (net 24))
  (segment (start 106.854998 85.851771) (end 106.87677 85.829999) (width 0.125) (layer "In2.Cu") (net 24))
  (segment (start 102.125 85.9375) (end 102.128447 85.906904) (width 0.125) (layer "In2.Cu") (net 24))
  (segment (start 106.781844 86.915801) (end 106.814074 86.823694) (width 0.125) (layer "In2.Cu") (net 24))
  (segment (start 102.564073 87.067428) (end 102.646699 87.119345) (width 0.125) (layer "In2.Cu") (net 24))
  (segment (start 103.40284 85.813617) (end 103.431903 85.803448) (width 0.125) (layer "In2.Cu") (net 24))
  (segment (start 100.393096 85.803448) (end 100.422159 85.813617) (width 0.125) (layer "In2.Cu") (net 24))
  (segment (start 110.506848 87.120249) (end 110.597026 87.151803) (width 0.125) (layer "In2.Cu") (net 24))
  (segment (start 107.086383 85.877841) (end 107.096552 85.906904) (width 0.125) (layer "In2.Cu") (net 24))
  (segment (start 105.910925 86.823694) (end 105.943155 86.915801) (width 0.125) (layer "In2.Cu") (net 24))
  (segment (start 101.960926 87.067428) (end 102.029927 86.998427) (width 0.125) (layer "In2.Cu") (net 24))
  (segment (start 100.5 86.726725) (end 100.510925 86.823694) (width 0.125) (layer "In2.Cu") (net 24))
  (segment (start 109.993519 86.518743) (end 110.002972 86.491728) (width 0.125) (layer "In2.Cu") (net 24))
  (segment (start 110.217191 86.447255) (end 110.237429 86.467493) (width 0.125) (layer "In2.Cu") (net 24))
  (segment (start 103.586383 85.877841) (end 103.596552 85.906904) (width 0.125) (layer "In2.Cu") (net 24))
  (segment (start 105.9 86.726725) (end 105.910925 86.823694) (width 0.125) (layer "In2.Cu") (net 24))
  (segment (start 106.486193 87.151575) (end 106.5783 87.119345) (width 0.125) (layer "In2.Cu") (net 24))
  (segment (start 100.060926 87.067428) (end 100.129927 86.998427) (width 0.125) (layer "In2.Cu") (net 24))
  (segment (start 106.828447 85.906904) (end 106.838616 85.877841) (width 0.125) (layer "In2.Cu") (net 24))
  (segment (start 99.638806 87.151575) (end 99.735775 87.1625) (width 0.125) (layer "In2.Cu") (net 24))
  (segment (start 103.431903 85.803448) (end 103.4625 85.8) (width 0.125) (layer "In2.Cu") (net 24))
  (segment (start 100.510925 86.823694) (end 100.543155 86.915801) (width 0.125) (layer "In2.Cu") (net 24))
  (segment (start 103.846699 87.119345) (end 103.938806 87.151575) (width 0.125) (layer "In2.Cu") (net 24))
  (segment (start 107.1 86.726725) (end 107.110925 86.823694) (width 0.125) (layer "In2.Cu") (net 24))
  (segment (start 109.948063 86.920967) (end 109.979617 86.830789) (width 0.125) (layer "In2.Cu") (net 24))
  (segment (start 106.5783 87.119345) (end 106.660926 87.067428) (width 0.125) (layer "In2.Cu") (net 24))
  (segment (start 109.563665 87.1625) (end 109.658603 87.151803) (width 0.125) (layer "In2.Cu") (net 24))
  (segment (start 101.786193 87.151575) (end 101.8783 87.119345) (width 0.125) (layer "In2.Cu") (net 24))
  (segment (start 102.396552 85.906904) (end 102.4 85.9375) (width 0.125) (layer "In2.Cu") (net 24))
  (segment (start 106.238806 87.151575) (end 106.335775 87.1625) (width 0.125) (layer "In2.Cu") (net 24))
  (segment (start 105.9 85.9375) (end 105.9 86.726725) (width 0.125) (layer "In2.Cu") (net 24))
  (segment (start 100.181844 86.915801) (end 100.214074 86.823694) (width 0.125) (layer "In2.Cu") (net 24))
  (segment (start 102.231903 85.803448) (end 102.2625 85.8) (width 0.125) (layer "In2.Cu") (net 24))
  (segment (start 107.1 85.9375) (end 107.1 86.726725) (width 0.125) (layer "In2.Cu") (net 24))
  (segment (start 99.296552 85.906904) (end 99.3 85.9375) (width 0.125) (layer "In2.Cu") (net 24))
  (segment (start 99.3 85.9375) (end 99.3 86.726725) (width 0.125) (layer "In2.Cu") (net 24))
  (segment (start 105.3783 87.119345) (end 105.460926 87.067428) (width 0.125) (layer "In2.Cu") (net 24))
  (segment (start 100.30284 85.813617) (end 100.331903 85.803448) (width 0.125) (layer "In2.Cu") (net 24))
  (segment (start 98.929927 86.998427) (end 98.981844 86.915801) (width 0.125) (layer "In2.Cu") (net 24))
  (segment (start 100.595072 86.998427) (end 100.664073 87.067428) (width 0.125) (layer "In2.Cu") (net 24))
  (segment (start 100.422159 85.813617) (end 100.448229 85.829999) (width 0.125) (layer "In2.Cu") (net 24))
  (segment (start 102.114074 86.823694) (end 102.125 86.726725) (width 0.125) (layer "In2.Cu") (net 24))
  (segment (start 105.529927 86.998427) (end 105.581844 86.915801) (width 0.125) (layer "In2.Cu") (net 24))
  (segment (start 107.535775 87.1625) (end 109.563665 87.1625) (width 0.125) (layer "In2.Cu") (net 24))
  (segment (start 109.829676 87.069419) (end 109.897233 87.001862) (width 0.125) (layer "In2.Cu") (net 24))
  (segment (start 105.286193 87.151575) (end 105.3783 87.119345) (width 0.125) (layer "In2.Cu") (net 24))
  (segment (start 110.237429 86.467493) (end 110.252657 86.491728) (width 0.125) (layer "In2.Cu") (net 24))
  (segment (start 103.643155 86.915801) (end 103.695072 86.998427) (width 0.125) (layer "In2.Cu") (net 24))
  (segment (start 100.214074 86.823694) (end 100.225 86.726725) (width 0.125) (layer "In2.Cu") (net 24))
  (segment (start 110.26211 86.518743) (end 110.265315 86.547184) (width 0.125) (layer "In2.Cu") (net 24))
  (segment (start 110.358396 87.001862) (end 110.425953 87.069419) (width 0.125) (layer "In2.Cu") (net 24))
  (segment (start 105.731903 85.803448) (end 105.7625 85.8) (width 0.125) (layer "In2.Cu") (net 24))
  (segment (start 98.860926 87.067428) (end 98.929927 86.998427) (width 0.125) (layer "In2.Cu") (net 24))
  (segment (start 99.310925 86.823694) (end 99.343155 86.915801) (width 0.125) (layer "In2.Cu") (net 24))
  (segment (start 99.9783 87.119345) (end 100.060926 87.067428) (width 0.125) (layer "In2.Cu") (net 24))
  (segment (start 110.1375 86.419369) (end 110.165941 86.422574) (width 0.125) (layer "In2.Cu") (net 24))
  (segment (start 99.789224 87.1625) (end 99.886193 87.151575) (width 0.125) (layer "In2.Cu") (net 24))
  (segment (start 97.31731 87.1625) (end 98.589224 87.1625) (width 0.125) (layer "In2.Cu") (net 24))
  (segment (start 105.995072 86.998427) (end 106.064073 87.067428) (width 0.125) (layer "In2.Cu") (net 24))
  (segment (start 107.346699 87.119345) (end 107.438806 87.151575) (width 0.125) (layer "In2.Cu") (net 24))
  (segment (start 100.254998 85.851771) (end 100.27677 85.829999) (width 0.125) (layer "In2.Cu") (net 24))
  (segment (start 102.4 86.726725) (end 102.410925 86.823694) (width 0.125) (layer "In2.Cu") (net 24))
  (segment (start 103.596552 85.906904) (end 103.6 85.9375) (width 0.125) (layer "In2.Cu") (net 24))
  (segment (start 99.131903 85.803448) (end 99.1625 85.8) (width 0.125) (layer "In2.Cu") (net 24))
  (segment (start 120.952936 86.1625) (end 121.514732 86.724296) (width 0.125) (layer "In2.Cu") (net 24))
  (segment (start 118.81731 87.1625) (end 119.81731 86.1625) (width 0.125) (layer "In2.Cu") (net 24))
  (segment (start 100.331903 85.803448) (end 100.3625 85.8) (width 0.125) (layer "In2.Cu") (net 24))
  (segment (start 99.054998 85.851771) (end 99.07677 85.829999) (width 0.125) (layer "In2.Cu") (net 24))
  (segment (start 102.370001 85.851771) (end 102.386383 85.877841) (width 0.125) (layer "In2.Cu") (net 24))
  (segment (start 100.228447 85.906904) (end 100.238616 85.877841) (width 0.125) (layer "In2.Cu") (net 24))
  (segment (start 100.27677 85.829999) (end 100.30284 85.813617) (width 0.125) (layer "In2.Cu") (net 24))
  (segment (start 110.307566 86.920967) (end 110.358396 87.001862) (width 0.125) (layer "In2.Cu") (net 24))
  (segment (start 102.889224 87.1625) (end 102.986193 87.151575) (width 0.125) (layer "In2.Cu") (net 24))
  (segment (start 102.029927 86.998427) (end 102.081844 86.915801) (width 0.125) (layer "In2.Cu") (net 24))
  (segment (start 99.248229 85.829999) (end 99.270001 85.851771) (width 0.125) (layer "In2.Cu") (net 24))
  (segment (start 109.979617 86.830789) (end 109.990315 86.735851) (width 0.125) (layer "In2.Cu") (net 24))
  (segment (start 105.628447 85.906904) (end 105.638616 85.877841) (width 0.125) (layer "In2.Cu") (net 24))
  (segment (start 110.0182 86.467493) (end 110.038438 86.447255) (width 0.125) (layer "In2.Cu") (net 24))
  (segment (start 99.014074 86.823694) (end 99.025 86.726725) (width 0.125) (layer "In2.Cu") (net 24))
  (segment (start 103.325 86.726725) (end 103.325 85.9375) (width 0.125) (layer "In2.Cu") (net 24))
  (segment (start 99.025 85.9375) (end 99.028447 85.906904) (width 0.125) (layer "In2.Cu") (net 24))
  (segment (start 99.025 86.726725) (end 99.025 85.9375) (width 0.125) (layer "In2.Cu") (net 24))
  (segment (start 99.270001 85.851771) (end 99.286383 85.877841) (width 0.125) (layer "In2.Cu") (net 24))
  (segment (start 107.438806 87.151575) (end 107.535775 87.1625) (width 0.125) (layer "In2.Cu") (net 24))
  (segment (start 107.143155 86.915801) (end 107.195072 86.998427) (width 0.125) (layer "In2.Cu") (net 24))
  (segment (start 102.128447 85.906904) (end 102.138616 85.877841) (width 0.125) (layer "In2.Cu") (net 24))
  (segment (start 102.4 85.9375) (end 102.4 86.726725) (width 0.125) (layer "In2.Cu") (net 24))
  (segment (start 101.8783 87.119345) (end 101.960926 87.067428) (width 0.125) (layer "In2.Cu") (net 24))
  (segment (start 102.495072 86.998427) (end 102.564073 87.067428) (width 0.125) (layer "In2.Cu") (net 24))
  (segment (start 102.125 86.726725) (end 102.125 85.9375) (width 0.125) (layer "In2.Cu") (net 24))
  (segment (start 110.165941 86.422574) (end 110.192956 86.432027) (width 0.125) (layer "In2.Cu") (net 24))
  (segment (start 102.081844 86.915801) (end 102.114074 86.823694) (width 0.125) (layer "In2.Cu") (net 24))
  (segment (start 103.281844 86.915801) (end 103.314074 86.823694) (width 0.125) (layer "In2.Cu") (net 24))
  (segment (start 103.570001 85.851771) (end 103.586383 85.877841) (width 0.125) (layer "In2.Cu") (net 24))
  (segment (start 109.658603 87.151803) (end 109.748781 87.120249) (width 0.125) (layer "In2.Cu") (net 24))
  (segment (start 103.37677 85.829999) (end 103.40284 85.813617) (width 0.125) (layer "In2.Cu") (net 24))
  (segment (start 103.548229 85.829999) (end 103.570001 85.851771) (width 0.125) (layer "In2.Cu") (net 24))
  (segment (start 106.814074 86.823694) (end 106.825 86.726725) (width 0.125) (layer "In2.Cu") (net 24))
  (segment (start 106.389224 87.1625) (end 106.486193 87.151575) (width 0.125) (layer "In2.Cu") (net 24))
  (segment (start 110.002972 86.491728) (end 110.0182 86.467493) (width 0.125) (layer "In2.Cu") (net 24))
  (segment (start 103.314074 86.823694) (end 103.325 86.726725) (width 0.125) (layer "In2.Cu") (net 24))
  (segment (start 110.265315 86.547184) (end 110.265315 86.735851) (width 0.125) (layer "In2.Cu") (net 24))
  (segment (start 110.11813 86.419369) (end 110.1375 86.419369) (width 0.125) (layer "In2.Cu") (net 24))
  (segment (start 105.67677 85.829999) (end 105.70284 85.813617) (width 0.125) (layer "In2.Cu") (net 24))
  (segment (start 106.90284 85.813617) (end 106.931903 85.803448) (width 0.125) (layer "In2.Cu") (net 24))
  (segment (start 110.192956 86.432027) (end 110.217191 86.447255) (width 0.125) (layer "In2.Cu") (net 24))
  (segment (start 106.335775 87.1625) (end 106.389224 87.1625) (width 0.125) (layer "In2.Cu") (net 24))
  (segment (start 103.493096 85.803448) (end 103.522159 85.813617) (width 0.125) (layer "In2.Cu") (net 24))
  (segment (start 99.222159 85.813617) (end 99.248229 85.829999) (width 0.125) (layer "In2.Cu") (net 24))
  (segment (start 105.870001 85.851771) (end 105.886383 85.877841) (width 0.125) (layer "In2.Cu") (net 24))
  (segment (start 103.764073 87.067428) (end 103.846699 87.119345) (width 0.125) (layer "In2.Cu") (net 24))
  (segment (start 102.986193 87.151575) (end 103.0783 87.119345) (width 0.125) (layer "In2.Cu") (net 24))
  (segment (start 105.638616 85.877841) (end 105.654998 85.851771) (width 0.125) (layer "In2.Cu") (net 24))
  (segment (start 109.990315 86.735851) (end 109.990315 86.547184) (width 0.125) (layer "In2.Cu") (net 24))
  (segment (start 99.07677 85.829999) (end 99.10284 85.813617) (width 0.125) (layer "In2.Cu") (net 24))
  (segment (start 96.425 94.290001) (end 96.425 94.7625) (width 0.125) (layer "B.Cu") (net 24))
  (segment (start 96.54 94.175001) (end 96.425 94.290001) (width 0.125) (layer "B.Cu") (net 24))
  (segment (start 96.54 93.95) (end 96.54 94.175001) (width 0.125) (layer "B.Cu") (net 24))
  (segment (start 96.425 94.7625) (end 96.6625 95) (width 0.125) (layer "B.Cu") (net 24))
  (segment (start 122.307239 87.869539) (end 122.407185 87.869539) (width 0.125) (layer "F.Cu") (net 25))
  (segment (start 119.875 84.775001) (end 119.875 87.751778) (width 0.125) (layer "F.Cu") (net 25))
  (segment (start 119.75 83.45) (end 119.75 84.650001) (width 0.125) (layer "F.Cu") (net 25))
  (segment (start 119.75 84.650001) (end 119.875 84.775001) (width 0.125) (layer "F.Cu") (net 25))
  (segment (start 121.851778 88.325) (end 122.307239 87.869539) (width 0.125) (layer "F.Cu") (net 25))
  (segment (start 120.448222 88.325) (end 121.851778 88.325) (width 0.125) (layer "F.Cu") (net 25))
  (segment (start 119.875 87.751778) (end 120.448222 88.325) (width 0.125) (layer "F.Cu") (net 25))
  (segment (start 122.407185 87.869539) (end 122.682185 88.144539) (width 0.125) (layer "F.Cu") (net 25))
  (via (at 97.9625 96) (size 0.6) (drill 0.25) (layers "F.Cu" "B.Cu") (net 25))
  (via (at 122.682185 88.144539) (size 0.6) (drill 0.25) (layers "F.Cu" "B.Cu") (net 25))
  (segment (start 104.071552 88.462271) (end 104.075 88.492867) (width 0.125) (layer "In2.Cu") (net 25))
  (segment (start 102.013806 90.558707) (end 102.110775 90.569633) (width 0.125) (layer "In2.Cu") (net 25))
  (segment (start 103.310775 90.569633) (end 103.364224 90.569633) (width 0.125) (layer "In2.Cu") (net 25))
  (segment (start 105.05177 89.492498) (end 105.07784 89.476116) (width 0.125) (layer "In2.Cu") (net 25))
  (segment (start 103.968096 88.358815) (end 103.997159 88.368984) (width 0.125) (layer "In2.Cu") (net 25))
  (segment (start 105.003447 89.569403) (end 105.013616 89.54034) (width 0.125) (layer "In2.Cu") (net 25))
  (segment (start 100.3375 89.4625) (end 100.368096 89.465947) (width 0.125) (layer "In2.Cu") (net 25))
  (segment (start 104.661193 90.558707) (end 104.7533 90.526477) (width 0.125) (layer "In2.Cu") (net 25))
  (segment (start 101.47784 89.476116) (end 101.506903 89.465947) (width 0.125) (layer "In2.Cu") (net 25))
  (segment (start 104.023229 88.385366) (end 104.045001 88.407138) (width 0.125) (layer "In2.Cu") (net 25))
  (segment (start 103.8 88.492867) (end 103.803447 88.462271) (width 0.125) (layer "In2.Cu") (net 25))
  (segment (start 102.875 90.133857) (end 102.885925 90.230826) (width 0.125) (layer "In2.Cu") (net 25))
  (segment (start 104.510775 90.569633) (end 104.564224 90.569633) (width 0.125) (layer "In2.Cu") (net 25))
  (segment (start 104.118155 90.322933) (end 104.170072 90.405559) (width 0.125) (layer "In2.Cu") (net 25))
  (segment (start 101.304927 90.405559) (end 101.356844 90.322933) (width 0.125) (layer "In2.Cu") (net 25))
  (segment (start 102.504927 90.405559) (end 102.556844 90.322933) (width 0.125) (layer "In2.Cu") (net 25))
  (segment (start 101.429998 89.51427) (end 101.45177 89.492498) (width 0.125) (layer "In2.Cu") (net 25))
  (segment (start 103.704927 90.405559) (end 103.756844 90.322933) (width 0.125) (layer "In2.Cu") (net 25))
  (segment (start 104.045001 88.407138) (end 104.061383 88.433208) (width 0.125) (layer "In2.Cu") (net 25))
  (segment (start 102.6 88.492867) (end 102.603447 88.462271) (width 0.125) (layer "In2.Cu") (net 25))
  (segment (start 101.5375 89.4625) (end 101.568096 89.465947) (width 0.125) (layer "In2.Cu") (net 25))
  (segment (start 104.170072 90.405559) (end 104.239073 90.47456) (width 0.125) (layer "In2.Cu") (net 25))
  (segment (start 101.839073 90.47456) (end 101.921699 90.526477) (width 0.125) (layer "In2.Cu") (net 25))
  (segment (start 101.389074 90.230826) (end 101.4 90.133857) (width 0.125) (layer "In2.Cu") (net 25))
  (segment (start 102.797159 88.368984) (end 102.823229 88.385366) (width 0.125) (layer "In2.Cu") (net 25))
  (segment (start 101.403447 89.569403) (end 101.413616 89.54034) (width 0.125) (layer "In2.Cu") (net 25))
  (segment (start 97.7625 95.8) (end 97.7625 89.96731) (width 0.125) (layer "In2.Cu") (net 25))
  (segment (start 97.9625 96) (end 97.7625 95.8) (width 0.125) (layer "In2.Cu") (net 25))
  (segment (start 105.106903 89.465947) (end 105.1375 89.4625) (width 0.125) (layer "In2.Cu") (net 25))
  (segment (start 102.613616 88.433208) (end 102.629998 88.407138) (width 0.125) (layer "In2.Cu") (net 25))
  (segment (start 102.861383 88.433208) (end 102.871552 88.462271) (width 0.125) (layer "In2.Cu") (net 25))
  (segment (start 105.07784 89.476116) (end 105.106903 89.465947) (width 0.125) (layer "In2.Cu") (net 25))
  (segment (start 104.413806 90.558707) (end 104.510775 90.569633) (width 0.125) (layer "In2.Cu") (net 25))
  (segment (start 101.4 89.6) (end 101.403447 89.569403) (width 0.125) (layer "In2.Cu") (net 25))
  (segment (start 104.321699 90.526477) (end 104.413806 90.558707) (width 0.125) (layer "In2.Cu") (net 25))
  (segment (start 100.461383 89.54034) (end 100.471552 89.569403) (width 0.125) (layer "In2.Cu") (net 25))
  (segment (start 100.471552 89.569403) (end 100.475 89.6) (width 0.125) (layer "In2.Cu") (net 25))
  (segment (start 105.013616 89.54034) (end 105.029998 89.51427) (width 0.125) (layer "In2.Cu") (net 25))
  (segment (start 102.918155 90.322933) (end 102.970072 90.405559) (width 0.125) (layer "In2.Cu") (net 25))
  (segment (start 103.364224 90.569633) (end 103.461193 90.558707) (width 0.125) (layer "In2.Cu") (net 25))
  (segment (start 100.518155 90.322933) (end 100.570072 90.405559) (width 0.125) (layer "In2.Cu") (net 25))
  (segment (start 102.845001 88.407138) (end 102.861383 88.433208) (width 0.125) (layer "In2.Cu") (net 25))
  (segment (start 105 90.133857) (end 105 89.6) (width 0.125) (layer "In2.Cu") (net 25))
  (segment (start 101.921699 90.526477) (end 102.013806 90.558707) (width 0.125) (layer "In2.Cu") (net 25))
  (segment (start 102.970072 90.405559) (end 103.039073 90.47456) (width 0.125) (layer "In2.Cu") (net 25))
  (segment (start 105.1375 89.4625) (end 120.76731 89.4625) (width 0.125) (layer "In2.Cu") (net 25))
  (segment (start 102.6 90.133857) (end 102.6 88.492867) (width 0.125) (layer "In2.Cu") (net 25))
  (segment (start 103.9375 88.355367) (end 103.968096 88.358815) (width 0.125) (layer "In2.Cu") (net 25))
  (segment (start 104.989074 90.230826) (end 105 90.133857) (width 0.125) (layer "In2.Cu") (net 25))
  (segment (start 103.461193 90.558707) (end 103.5533 90.526477) (width 0.125) (layer "In2.Cu") (net 25))
  (segment (start 101.685925 90.230826) (end 101.718155 90.322933) (width 0.125) (layer "In2.Cu") (net 25))
  (segment (start 120.76731 89.4625) (end 122.322771 87.907039) (width 0.125) (layer "In2.Cu") (net 25))
  (segment (start 102.589074 90.230826) (end 102.6 90.133857) (width 0.125) (layer "In2.Cu") (net 25))
  (segment (start 104.061383 88.433208) (end 104.071552 88.462271) (width 0.125) (layer "In2.Cu") (net 25))
  (segment (start 100.813806 90.558707) (end 100.910775 90.569633) (width 0.125) (layer "In2.Cu") (net 25))
  (segment (start 102.435926 90.47456) (end 102.504927 90.405559) (width 0.125) (layer "In2.Cu") (net 25))
  (segment (start 101.4 90.133857) (end 101.4 89.6) (width 0.125) (layer "In2.Cu") (net 25))
  (segment (start 103.85177 88.385366) (end 103.87784 88.368984) (width 0.125) (layer "In2.Cu") (net 25))
  (segment (start 104.239073 90.47456) (end 104.321699 90.526477) (width 0.125) (layer "In2.Cu") (net 25))
  (segment (start 105 89.6) (end 105.003447 89.569403) (width 0.125) (layer "In2.Cu") (net 25))
  (segment (start 100.485925 90.230826) (end 100.518155 90.322933) (width 0.125) (layer "In2.Cu") (net 25))
  (segment (start 103.121699 90.526477) (end 103.213806 90.558707) (width 0.125) (layer "In2.Cu") (net 25))
  (segment (start 98.26731 89.4625) (end 100.3375 89.4625) (width 0.125) (layer "In2.Cu") (net 25))
  (segment (start 103.213806 90.558707) (end 103.310775 90.569633) (width 0.125) (layer "In2.Cu") (net 25))
  (segment (start 104.075 90.133857) (end 104.085925 90.230826) (width 0.125) (layer "In2.Cu") (net 25))
  (segment (start 101.645001 89.51427) (end 101.661383 89.54034) (width 0.125) (layer "In2.Cu") (net 25))
  (segment (start 102.823229 88.385366) (end 102.845001 88.407138) (width 0.125) (layer "In2.Cu") (net 25))
  (segment (start 100.397159 89.476116) (end 100.423229 89.492498) (width 0.125) (layer "In2.Cu") (net 25))
  (segment (start 101.413616 89.54034) (end 101.429998 89.51427) (width 0.125) (layer "In2.Cu") (net 25))
  (segment (start 102.603447 88.462271) (end 102.613616 88.433208) (width 0.125) (layer "In2.Cu") (net 25))
  (segment (start 103.906903 88.358815) (end 103.9375 88.355367) (width 0.125) (layer "In2.Cu") (net 25))
  (segment (start 122.444685 87.907039) (end 122.682185 88.144539) (width 0.125) (layer "In2.Cu") (net 25))
  (segment (start 103.039073 90.47456) (end 103.121699 90.526477) (width 0.125) (layer "In2.Cu") (net 25))
  (segment (start 101.45177 89.492498) (end 101.47784 89.476116) (width 0.125) (layer "In2.Cu") (net 25))
  (segment (start 100.475 90.133857) (end 100.485925 90.230826) (width 0.125) (layer "In2.Cu") (net 25))
  (segment (start 100.368096 89.465947) (end 100.397159 89.476116) (width 0.125) (layer "In2.Cu") (net 25))
  (segment (start 101.597159 89.476116) (end 101.623229 89.492498) (width 0.125) (layer "In2.Cu") (net 25))
  (segment (start 102.768096 88.358815) (end 102.797159 88.368984) (width 0.125) (layer "In2.Cu") (net 25))
  (segment (start 102.7375 88.355367) (end 102.768096 88.358815) (width 0.125) (layer "In2.Cu") (net 25))
  (segment (start 100.910775 90.569633) (end 100.964224 90.569633) (width 0.125) (layer "In2.Cu") (net 25))
  (segment (start 122.322771 87.907039) (end 122.444685 87.907039) (width 0.125) (layer "In2.Cu") (net 25))
  (segment (start 100.721699 90.526477) (end 100.813806 90.558707) (width 0.125) (layer "In2.Cu") (net 25))
  (segment (start 100.964224 90.569633) (end 101.061193 90.558707) (width 0.125) (layer "In2.Cu") (net 25))
  (segment (start 101.568096 89.465947) (end 101.597159 89.476116) (width 0.125) (layer "In2.Cu") (net 25))
  (segment (start 103.87784 88.368984) (end 103.906903 88.358815) (width 0.125) (layer "In2.Cu") (net 25))
  (segment (start 101.506903 89.465947) (end 101.5375 89.4625) (width 0.125) (layer "In2.Cu") (net 25))
  (segment (start 102.706903 88.358815) (end 102.7375 88.355367) (width 0.125) (layer "In2.Cu") (net 25))
  (segment (start 104.835926 90.47456) (end 104.904927 90.405559) (width 0.125) (layer "In2.Cu") (net 25))
  (segment (start 105.029998 89.51427) (end 105.05177 89.492498) (width 0.125) (layer "In2.Cu") (net 25))
  (segment (start 102.164224 90.569633) (end 102.261193 90.558707) (width 0.125) (layer "In2.Cu") (net 25))
  (segment (start 100.639073 90.47456) (end 100.721699 90.526477) (width 0.125) (layer "In2.Cu") (net 25))
  (segment (start 101.671552 89.569403) (end 101.675 89.6) (width 0.125) (layer "In2.Cu") (net 25))
  (segment (start 102.871552 88.462271) (end 102.875 88.492867) (width 0.125) (layer "In2.Cu") (net 25))
  (segment (start 103.997159 88.368984) (end 104.023229 88.385366) (width 0.125) (layer "In2.Cu") (net 25))
  (segment (start 100.570072 90.405559) (end 100.639073 90.47456) (width 0.125) (layer "In2.Cu") (net 25))
  (segment (start 101.770072 90.405559) (end 101.839073 90.47456) (width 0.125) (layer "In2.Cu") (net 25))
  (segment (start 103.813616 88.433208) (end 103.829998 88.407138) (width 0.125) (layer "In2.Cu") (net 25))
  (segment (start 101.718155 90.322933) (end 101.770072 90.405559) (width 0.125) (layer "In2.Cu") (net 25))
  (segment (start 102.67784 88.368984) (end 102.706903 88.358815) (width 0.125) (layer "In2.Cu") (net 25))
  (segment (start 103.5533 90.526477) (end 103.635926 90.47456) (width 0.125) (layer "In2.Cu") (net 25))
  (segment (start 104.564224 90.569633) (end 104.661193 90.558707) (width 0.125) (layer "In2.Cu") (net 25))
  (segment (start 102.875 88.492867) (end 102.875 90.133857) (width 0.125) (layer "In2.Cu") (net 25))
  (segment (start 103.756844 90.322933) (end 103.789074 90.230826) (width 0.125) (layer "In2.Cu") (net 25))
  (segment (start 104.7533 90.526477) (end 104.835926 90.47456) (width 0.125) (layer "In2.Cu") (net 25))
  (segment (start 104.085925 90.230826) (end 104.118155 90.322933) (width 0.125) (layer "In2.Cu") (net 25))
  (segment (start 102.110775 90.569633) (end 102.164224 90.569633) (width 0.125) (layer "In2.Cu") (net 25))
  (segment (start 103.8 90.133857) (end 103.8 88.492867) (width 0.125) (layer "In2.Cu") (net 25))
  (segment (start 101.675 89.6) (end 101.675 90.133857) (width 0.125) (layer "In2.Cu") (net 25))
  (segment (start 103.635926 90.47456) (end 103.704927 90.405559) (width 0.125) (layer "In2.Cu") (net 25))
  (segment (start 102.261193 90.558707) (end 102.3533 90.526477) (width 0.125) (layer "In2.Cu") (net 25))
  (segment (start 97.7625 89.96731) (end 98.26731 89.4625) (width 0.125) (layer "In2.Cu") (net 25))
  (segment (start 102.629998 88.407138) (end 102.65177 88.385366) (width 0.125) (layer "In2.Cu") (net 25))
  (segment (start 101.623229 89.492498) (end 101.645001 89.51427) (width 0.125) (layer "In2.Cu") (net 25))
  (segment (start 104.075 88.492867) (end 104.075 90.133857) (width 0.125) (layer "In2.Cu") (net 25))
  (segment (start 102.885925 90.230826) (end 102.918155 90.322933) (width 0.125) (layer "In2.Cu") (net 25))
  (segment (start 101.675 90.133857) (end 101.685925 90.230826) (width 0.125) (layer "In2.Cu") (net 25))
  (segment (start 104.904927 90.405559) (end 104.956844 90.322933) (width 0.125) (layer "In2.Cu") (net 25))
  (segment (start 101.061193 90.558707) (end 101.1533 90.526477) (width 0.125) (layer "In2.Cu") (net 25))
  (segment (start 104.956844 90.322933) (end 104.989074 90.230826) (width 0.125) (layer "In2.Cu") (net 25))
  (segment (start 100.423229 89.492498) (end 100.445001 89.51427) (width 0.125) (layer "In2.Cu") (net 25))
  (segment (start 100.475 89.6) (end 100.475 90.133857) (width 0.125) (layer "In2.Cu") (net 25))
  (segment (start 101.661383 89.54034) (end 101.671552 89.569403) (width 0.125) (layer "In2.Cu") (net 25))
  (segment (start 102.556844 90.322933) (end 102.589074 90.230826) (width 0.125) (layer "In2.Cu") (net 25))
  (segment (start 101.1533 90.526477) (end 101.235926 90.47456) (width 0.125) (layer "In2.Cu") (net 25))
  (segment (start 102.65177 88.385366) (end 102.67784 88.368984) (width 0.125) (layer "In2.Cu") (net 25))
  (segment (start 103.803447 88.462271) (end 103.813616 88.433208) (width 0.125) (layer "In2.Cu") (net 25))
  (segment (start 101.356844 90.322933) (end 101.389074 90.230826) (width 0.125) (layer "In2.Cu") (net 25))
  (segment (start 101.235926 90.47456) (end 101.304927 90.405559) (width 0.125) (layer "In2.Cu") (net 25))
  (segment (start 103.829998 88.407138) (end 103.85177 88.385366) (width 0.125) (layer "In2.Cu") (net 25))
  (segment (start 102.3533 90.526477) (end 102.435926 90.47456) (width 0.125) (layer "In2.Cu") (net 25))
  (segment (start 103.789074 90.230826) (end 103.8 90.133857) (width 0.125) (layer "In2.Cu") (net 25))
  (segment (start 100.445001 89.51427) (end 100.461383 89.54034) (width 0.125) (layer "In2.Cu") (net 25))
  (segment (start 97.725 95.7625) (end 97.9625 96) (width 0.125) (layer "B.Cu") (net 25))
  (segment (start 97.725 94.290001) (end 97.725 95.7625) (width 0.125) (layer "B.Cu") (net 25))
  (segment (start 97.84 94.175001) (end 97.725 94.290001) (width 0.125) (layer "B.Cu") (net 25))
  (segment (start 97.84 93.95) (end 97.84 94.175001) (width 0.125) (layer "B.Cu") (net 25))
  (segment (start 120.125 84.775001) (end 120.125 87.648222) (width 0.125) (layer "F.Cu") (net 26))
  (segment (start 122.203683 87.619539) (end 122.407185 87.619539) (width 0.125) (layer "F.Cu") (net 26))
  (segment (start 121.748222 88.075) (end 122.203683 87.619539) (width 0.125) (layer "F.Cu") (net 26))
  (segment (start 120.551778 88.075) (end 121.748222 88.075) (width 0.125) (layer "F.Cu") (net 26))
  (segment (start 120.25 83.45) (end 120.25 84.650001) (width 0.125) (layer "F.Cu") (net 26))
  (segment (start 122.407185 87.619539) (end 122.682185 87.344539) (width 0.125) (layer "F.Cu") (net 26))
  (segment (start 120.25 84.650001) (end 120.125 84.775001) (width 0.125) (layer "F.Cu") (net 26))
  (segment (start 120.125 87.648222) (end 120.551778 88.075) (width 0.125) (layer "F.Cu") (net 26))
  (via (at 97.2375 96) (size 0.6) (drill 0.25) (layers "F.Cu" "B.Cu") (net 26))
  (via (at 122.682185 87.344539) (size 0.6) (drill 0.25) (layers "F.Cu" "B.Cu") (net 26))
  (segment (start 102.9533 88.073523) (end 103.035926 88.12544) (width 0.125) (layer "In2.Cu") (net 26))
  (segment (start 104.506903 90.241185) (end 104.5375 90.244633) (width 0.125) (layer "In2.Cu") (net 26))
  (segment (start 100.5533 89.180655) (end 100.635926 89.232572) (width 0.125) (layer "In2.Cu") (net 26))
  (segment (start 101.956844 89.384199) (end 101.989074 89.476306) (width 0.125) (layer "In2.Cu") (net 26))
  (segment (start 100.461193 89.148425) (end 100.5533 89.180655) (width 0.125) (layer "In2.Cu") (net 26))
  (segment (start 104.389074 88.369174) (end 104.4 88.466143) (width 0.125) (layer "In2.Cu") (net 26))
  (segment (start 102.029998 90.192862) (end 102.05177 90.214634) (width 0.125) (layer "In2.Cu") (net 26))
  (segment (start 102 90.107133) (end 102.003447 90.137729) (width 0.125) (layer "In2.Cu") (net 26))
  (segment (start 104.403447 90.137729) (end 104.413616 90.166792) (width 0.125) (layer "In2.Cu") (net 26))
  (segment (start 104.5375 90.244633) (end 104.568096 90.241185) (width 0.125) (layer "In2.Cu") (net 26))
  (segment (start 100.9375 90.244633) (end 100.968096 90.241185) (width 0.125) (layer "In2.Cu") (net 26))
  (segment (start 101.661193 89.148425) (end 101.7533 89.180655) (width 0.125) (layer "In2.Cu") (net 26))
  (segment (start 102.861193 88.041293) (end 102.9533 88.073523) (width 0.125) (layer "In2.Cu") (net 26))
  (segment (start 102.106903 90.241185) (end 102.1375 90.244633) (width 0.125) (layer "In2.Cu") (net 26))
  (segment (start 103.475 90.107133) (end 103.475 88.466143) (width 0.125) (layer "In2.Cu") (net 26))
  (segment (start 101.118155 89.384199) (end 101.170072 89.301573) (width 0.125) (layer "In2.Cu") (net 26))
  (segment (start 102.168096 90.241185) (end 102.197159 90.231016) (width 0.125) (layer "In2.Cu") (net 26))
  (segment (start 102.285925 88.369174) (end 102.318155 88.277067) (width 0.125) (layer "In2.Cu") (net 26))
  (segment (start 100.997159 90.231016) (end 101.023229 90.214634) (width 0.125) (layer "In2.Cu") (net 26))
  (segment (start 102.261383 90.166792) (end 102.271552 90.137729) (width 0.125) (layer "In2.Cu") (net 26))
  (segment (start 104.4 88.466143) (end 104.4 90.107133) (width 0.125) (layer "In2.Cu") (net 26))
  (segment (start 105.110775 89.1375) (end 120.63269 89.1375) (width 0.125) (layer "In2.Cu") (net 26))
  (segment (start 100.87784 90.231016) (end 100.906903 90.241185) (width 0.125) (layer "In2.Cu") (net 26))
  (segment (start 97.4375 89.83269) (end 98.13269 89.1375) (width 0.125) (layer "In2.Cu") (net 26))
  (segment (start 103.570072 88.194441) (end 103.639073 88.12544) (width 0.125) (layer "In2.Cu") (net 26))
  (segment (start 102.318155 88.277067) (end 102.370072 88.194441) (width 0.125) (layer "In2.Cu") (net 26))
  (segment (start 101.071552 90.137729) (end 101.075 90.107133) (width 0.125) (layer "In2.Cu") (net 26))
  (segment (start 103.2 90.107133) (end 103.203447 90.137729) (width 0.125) (layer "In2.Cu") (net 26))
  (segment (start 103.035926 88.12544) (end 103.104927 88.194441) (width 0.125) (layer "In2.Cu") (net 26))
  (segment (start 103.813806 88.041293) (end 103.910775 88.030367) (width 0.125) (layer "In2.Cu") (net 26))
  (segment (start 101.023229 90.214634) (end 101.045001 90.192862) (width 0.125) (layer "In2.Cu") (net 26))
  (segment (start 103.203447 90.137729) (end 103.213616 90.166792) (width 0.125) (layer "In2.Cu") (net 26))
  (segment (start 102.1375 90.244633) (end 102.168096 90.241185) (width 0.125) (layer "In2.Cu") (net 26))
  (segment (start 104.413616 90.166792) (end 104.429998 90.192862) (width 0.125) (layer "In2.Cu") (net 26))
  (segment (start 102.710775 88.030367) (end 102.764224 88.030367) (width 0.125) (layer "In2.Cu") (net 26))
  (segment (start 101.835926 89.232572) (end 101.904927 89.301573) (width 0.125) (layer "In2.Cu") (net 26))
  (segment (start 104.061193 88.041293) (end 104.1533 88.073523) (width 0.125) (layer "In2.Cu") (net 26))
  (segment (start 103.639073 88.12544) (end 103.721699 88.073523) (width 0.125) (layer "In2.Cu") (net 26))
  (segment (start 104.661383 90.166792) (end 104.671552 90.137729) (width 0.125) (layer "In2.Cu") (net 26))
  (segment (start 104.235926 88.12544) (end 104.304927 88.194441) (width 0.125) (layer "In2.Cu") (net 26))
  (segment (start 103.721699 88.073523) (end 103.813806 88.041293) (width 0.125) (layer "In2.Cu") (net 26))
  (segment (start 100.8 89.573275) (end 100.8 90.107133) (width 0.125) (layer "In2.Cu") (net 26))
  (segment (start 102 89.573275) (end 102 90.107133) (width 0.125) (layer "In2.Cu") (net 26))
  (segment (start 104.770072 89.301573) (end 104.839073 89.232572) (width 0.125) (layer "In2.Cu") (net 26))
  (segment (start 104.675 89.573275) (end 104.685925 89.476306) (width 0.125) (layer "In2.Cu") (net 26))
  (segment (start 100.756844 89.384199) (end 100.789074 89.476306) (width 0.125) (layer "In2.Cu") (net 26))
  (segment (start 103.910775 88.030367) (end 103.964224 88.030367) (width 0.125) (layer "In2.Cu") (net 26))
  (segment (start 104.718155 89.384199) (end 104.770072 89.301573) (width 0.125) (layer "In2.Cu") (net 26))
  (segment (start 104.356844 88.277067) (end 104.389074 88.369174) (width 0.125) (layer "In2.Cu") (net 26))
  (segment (start 102.013616 90.166792) (end 102.029998 90.192862) (width 0.125) (layer "In2.Cu") (net 26))
  (segment (start 101.564224 89.1375) (end 101.661193 89.148425) (width 0.125) (layer "In2.Cu") (net 26))
  (segment (start 102.223229 90.214634) (end 102.245001 90.192862) (width 0.125) (layer "In2.Cu") (net 26))
  (segment (start 103.485925 88.369174) (end 103.518155 88.277067) (width 0.125) (layer "In2.Cu") (net 26))
  (segment (start 104.45177 90.214634) (end 104.47784 90.231016) (width 0.125) (layer "In2.Cu") (net 26))
  (segment (start 103.518155 88.277067) (end 103.570072 88.194441) (width 0.125) (layer "In2.Cu") (net 26))
  (segment (start 102.271552 90.137729) (end 102.275 90.107133) (width 0.125) (layer "In2.Cu") (net 26))
  (segment (start 101.989074 89.476306) (end 102 89.573275) (width 0.125) (layer "In2.Cu") (net 26))
  (segment (start 103.25177 90.214634) (end 103.27784 90.231016) (width 0.125) (layer "In2.Cu") (net 26))
  (segment (start 104.47784 90.231016) (end 104.506903 90.241185) (width 0.125) (layer "In2.Cu") (net 26))
  (segment (start 103.3375 90.244633) (end 103.368096 90.241185) (width 0.125) (layer "In2.Cu") (net 26))
  (segment (start 102.439073 88.12544) (end 102.521699 88.073523) (width 0.125) (layer "In2.Cu") (net 26))
  (segment (start 100.803447 90.137729) (end 100.813616 90.166792) (width 0.125) (layer "In2.Cu") (net 26))
  (segment (start 102.05177 90.214634) (end 102.07784 90.231016) (width 0.125) (layer "In2.Cu") (net 26))
  (segment (start 101.085925 89.476306) (end 101.118155 89.384199) (width 0.125) (layer "In2.Cu") (net 26))
  (segment (start 103.27784 90.231016) (end 103.306903 90.241185) (width 0.125) (layer "In2.Cu") (net 26))
  (segment (start 101.510775 89.1375) (end 101.564224 89.1375) (width 0.125) (layer "In2.Cu") (net 26))
  (segment (start 100.968096 90.241185) (end 100.997159 90.231016) (width 0.125) (layer "In2.Cu") (net 26))
  (segment (start 100.85177 90.214634) (end 100.87784 90.231016) (width 0.125) (layer "In2.Cu") (net 26))
  (segment (start 103.461383 90.166792) (end 103.471552 90.137729) (width 0.125) (layer "In2.Cu") (net 26))
  (segment (start 103.397159 90.231016) (end 103.423229 90.214634) (width 0.125) (layer "In2.Cu") (net 26))
  (segment (start 103.189074 88.369174) (end 103.2 88.466143) (width 0.125) (layer "In2.Cu") (net 26))
  (segment (start 104.568096 90.241185) (end 104.597159 90.231016) (width 0.125) (layer "In2.Cu") (net 26))
  (segment (start 100.813616 90.166792) (end 100.829998 90.192862) (width 0.125) (layer "In2.Cu") (net 26))
  (segment (start 100.906903 90.241185) (end 100.9375 90.244633) (width 0.125) (layer "In2.Cu") (net 26))
  (segment (start 100.829998 90.192862) (end 100.85177 90.214634) (width 0.125) (layer "In2.Cu") (net 26))
  (segment (start 97.4375 95.8) (end 97.4375 89.83269) (width 0.125) (layer "In2.Cu") (net 26))
  (segment (start 102.003447 90.137729) (end 102.013616 90.166792) (width 0.125) (layer "In2.Cu") (net 26))
  (segment (start 103.306903 90.241185) (end 103.3375 90.244633) (width 0.125) (layer "In2.Cu") (net 26))
  (segment (start 102.275 88.466143) (end 102.285925 88.369174) (width 0.125) (layer "In2.Cu") (net 26))
  (segment (start 103.445001 90.192862) (end 103.461383 90.166792) (width 0.125) (layer "In2.Cu") (net 26))
  (segment (start 102.370072 88.194441) (end 102.439073 88.12544) (width 0.125) (layer "In2.Cu") (net 26))
  (segment (start 98.13269 89.1375) (end 100.364224 89.1375) (width 0.125) (layer "In2.Cu") (net 26))
  (segment (start 102.613806 88.041293) (end 102.710775 88.030367) (width 0.125) (layer "In2.Cu") (net 26))
  (segment (start 103.213616 90.166792) (end 103.229998 90.192862) (width 0.125) (layer "In2.Cu") (net 26))
  (segment (start 102.245001 90.192862) (end 102.261383 90.166792) (width 0.125) (layer "In2.Cu") (net 26))
  (segment (start 103.964224 88.030367) (end 104.061193 88.041293) (width 0.125) (layer "In2.Cu") (net 26))
  (segment (start 101.075 90.107133) (end 101.075 89.573275) (width 0.125) (layer "In2.Cu") (net 26))
  (segment (start 101.170072 89.301573) (end 101.239073 89.232572) (width 0.125) (layer "In2.Cu") (net 26))
  (segment (start 102.197159 90.231016) (end 102.223229 90.214634) (width 0.125) (layer "In2.Cu") (net 26))
  (segment (start 103.229998 90.192862) (end 103.25177 90.214634) (width 0.125) (layer "In2.Cu") (net 26))
  (segment (start 103.368096 90.241185) (end 103.397159 90.231016) (width 0.125) (layer "In2.Cu") (net 26))
  (segment (start 104.675 90.107133) (end 104.675 89.573275) (width 0.125) (layer "In2.Cu") (net 26))
  (segment (start 100.789074 89.476306) (end 100.8 89.573275) (width 0.125) (layer "In2.Cu") (net 26))
  (segment (start 101.904927 89.301573) (end 101.956844 89.384199) (width 0.125) (layer "In2.Cu") (net 26))
  (segment (start 104.304927 88.194441) (end 104.356844 88.277067) (width 0.125) (layer "In2.Cu") (net 26))
  (segment (start 104.4 90.107133) (end 104.403447 90.137729) (width 0.125) (layer "In2.Cu") (net 26))
  (segment (start 100.704927 89.301573) (end 100.756844 89.384199) (width 0.125) (layer "In2.Cu") (net 26))
  (segment (start 97.2375 96) (end 97.4375 95.8) (width 0.125) (layer "In2.Cu") (net 26))
  (segment (start 101.075 89.573275) (end 101.085925 89.476306) (width 0.125) (layer "In2.Cu") (net 26))
  (segment (start 104.429998 90.192862) (end 104.45177 90.214634) (width 0.125) (layer "In2.Cu") (net 26))
  (segment (start 104.921699 89.180655) (end 105.013806 89.148425) (width 0.125) (layer "In2.Cu") (net 26))
  (segment (start 103.423229 90.214634) (end 103.445001 90.192862) (width 0.125) (layer "In2.Cu") (net 26))
  (segment (start 105.013806 89.148425) (end 105.110775 89.1375) (width 0.125) (layer "In2.Cu") (net 26))
  (segment (start 104.1533 88.073523) (end 104.235926 88.12544) (width 0.125) (layer "In2.Cu") (net 26))
  (segment (start 104.645001 90.192862) (end 104.661383 90.166792) (width 0.125) (layer "In2.Cu") (net 26))
  (segment (start 104.597159 90.231016) (end 104.623229 90.214634) (width 0.125) (layer "In2.Cu") (net 26))
  (segment (start 122.188151 87.582039) (end 122.444685 87.582039) (width 0.125) (layer "In2.Cu") (net 26))
  (segment (start 104.671552 90.137729) (end 104.675 90.107133) (width 0.125) (layer "In2.Cu") (net 26))
  (segment (start 101.239073 89.232572) (end 101.321699 89.180655) (width 0.125) (layer "In2.Cu") (net 26))
  (segment (start 101.045001 90.192862) (end 101.061383 90.166792) (width 0.125) (layer "In2.Cu") (net 26))
  (segment (start 100.8 90.107133) (end 100.803447 90.137729) (width 0.125) (layer "In2.Cu") (net 26))
  (segment (start 100.364224 89.1375) (end 100.461193 89.148425) (width 0.125) (layer "In2.Cu") (net 26))
  (segment (start 103.471552 90.137729) (end 103.475 90.107133) (width 0.125) (layer "In2.Cu") (net 26))
  (segment (start 100.635926 89.232572) (end 100.704927 89.301573) (width 0.125) (layer "In2.Cu") (net 26))
  (segment (start 120.63269 89.1375) (end 122.188151 87.582039) (width 0.125) (layer "In2.Cu") (net 26))
  (segment (start 104.839073 89.232572) (end 104.921699 89.180655) (width 0.125) (layer "In2.Cu") (net 26))
  (segment (start 102.764224 88.030367) (end 102.861193 88.041293) (width 0.125) (layer "In2.Cu") (net 26))
  (segment (start 103.475 88.466143) (end 103.485925 88.369174) (width 0.125) (layer "In2.Cu") (net 26))
  (segment (start 103.104927 88.194441) (end 103.156844 88.277067) (width 0.125) (layer "In2.Cu") (net 26))
  (segment (start 101.413806 89.148425) (end 101.510775 89.1375) (width 0.125) (layer "In2.Cu") (net 26))
  (segment (start 102.521699 88.073523) (end 102.613806 88.041293) (width 0.125) (layer "In2.Cu") (net 26))
  (segment (start 103.2 88.466143) (end 103.2 90.107133) (width 0.125) (layer "In2.Cu") (net 26))
  (segment (start 101.321699 89.180655) (end 101.413806 89.148425) (width 0.125) (layer "In2.Cu") (net 26))
  (segment (start 104.623229 90.214634) (end 104.645001 90.192862) (width 0.125) (layer "In2.Cu") (net 26))
  (segment (start 101.7533 89.180655) (end 101.835926 89.232572) (width 0.125) (layer "In2.Cu") (net 26))
  (segment (start 103.156844 88.277067) (end 103.189074 88.369174) (width 0.125) (layer "In2.Cu") (net 26))
  (segment (start 104.685925 89.476306) (end 104.718155 89.384199) (width 0.125) (layer "In2.Cu") (net 26))
  (segment (start 102.275 90.107133) (end 102.275 88.466143) (width 0.125) (layer "In2.Cu") (net 26))
  (segment (start 101.061383 90.166792) (end 101.071552 90.137729) (width 0.125) (layer "In2.Cu") (net 26))
  (segment (start 102.07784 90.231016) (end 102.106903 90.241185) (width 0.125) (layer "In2.Cu") (net 26))
  (segment (start 122.444685 87.582039) (end 122.682185 87.344539) (width 0.125) (layer "In2.Cu") (net 26))
  (segment (start 97.475 94.290001) (end 97.475 95.7625) (width 0.125) (layer "B.Cu") (net 26))
  (segment (start 97.475 95.7625) (end 97.2375 96) (width 0.125) (layer "B.Cu") (net 26))
  (segment (start 97.36 93.95) (end 97.36 94.175001) (width 0.125) (layer "B.Cu") (net 26))
  (segment (start 97.36 94.175001) (end 97.475 94.290001) (width 0.125) (layer "B.Cu") (net 26))
  (segment (start 133.250001 84.650151) (end 133.250001 83.45) (width 0.125) (layer "F.Cu") (net 27))
  (segment (start 133.698222 85.375) (end 133.375001 85.051779) (width 0.125) (layer "F.Cu") (net 27))
  (segment (start 134.5 85.6125) (end 134.2625 85.375) (width 0.125) (layer "F.Cu") (net 27))
  (segment (start 133.375001 84.775151) (end 133.250001 84.650151) (width 0.125) (layer "F.Cu") (net 27))
  (segment (start 133.375001 85.051779) (end 133.375001 84.775151) (width 0.125) (layer "F.Cu") (net 27))
  (segment (start 134.2625 85.375) (end 133.698222 85.375) (width 0.125) (layer "F.Cu") (net 27))
  (via (at 101.4375 94.889793) (size 0.6) (drill 0.25) (layers "F.Cu" "B.Cu") (net 27))
  (via (at 134.5 85.6125) (size 0.6) (drill 0.25) (layers "F.Cu" "B.Cu") (net 27))
  (segment (start 133.6625 85.56731) (end 133.81731 85.4125) (width 0.125) (layer "In2.Cu") (net 27))
  (segment (start 134.3 85.4125) (end 134.5 85.6125) (width 0.125) (layer "In2.Cu") (net 27))
  (segment (start 133.6625 94.31731) (end 133.6625 85.56731) (width 0.125) (layer "In2.Cu") (net 27))
  (segment (start 101.6375 96.36731) (end 106.93269 101.6625) (width 0.125) (layer "In2.Cu") (net 27))
  (segment (start 133.81731 85.4125) (end 134.3 85.4125) (width 0.125) (layer "In2.Cu") (net 27))
  (segment (start 126.31731 101.6625) (end 133.6625 94.31731) (width 0.125) (layer "In2.Cu") (net 27))
  (segment (start 106.93269 101.6625) (end 126.31731 101.6625) (width 0.125) (layer "In2.Cu") (net 27))
  (segment (start 101.6375 95.089793) (end 101.6375 96.36731) (width 0.125) (layer "In2.Cu") (net 27))
  (segment (start 101.4375 94.889793) (end 101.6375 95.089793) (width 0.125) (layer "In2.Cu") (net 27))
  (segment (start 101.675 94.290001) (end 101.675 94.652293) (width 0.125) (layer "B.Cu") (net 27))
  (segment (start 101.56 93.95) (end 101.56 94.175001) (width 0.125) (layer "B.Cu") (net 27))
  (segment (start 101.675 94.652293) (end 101.4375 94.889793) (width 0.125) (layer "B.Cu") (net 27))
  (segment (start 101.56 94.175001) (end 101.675 94.290001) (width 0.125) (layer "B.Cu") (net 27))
  (segment (start 133.75 84.650151) (end 133.75 83.45) (width 0.125) (layer "F.Cu") (net 28))
  (segment (start 134.2625 85.125) (end 133.801778 85.125) (width 0.125) (layer "F.Cu") (net 28))
  (segment (start 133.625 84.775151) (end 133.75 84.650151) (width 0.125) (layer "F.Cu") (net 28))
  (segment (start 133.801778 85.125) (end 133.625 84.948222) (width 0.125) (layer "F.Cu") (net 28))
  (segment (start 133.625 84.948222) (end 133.625 84.775151) (width 0.125) (layer "F.Cu") (net 28))
  (segment (start 134.5 84.8875) (end 134.2625 85.125) (width 0.125) (layer "F.Cu") (net 28))
  (via (at 134.5 84.8875) (size 0.6) (drill 0.25) (layers "F.Cu" "B.Cu") (net 28))
  (via (at 102.1625 94.889793) (size 0.6) (drill 0.25) (layers "F.Cu" "B.Cu") (net 28))
  (segment (start 102.1625 94.889793) (end 101.9625 95.089793) (width 0.125) (layer "In2.Cu") (net 28))
  (segment (start 133.3375 94.18269) (end 133.3375 85.43269) (width 0.125) (layer "In2.Cu") (net 28))
  (segment (start 126.18269 101.3375) (end 133.3375 94.18269) (width 0.125) (layer "In2.Cu") (net 28))
  (segment (start 101.9625 96.23269) (end 107.06731 101.3375) (width 0.125) (layer "In2.Cu") (net 28))
  (segment (start 134.3 85.0875) (end 134.5 84.8875) (width 0.125) (layer "In2.Cu") (net 28))
  (segment (start 101.9625 95.089793) (end 101.9625 96.23269) (width 0.125) (layer "In2.Cu") (net 28))
  (segment (start 107.06731 101.3375) (end 126.18269 101.3375) (width 0.125) (layer "In2.Cu") (net 28))
  (segment (start 133.68269 85.0875) (end 134.3 85.0875) (width 0.125) (layer "In2.Cu") (net 28))
  (segment (start 133.3375 85.43269) (end 133.68269 85.0875) (width 0.125) (layer "In2.Cu") (net 28))
  (segment (start 101.925 94.652293) (end 102.1625 94.889793) (width 0.125) (layer "B.Cu") (net 28))
  (segment (start 102.04 94.175001) (end 101.925 94.290001) (width 0.125) (layer "B.Cu") (net 28))
  (segment (start 102.04 93.95) (end 102.04 94.175001) (width 0.125) (layer "B.Cu") (net 28))
  (segment (start 101.925 94.290001) (end 101.925 94.652293) (width 0.125) (layer "B.Cu") (net 28))
  (segment (start 131.749999 84.650151) (end 131.875 84.775152) (width 0.125) (layer "F.Cu") (net 29))
  (segment (start 131.875 85.014306) (end 131.6375 85.251806) (width 0.125) (layer "F.Cu") (net 29))
  (segment (start 131.875 84.775152) (end 131.875 85.014306) (width 0.125) (layer "F.Cu") (net 29))
  (segment (start 131.749999 83.45) (end 131.749999 84.650151) (width 0.125) (layer "F.Cu") (net 29))
  (via (at 131.6375 85.251806) (size 0.6) (drill 0.25) (layers "F.Cu" "B.Cu") (net 29))
  (via (at 103.4625 95.407527) (size 0.6) (drill 0.25) (layers "F.Cu" "B.Cu") (net 29))
  (segment (start 132.635625 87.571552) (end 132.605028 87.575) (width 0.125) (layer "In2.Cu") (net 29))
  (segment (start 131.368247 87.3) (end 132.605028 87.3) (width 0.125) (layer "In2.Cu") (net 29))
  (segment (start 132.739081 87.468096) (end 132.728912 87.497159) (width 0.125) (layer "In2.Cu") (net 29))
  (segment (start 131.8375 85.451806) (end 131.8375 86.2375) (width 0.125) (layer "In2.Cu") (net 29))
  (segment (start 131.7 86.375) (end 131.368247 86.375) (width 0.125) (layer "In2.Cu") (net 29))
  (segment (start 131.179171 87.618155) (end 131.096545 87.670072) (width 0.125) (layer "In2.Cu") (net 29))
  (segment (start 132.001574 88.870072) (end 131.932573 88.939073) (width 0.125) (layer "In2.Cu") (net 29))
  (segment (start 132.739081 87.406903) (end 132.742528 87.4375) (width 0.125) (layer "In2.Cu") (net 29))
  (segment (start 131.271278 88.489074) (end 131.368247 88.5) (width 0.125) (layer "In2.Cu") (net 29))
  (segment (start 131.8375 86.2375) (end 131.834052 86.268096) (width 0.125) (layer "In2.Cu") (net 29))
  (segment (start 132.176307 88.785925) (end 132.0842 88.818155) (width 0.125) (layer "In2.Cu") (net 29))
  (segment (start 131.271278 87.585925) (end 131.179171 87.618155) (width 0.125) (layer "In2.Cu") (net 29))
  (segment (start 131.834052 86.268096) (end 131.823883 86.297159) (width 0.125) (layer "In2.Cu") (net 29))
  (segment (start 132.690758 87.545001) (end 132.664688 87.561383) (width 0.125) (layer "In2.Cu") (net 29))
  (segment (start 130.975627 86.621699) (end 130.943397 86.713806) (width 0.125) (layer "In2.Cu") (net 29))
  (segment (start 132.728912 87.497159) (end 132.71253 87.523229) (width 0.125) (layer "In2.Cu") (net 29))
  (segment (start 125.03269 100.2375) (end 107.46731 100.2375) (width 0.125) (layer "In2.Cu") (net 29))
  (segment (start 107.46731 100.2375) (end 103.2625 96.03269) (width 0.125) (layer "In2.Cu") (net 29))
  (segment (start 132.273276 88.775) (end 132.176307 88.785925) (width 0.125) (layer "In2.Cu") (net 29))
  (segment (start 132.635625 87.303447) (end 132.664688 87.313616) (width 0.125) (layer "In2.Cu") (net 29))
  (segment (start 130.943397 88.161193) (end 130.975627 88.2533) (width 0.125) (layer "In2.Cu") (net 29))
  (segment (start 132.690758 88.529998) (end 132.71253 88.55177) (width 0.125) (layer "In2.Cu") (net 29))
  (segment (start 131.096545 87.204927) (end 131.179171 87.256844) (width 0.125) (layer "In2.Cu") (net 29))
  (segment (start 132.664688 88.513616) (end 132.690758 88.529998) (width 0.125) (layer "In2.Cu") (net 29))
  (segment (start 132.739081 88.668096) (end 132.728912 88.697159) (width 0.125) (layer "In2.Cu") (net 29))
  (segment (start 131.8375 93.43269) (end 125.03269 100.2375) (width 0.125) (layer "In2.Cu") (net 29))
  (segment (start 131.807501 86.323229) (end 131.785729 86.345001) (width 0.125) (layer "In2.Cu") (net 29))
  (segment (start 131.880656 89.021699) (end 131.848426 89.113806) (width 0.125) (layer "In2.Cu") (net 29))
  (segment (start 132.664688 88.761383) (end 132.635625 88.771552) (width 0.125) (layer "In2.Cu") (net 29))
  (segment (start 132.664688 87.313616) (end 132.690758 87.329998) (width 0.125) (layer "In2.Cu") (net 29))
  (segment (start 131.368247 88.5) (end 132.605028 88.5) (width 0.125) (layer "In2.Cu") (net 29))
  (segment (start 132.739081 88.606903) (end 132.742528 88.6375) (width 0.125) (layer "In2.Cu") (net 29))
  (segment (start 130.943397 86.713806) (end 130.932472 86.810775) (width 0.125) (layer "In2.Cu") (net 29))
  (segment (start 130.932472 86.864224) (end 130.943397 86.961193) (width 0.125) (layer "In2.Cu") (net 29))
  (segment (start 131.271278 87.289074) (end 131.368247 87.3) (width 0.125) (layer "In2.Cu") (net 29))
  (segment (start 130.975627 88.2533) (end 131.027544 88.335926) (width 0.125) (layer "In2.Cu") (net 29))
  (segment (start 131.6375 85.251806) (end 131.8375 85.451806) (width 0.125) (layer "In2.Cu") (net 29))
  (segment (start 131.823883 86.297159) (end 131.807501 86.323229) (width 0.125) (layer "In2.Cu") (net 29))
  (segment (start 131.730596 86.371552) (end 131.7 86.375) (width 0.125) (layer "In2.Cu") (net 29))
  (segment (start 132.690758 87.329998) (end 132.71253 87.35177) (width 0.125) (layer "In2.Cu") (net 29))
  (segment (start 132.71253 88.55177) (end 132.728912 88.57784) (width 0.125) (layer "In2.Cu") (net 29))
  (segment (start 130.932472 88.064224) (end 130.943397 88.161193) (width 0.125) (layer "In2.Cu") (net 29))
  (segment (start 131.027544 87.135926) (end 131.096545 87.204927) (width 0.125) (layer "In2.Cu") (net 29))
  (segment (start 130.975627 87.0533) (end 131.027544 87.135926) (width 0.125) (layer "In2.Cu") (net 29))
  (segment (start 132.664688 87.561383) (end 132.635625 87.571552) (width 0.125) (layer "In2.Cu") (net 29))
  (segment (start 132.728912 88.697159) (end 132.71253 88.723229) (width 0.125) (layer "In2.Cu") (net 29))
  (segment (start 130.943397 86.961193) (end 130.975627 87.0533) (width 0.125) (layer "In2.Cu") (net 29))
  (segment (start 103.2625 96.03269) (end 103.2625 95.607527) (width 0.125) (layer "In2.Cu") (net 29))
  (segment (start 131.368247 86.375) (end 131.271278 86.385925) (width 0.125) (layer "In2.Cu") (net 29))
  (segment (start 132.71253 87.523229) (end 132.690758 87.545001) (width 0.125) (layer "In2.Cu") (net 29))
  (segment (start 131.179171 87.256844) (end 131.271278 87.289074) (width 0.125) (layer "In2.Cu") (net 29))
  (segment (start 131.027544 87.739073) (end 130.975627 87.821699) (width 0.125) (layer "In2.Cu") (net 29))
  (segment (start 132.690758 88.745001) (end 132.664688 88.761383) (width 0.125) (layer "In2.Cu") (net 29))
  (segment (start 131.027544 86.539073) (end 130.975627 86.621699) (width 0.125) (layer "In2.Cu") (net 29))
  (segment (start 103.2625 95.607527) (end 103.4625 95.407527) (width 0.125) (layer "In2.Cu") (net 29))
  (segment (start 131.848426 89.113806) (end 131.8375 89.210775) (width 0.125) (layer "In2.Cu") (net 29))
  (segment (start 131.785729 86.345001) (end 131.759659 86.361383) (width 0.125) (layer "In2.Cu") (net 29))
  (segment (start 131.096545 87.670072) (end 131.027544 87.739073) (width 0.125) (layer "In2.Cu") (net 29))
  (segment (start 132.742528 88.6375) (end 132.739081 88.668096) (width 0.125) (layer "In2.Cu") (net 29))
  (segment (start 131.759659 86.361383) (end 131.730596 86.371552) (width 0.125) (layer "In2.Cu") (net 29))
  (segment (start 131.932573 88.939073) (end 131.880656 89.021699) (width 0.125) (layer "In2.Cu") (net 29))
  (segment (start 131.179171 86.418155) (end 131.096545 86.470072) (width 0.125) (layer "In2.Cu") (net 29))
  (segment (start 130.943397 87.913806) (end 130.932472 88.010775) (width 0.125) (layer "In2.Cu") (net 29))
  (segment (start 132.0842 88.818155) (end 132.001574 88.870072) (width 0.125) (layer "In2.Cu") (net 29))
  (segment (start 132.605028 87.3) (end 132.635625 87.303447) (width 0.125) (layer "In2.Cu") (net 29))
  (segment (start 131.027544 88.335926) (end 131.096545 88.404927) (width 0.125) (layer "In2.Cu") (net 29))
  (segment (start 130.932472 88.010775) (end 130.932472 88.064224) (width 0.125) (layer "In2.Cu") (net 29))
  (segment (start 132.728912 87.37784) (end 132.739081 87.406903) (width 0.125) (layer "In2.Cu") (net 29))
  (segment (start 132.605028 88.5) (end 132.635625 88.503447) (width 0.125) (layer "In2.Cu") (net 29))
  (segment (start 132.742528 87.4375) (end 132.739081 87.468096) (width 0.125) (layer "In2.Cu") (net 29))
  (segment (start 132.635625 88.503447) (end 132.664688 88.513616) (width 0.125) (layer "In2.Cu") (net 29))
  (segment (start 131.179171 88.456844) (end 131.271278 88.489074) (width 0.125) (layer "In2.Cu") (net 29))
  (segment (start 130.975627 87.821699) (end 130.943397 87.913806) (width 0.125) (layer "In2.Cu") (net 29))
  (segment (start 131.368247 87.575) (end 131.271278 87.585925) (width 0.125) (layer "In2.Cu") (net 29))
  (segment (start 131.8375 89.210775) (end 131.8375 93.43269) (width 0.125) (layer "In2.Cu") (net 29))
  (segment (start 132.635625 88.771552) (end 132.605028 88.775) (width 0.125) (layer "In2.Cu") (net 29))
  (segment (start 131.096545 86.470072) (end 131.027544 86.539073) (width 0.125) (layer "In2.Cu") (net 29))
  (segment (start 131.096545 88.404927) (end 131.179171 88.456844) (width 0.125) (layer "In2.Cu") (net 29))
  (segment (start 132.71253 88.723229) (end 132.690758 88.745001) (width 0.125) (layer "In2.Cu") (net 29))
  (segment (start 132.605028 87.575) (end 131.368247 87.575) (width 0.125) (layer "In2.Cu") (net 29))
  (segment (start 132.728912 88.57784) (end 132.739081 88.606903) (width 0.125) (layer "In2.Cu") (net 29))
  (segment (start 132.605028 88.775) (end 132.273276 88.775) (width 0.125) (layer "In2.Cu") (net 29))
  (segment (start 130.932472 86.810775) (end 130.932472 86.864224) (width 0.125) (layer "In2.Cu") (net 29))
  (segment (start 131.271278 86.385925) (end 131.179171 86.418155) (width 0.125) (layer "In2.Cu") (net 29))
  (segment (start 132.71253 87.35177) (end 132.728912 87.37784) (width 0.125) (layer "In2.Cu") (net 29))
  (segment (start 103.225 94.290001) (end 103.225 95.170027) (width 0.125) (layer "B.Cu") (net 29))
  (segment (start 103.225 95.170027) (end 103.4625 95.407527) (width 0.125) (layer "B.Cu") (net 29))
  (segment (start 103.34 93.95) (end 103.34 94.175001) (width 0.125) (layer "B.Cu") (net 29))
  (segment (start 103.34 94.175001) (end 103.225 94.290001) (width 0.125) (layer "B.Cu") (net 29))
  (segment (start 132.250001 84.650151) (end 132.125 84.775152) (width 0.125) (layer "F.Cu") (net 30))
  (segment (start 132.250001 83.45) (end 132.250001 84.650151) (width 0.125) (layer "F.Cu") (net 30))
  (segment (start 132.125 85.014306) (end 132.3625 85.251806) (width 0.125) (layer "F.Cu") (net 30))
  (segment (start 132.125 84.775152) (end 132.125 85.014306) (width 0.125) (layer "F.Cu") (net 30))
  (via (at 102.7375 95.407527) (size 0.6) (drill 0.25) (layers "F.Cu" "B.Cu") (net 30))
  (via (at 132.3625 85.251806) (size 0.6) (drill 0.25) (layers "F.Cu" "B.Cu") (net 30))
  (segment (start 132.240341 89.113616) (end 132.214271 89.129998) (width 0.125) (layer "In2.Cu") (net 30))
  (segment (start 132.903455 88.270072) (end 132.972456 88.339073) (width 0.125) (layer "In2.Cu") (net 30))
  (segment (start 131.309242 88.145001) (end 131.335312 88.161383) (width 0.125) (layer "In2.Cu") (net 30))
  (segment (start 132.3 89.1) (end 132.269404 89.103447) (width 0.125) (layer "In2.Cu") (net 30))
  (segment (start 131.823693 86.689074) (end 131.726724 86.7) (width 0.125) (layer "In2.Cu") (net 30))
  (segment (start 132.151574 86.361193) (end 132.119344 86.4533) (width 0.125) (layer "In2.Cu") (net 30))
  (segment (start 132.067427 86.535926) (end 131.998426 86.604927) (width 0.125) (layer "In2.Cu") (net 30))
  (segment (start 132.728722 89.089074) (end 132.631753 89.1) (width 0.125) (layer "In2.Cu") (net 30))
  (segment (start 133.056603 87.561193) (end 133.024373 87.6533) (width 0.125) (layer "In2.Cu") (net 30))
  (segment (start 131.28747 87.95177) (end 131.271088 87.97784) (width 0.125) (layer "In2.Cu") (net 30))
  (segment (start 132.631753 87.9) (end 131.394972 87.9) (width 0.125) (layer "In2.Cu") (net 30))
  (segment (start 102.9375 96.16731) (end 102.9375 95.607527) (width 0.125) (layer "In2.Cu") (net 30))
  (segment (start 132.1625 89.2375) (end 132.1625 93.56731) (width 0.125) (layer "In2.Cu") (net 30))
  (segment (start 132.820829 88.218155) (end 132.903455 88.270072) (width 0.125) (layer "In2.Cu") (net 30))
  (segment (start 133.024373 87.6533) (end 132.972456 87.735926) (width 0.125) (layer "In2.Cu") (net 30))
  (segment (start 133.024373 87.221699) (end 133.056603 87.313806) (width 0.125) (layer "In2.Cu") (net 30))
  (segment (start 131.271088 86.77784) (end 131.260919 86.806903) (width 0.125) (layer "In2.Cu") (net 30))
  (segment (start 133.056603 88.513806) (end 133.067528 88.610775) (width 0.125) (layer "In2.Cu") (net 30))
  (segment (start 131.364375 86.971552) (end 131.394972 86.975) (width 0.125) (layer "In2.Cu") (net 30))
  (segment (start 132.728722 88.185925) (end 132.820829 88.218155) (width 0.125) (layer "In2.Cu") (net 30))
  (segment (start 133.024373 88.421699) (end 133.056603 88.513806) (width 0.125) (layer "In2.Cu") (net 30))
  (segment (start 132.903455 87.804927) (end 132.820829 87.856844) (width 0.125) (layer "In2.Cu") (net 30))
  (segment (start 132.1625 85.451806) (end 132.1625 86.264224) (width 0.125) (layer "In2.Cu") (net 30))
  (segment (start 132.192499 89.15177) (end 132.176117 89.17784) (width 0.125) (layer "In2.Cu") (net 30))
  (segment (start 131.257472 86.8375) (end 131.260919 86.868096) (width 0.125) (layer "In2.Cu") (net 30))
  (segment (start 131.309242 86.729998) (end 131.28747 86.75177) (width 0.125) (layer "In2.Cu") (net 30))
  (segment (start 131.260919 86.868096) (end 131.271088 86.897159) (width 0.125) (layer "In2.Cu") (net 30))
  (segment (start 131.364375 88.171552) (end 131.394972 88.175) (width 0.125) (layer "In2.Cu") (net 30))
  (segment (start 107.33269 100.5625) (end 102.9375 96.16731) (width 0.125) (layer "In2.Cu") (net 30))
  (segment (start 132.1625 93.56731) (end 125.16731 100.5625) (width 0.125) (layer "In2.Cu") (net 30))
  (segment (start 131.364375 87.903447) (end 131.335312 87.913616) (width 0.125) (layer "In2.Cu") (net 30))
  (segment (start 132.903455 89.004927) (end 132.820829 89.056844) (width 0.125) (layer "In2.Cu") (net 30))
  (segment (start 131.260919 86.806903) (end 131.257472 86.8375) (width 0.125) (layer "In2.Cu") (net 30))
  (segment (start 132.1625 86.264224) (end 132.151574 86.361193) (width 0.125) (layer "In2.Cu") (net 30))
  (segment (start 132.269404 89.103447) (end 132.240341 89.113616) (width 0.125) (layer "In2.Cu") (net 30))
  (segment (start 132.728722 87.889074) (end 132.631753 87.9) (width 0.125) (layer "In2.Cu") (net 30))
  (segment (start 133.024373 88.8533) (end 132.972456 88.935926) (width 0.125) (layer "In2.Cu") (net 30))
  (segment (start 132.3625 85.251806) (end 132.1625 85.451806) (width 0.125) (layer "In2.Cu") (net 30))
  (segment (start 131.394972 88.175) (end 132.631753 88.175) (width 0.125) (layer "In2.Cu") (net 30))
  (segment (start 132.631753 89.1) (end 132.3 89.1) (width 0.125) (layer "In2.Cu") (net 30))
  (segment (start 132.119344 86.4533) (end 132.067427 86.535926) (width 0.125) (layer "In2.Cu") (net 30))
  (segment (start 131.28747 86.923229) (end 131.309242 86.945001) (width 0.125) (layer "In2.Cu") (net 30))
  (segment (start 132.165948 89.206903) (end 132.1625 89.2375) (width 0.125) (layer "In2.Cu") (net 30))
  (segment (start 131.9158 86.656844) (end 131.823693 86.689074) (width 0.125) (layer "In2.Cu") (net 30))
  (segment (start 131.271088 86.897159) (end 131.28747 86.923229) (width 0.125) (layer "In2.Cu") (net 30))
  (segment (start 133.067528 87.464224) (end 133.056603 87.561193) (width 0.125) (layer "In2.Cu") (net 30))
  (segment (start 133.067528 88.664224) (end 133.056603 88.761193) (width 0.125) (layer "In2.Cu") (net 30))
  (segment (start 133.067528 87.410775) (end 133.067528 87.464224) (width 0.125) (layer "In2.Cu") (net 30))
  (segment (start 132.631753 88.175) (end 132.728722 88.185925) (width 0.125) (layer "In2.Cu") (net 30))
  (segment (start 131.726724 86.7) (end 131.394972 86.7) (width 0.125) (layer "In2.Cu") (net 30))
  (segment (start 133.056603 87.313806) (end 133.067528 87.410775) (width 0.125) (layer "In2.Cu") (net 30))
  (segment (start 131.394972 86.975) (end 132.631753 86.975) (width 0.125) (layer "In2.Cu") (net 30))
  (segment (start 132.820829 89.056844) (end 132.728722 89.089074) (width 0.125) (layer "In2.Cu") (net 30))
  (segment (start 131.260919 88.068096) (end 131.271088 88.097159) (width 0.125) (layer "In2.Cu") (net 30))
  (segment (start 133.056603 88.761193) (end 133.024373 88.8533) (width 0.125) (layer "In2.Cu") (net 30))
  (segment (start 132.972456 87.139073) (end 133.024373 87.221699) (width 0.125) (layer "In2.Cu") (net 30))
  (segment (start 131.271088 87.97784) (end 131.260919 88.006903) (width 0.125) (layer "In2.Cu") (net 30))
  (segment (start 131.335312 86.961383) (end 131.364375 86.971552) (width 0.125) (layer "In2.Cu") (net 30))
  (segment (start 131.309242 86.945001) (end 131.335312 86.961383) (width 0.125) (layer "In2.Cu") (net 30))
  (segment (start 102.9375 95.607527) (end 102.7375 95.407527) (width 0.125) (layer "In2.Cu") (net 30))
  (segment (start 132.214271 89.129998) (end 132.192499 89.15177) (width 0.125) (layer "In2.Cu") (net 30))
  (segment (start 131.998426 86.604927) (end 131.9158 86.656844) (width 0.125) (layer "In2.Cu") (net 30))
  (segment (start 132.972456 88.935926) (end 132.903455 89.004927) (width 0.125) (layer "In2.Cu") (net 30))
  (segment (start 125.16731 100.5625) (end 107.33269 100.5625) (width 0.125) (layer "In2.Cu") (net 30))
  (segment (start 131.394972 87.9) (end 131.364375 87.903447) (width 0.125) (layer "In2.Cu") (net 30))
  (segment (start 132.820829 87.856844) (end 132.728722 87.889074) (width 0.125) (layer "In2.Cu") (net 30))
  (segment (start 132.176117 89.17784) (end 132.165948 89.206903) (width 0.125) (layer "In2.Cu") (net 30))
  (segment (start 131.28747 86.75177) (end 131.271088 86.77784) (width 0.125) (layer "In2.Cu") (net 30))
  (segment (start 133.067528 88.610775) (end 133.067528 88.664224) (width 0.125) (layer "In2.Cu") (net 30))
  (segment (start 132.631753 86.975) (end 132.728722 86.985925) (width 0.125) (layer "In2.Cu") (net 30))
  (segment (start 132.972456 88.339073) (end 133.024373 88.421699) (width 0.125) (layer "In2.Cu") (net 30))
  (segment (start 131.335312 88.161383) (end 131.364375 88.171552) (width 0.125) (layer "In2.Cu") (net 30))
  (segment (start 131.28747 88.123229) (end 131.309242 88.145001) (width 0.125) (layer "In2.Cu") (net 30))
  (segment (start 131.271088 88.097159) (end 131.28747 88.123229) (width 0.125) (layer "In2.Cu") (net 30))
  (segment (start 131.394972 86.7) (end 131.364375 86.703447) (width 0.125) (layer "In2.Cu") (net 30))
  (segment (start 132.972456 87.735926) (end 132.903455 87.804927) (width 0.125) (layer "In2.Cu") (net 30))
  (segment (start 131.309242 87.929998) (end 131.28747 87.95177) (width 0.125) (layer "In2.Cu") (net 30))
  (segment (start 131.260919 88.006903) (end 131.257472 88.0375) (width 0.125) (layer "In2.Cu") (net 30))
  (segment (start 132.728722 86.985925) (end 132.820829 87.018155) (width 0.125) (layer "In2.Cu") (net 30))
  (segment (start 131.257472 88.0375) (end 131.260919 88.068096) (width 0.125) (layer "In2.Cu") (net 30))
  (segment (start 131.364375 86.703447) (end 131.335312 86.713616) (width 0.125) (layer "In2.Cu") (net 30))
  (segment (start 132.903455 87.070072) (end 132.972456 87.139073) (width 0.125) (layer "In2.Cu") (net 30))
  (segment (start 131.335312 87.913616) (end 131.309242 87.929998) (width 0.125) (layer "In2.Cu") (net 30))
  (segment (start 132.820829 87.018155) (end 132.903455 87.070072) (width 0.125) (layer "In2.Cu") (net 30))
  (segment (start 131.335312 86.713616) (end 131.309242 86.729998) (width 0.125) (layer "In2.Cu") (net 30))
  (segment (start 102.975 94.290001) (end 102.975 95.170027) (width 0.125) (layer "B.Cu") (net 30))
  (segment (start 102.86 94.175001) (end 102.975 94.290001) (width 0.125) (layer "B.Cu") (net 30))
  (segment (start 102.975 95.170027) (end 102.7375 95.407527) (width 0.125) (layer "B.Cu") (net 30))
  (segment (start 102.86 93.95) (end 102.86 94.175001) (width 0.125) (layer "B.Cu") (net 30))
  (segment (start 130.750001 84.650151) (end 130.625 84.775152) (width 0.125) (layer "F.Cu") (net 31))
  (segment (start 130.750001 83.45) (end 130.750001 84.650151) (width 0.125) (layer "F.Cu") (net 31))
  (segment (start 130.625 84.9625) (end 130.8625 85.2) (width 0.125) (layer "F.Cu") (net 31))
  (segment (start 130.625 84.775152) (end 130.625 84.9625) (width 0.125) (layer "F.Cu") (net 31))
  (via (at 130.8625 85.2) (size 0.6) (drill 0.25) (layers "F.Cu" "B.Cu") (net 31))
  (via (at 104.0375 94.880158) (size 0.6) (drill 0.25) (layers "F.Cu" "B.Cu") (net 31))
  (segment (start 116.014771 98.453659) (end 116.034563 98.433867) (width 0.125) (layer "In2.Cu") (net 31))
  (segment (start 118.579488 99.678373) (end 118.630002 99.758765) (width 0.125) (layer "In2.Cu") (net 31))
  (segment (start 115.0875 99.494407) (end 115.09813 99.588755) (width 0.125) (layer "In2.Cu") (net 31))
  (segment (start 114.9625 99.1625) (end 114.990315 99.165634) (width 0.125) (layer "In2.Cu") (net 31))
  (segment (start 104.2375 95.080158) (end 104.2375 96.21731) (width 0.125) (layer "In2.Cu") (net 31))
  (segment (start 115.327531 99.876416) (end 115.417149 99.907774) (width 0.125) (layer "In2.Cu") (net 31))
  (segment (start 117.164771 98.453659) (end 117.184563 98.433867) (width 0.125) (layer "In2.Cu") (net 31))
  (segment (start 119.6875 98.531595) (end 119.6875 98.738503) (width 0.125) (layer "In2.Cu") (net 31))
  (segment (start 117.1375 98.531595) (end 117.140634 98.50378) (width 0.125) (layer "In2.Cu") (net 31))
  (segment (start 116.210228 98.453659) (end 116.225121 98.47736) (width 0.125) (layer "In2.Cu") (net 31))
  (segment (start 117.360228 98.453659) (end 117.375121 98.47736) (width 0.125) (layer "In2.Cu") (net 31))
  (segment (start 116.225121 98.47736) (end 116.234365 98.50378) (width 0.125) (layer "In2.Cu") (net 31))
  (segment (start 117.39813 99.588755) (end 117.429488 99.678373) (width 0.125) (layer "In2.Cu") (net 31))
  (segment (start 117.126869 99.588755) (end 117.1375 99.494407) (width 0.125) (layer "In2.Cu") (net 31))
  (segment (start 118.4125 98.406595) (end 118.440315 98.40973) (width 0.125) (layer "In2.Cu") (net 31))
  (segment (start 118.440315 98.40973) (end 118.466735 98.418974) (width 0.125) (layer "In2.Cu") (net 31))
  (segment (start 119.5625 98.406595) (end 119.590315 98.40973) (width 0.125) (layer "In2.Cu") (net 31))
  (segment (start 117.863502 99.918405) (end 117.95785 99.907774) (width 0.125) (layer "In2.Cu") (net 31))
  (segment (start 115.511497 99.918405) (end 115.563502 99.918405) (width 0.125) (layer "In2.Cu") (net 31))
  (segment (start 116.234365 98.50378) (end 116.2375 98.531595) (width 0.125) (layer "In2.Cu") (net 31))
  (segment (start 117.384365 98.50378) (end 117.3875 98.531595) (width 0.125) (layer "In2.Cu") (net 31))
  (segment (start 116.166735 98.418974) (end 116.190436 98.433867) (width 0.125) (layer "In2.Cu") (net 31))
  (segment (start 115.040436 99.189771) (end 115.060228 99.209563) (width 0.125) (layer "In2.Cu") (net 31))
  (segment (start 117.044997 99.758765) (end 117.095511 99.678373) (width 0.125) (layer "In2.Cu") (net 31))
  (segment (start 117.375121 98.47736) (end 117.384365 98.50378) (width 0.125) (layer "In2.Cu") (net 31))
  (segment (start 118.490436 98.433867) (end 118.510228 98.453659) (width 0.125) (layer "In2.Cu") (net 31))
  (segment (start 115.9875 99.494407) (end 115.9875 98.531595) (width 0.125) (layer "In2.Cu") (net 31))
  (segment (start 120.111497 99.1625) (end 124.81731 99.1625) (width 0.125) (layer "In2.Cu") (net 31))
  (segment (start 118.697139 99.825902) (end 118.777531 99.876416) (width 0.125) (layer "In2.Cu") (net 31))
  (segment (start 116.897468 99.876416) (end 116.97786 99.825902) (width 0.125) (layer "In2.Cu") (net 31))
  (segment (start 119.4375 99.494407) (end 119.4375 98.531595) (width 0.125) (layer "In2.Cu") (net 31))
  (segment (start 118.867149 99.907774) (end 118.961497 99.918405) (width 0.125) (layer "In2.Cu") (net 31))
  (segment (start 117.140634 98.50378) (end 117.149878 98.47736) (width 0.125) (layer "In2.Cu") (net 31))
  (segment (start 119.684365 98.50378) (end 119.6875 98.531595) (width 0.125) (layer "In2.Cu") (net 31))
  (segment (start 117.095511 99.678373) (end 117.126869 99.588755) (width 0.125) (layer "In2.Cu") (net 31))
  (segment (start 117.2625 98.406595) (end 117.290315 98.40973) (width 0.125) (layer "In2.Cu") (net 31))
  (segment (start 118.534365 98.50378) (end 118.5375 98.531595) (width 0.125) (layer "In2.Cu") (net 31))
  (segment (start 116.567149 99.907774) (end 116.661497 99.918405) (width 0.125) (layer "In2.Cu") (net 31))
  (segment (start 119.464771 98.453659) (end 119.484563 98.433867) (width 0.125) (layer "In2.Cu") (net 31))
  (segment (start 119.675121 98.47736) (end 119.684365 98.50378) (width 0.125) (layer "In2.Cu") (net 31))
  (segment (start 120.017149 99.15187) (end 120.111497 99.1625) (width 0.125) (layer "In2.Cu") (net 31))
  (segment (start 115.894997 99.758765) (end 115.945511 99.678373) (width 0.125) (layer "In2.Cu") (net 31))
  (segment (start 118.2875 98.531595) (end 118.290634 98.50378) (width 0.125) (layer "In2.Cu") (net 31))
  (segment (start 118.466735 98.418974) (end 118.490436 98.433867) (width 0.125) (layer "In2.Cu") (net 31))
  (segment (start 115.129488 99.678373) (end 115.180002 99.758765) (width 0.125) (layer "In2.Cu") (net 31))
  (segment (start 117.340436 98.433867) (end 117.360228 98.453659) (width 0.125) (layer "In2.Cu") (net 31))
  (segment (start 107.18269 99.1625) (end 114.9625 99.1625) (width 0.125) (layer "In2.Cu") (net 31))
  (segment (start 119.426869 99.588755) (end 119.4375 99.494407) (width 0.125) (layer "In2.Cu") (net 31))
  (segment (start 118.047468 99.876416) (end 118.12786 99.825902) (width 0.125) (layer "In2.Cu") (net 31))
  (segment (start 104.2375 96.21731) (end 107.18269 99.1625) (width 0.125) (layer "In2.Cu") (net 31))
  (segment (start 117.1375 99.494407) (end 117.1375 98.531595) (width 0.125) (layer "In2.Cu") (net 31))
  (segment (start 119.847139 99.069998) (end 119.927531 99.120512) (width 0.125) (layer "In2.Cu") (net 31))
  (segment (start 119.197468 99.876416) (end 119.27786 99.825902) (width 0.125) (layer "In2.Cu") (net 31))
  (segment (start 118.358264 98.418974) (end 118.384684 98.40973) (width 0.125) (layer "In2.Cu") (net 31))
  (segment (start 119.729488 98.922469) (end 119.780002 99.002861) (width 0.125) (layer "In2.Cu") (net 31))
  (segment (start 117.480002 99.758765) (end 117.547139 99.825902) (width 0.125) (layer "In2.Cu") (net 31))
  (segment (start 115.084365 99.259684) (end 115.0875 99.2875) (width 0.125) (layer "In2.Cu") (net 31))
  (segment (start 118.630002 99.758765) (end 118.697139 99.825902) (width 0.125) (layer "In2.Cu") (net 31))
  (segment (start 130.6625 85.4) (end 130.8625 85.2) (width 0.125) (layer "In2.Cu") (net 31))
  (segment (start 119.660228 98.453659) (end 119.675121 98.47736) (width 0.125) (layer "In2.Cu") (net 31))
  (segment (start 115.999878 98.47736) (end 116.014771 98.453659) (width 0.125) (layer "In2.Cu") (net 31))
  (segment (start 115.247139 99.825902) (end 115.327531 99.876416) (width 0.125) (layer "In2.Cu") (net 31))
  (segment (start 116.058264 98.418974) (end 116.084684 98.40973) (width 0.125) (layer "In2.Cu") (net 31))
  (segment (start 119.27786 99.825902) (end 119.344997 99.758765) (width 0.125) (layer "In2.Cu") (net 31))
  (segment (start 116.713502 99.918405) (end 116.80785 99.907774) (width 0.125) (layer "In2.Cu") (net 31))
  (segment (start 119.440634 98.50378) (end 119.449878 98.47736) (width 0.125) (layer "In2.Cu") (net 31))
  (segment (start 116.330002 99.758765) (end 116.397139 99.825902) (width 0.125) (layer "In2.Cu") (net 31))
  (segment (start 115.563502 99.918405) (end 115.65785 99.907774) (width 0.125) (layer "In2.Cu") (net 31))
  (segment (start 118.290634 98.50378) (end 118.299878 98.47736) (width 0.125) (layer "In2.Cu") (net 31))
  (segment (start 118.5375 99.494407) (end 118.54813 99.588755) (width 0.125) (layer "In2.Cu") (net 31))
  (segment (start 116.661497 99.918405) (end 116.713502 99.918405) (width 0.125) (layer "In2.Cu") (net 31))
  (segment (start 117.290315 98.40973) (end 117.316735 98.418974) (width 0.125) (layer "In2.Cu") (net 31))
  (segment (start 116.2375 99.494407) (end 116.24813 99.588755) (width 0.125) (layer "In2.Cu") (net 31))
  (segment (start 114.990315 99.165634) (end 115.016735 99.174878) (width 0.125) (layer "In2.Cu") (net 31))
  (segment (start 119.927531 99.120512) (end 120.017149 99.15187) (width 0.125) (layer "In2.Cu") (net 31))
  (segment (start 118.5375 98.531595) (end 118.5375 99.494407) (width 0.125) (layer "In2.Cu") (net 31))
  (segment (start 118.12786 99.825902) (end 118.194997 99.758765) (width 0.125) (layer "In2.Cu") (net 31))
  (segment (start 119.395511 99.678373) (end 119.426869 99.588755) (width 0.125) (layer "In2.Cu") (net 31))
  (segment (start 117.811497 99.918405) (end 117.863502 99.918405) (width 0.125) (layer "In2.Cu") (net 31))
  (segment (start 116.034563 98.433867) (end 116.058264 98.418974) (width 0.125) (layer "In2.Cu") (net 31))
  (segment (start 116.2375 98.531595) (end 116.2375 99.494407) (width 0.125) (layer "In2.Cu") (net 31))
  (segment (start 104.0375 94.880158) (end 104.2375 95.080158) (width 0.125) (layer "In2.Cu") (net 31))
  (segment (start 117.717149 99.907774) (end 117.811497 99.918405) (width 0.125) (layer "In2.Cu") (net 31))
  (segment (start 118.384684 98.40973) (end 118.4125 98.406595) (width 0.125) (layer "In2.Cu") (net 31))
  (segment (start 115.976869 99.588755) (end 115.9875 99.494407) (width 0.125) (layer "In2.Cu") (net 31))
  (segment (start 116.477531 99.876416) (end 116.567149 99.907774) (width 0.125) (layer "In2.Cu") (net 31))
  (segment (start 115.9875 98.531595) (end 115.990634 98.50378) (width 0.125) (layer "In2.Cu") (net 31))
  (segment (start 130.6625 93.31731) (end 130.6625 85.4) (width 0.125) (layer "In2.Cu") (net 31))
  (segment (start 118.299878 98.47736) (end 118.314771 98.453659) (width 0.125) (layer "In2.Cu") (net 31))
  (segment (start 118.314771 98.453659) (end 118.334563 98.433867) (width 0.125) (layer "In2.Cu") (net 31))
  (segment (start 117.547139 99.825902) (end 117.627531 99.876416) (width 0.125) (layer "In2.Cu") (net 31))
  (segment (start 119.508264 98.418974) (end 119.534684 98.40973) (width 0.125) (layer "In2.Cu") (net 31))
  (segment (start 115.747468 99.876416) (end 115.82786 99.825902) (width 0.125) (layer "In2.Cu") (net 31))
  (segment (start 118.276869 99.588755) (end 118.2875 99.494407) (width 0.125) (layer "In2.Cu") (net 31))
  (segment (start 117.184563 98.433867) (end 117.208264 98.418974) (width 0.125) (layer "In2.Cu") (net 31))
  (segment (start 118.510228 98.453659) (end 118.525121 98.47736) (width 0.125) (layer "In2.Cu") (net 31))
  (segment (start 119.10785 99.907774) (end 119.197468 99.876416) (width 0.125) (layer "In2.Cu") (net 31))
  (segment (start 115.180002 99.758765) (end 115.247139 99.825902) (width 0.125) (layer "In2.Cu") (net 31))
  (segment (start 116.190436 98.433867) (end 116.210228 98.453659) (width 0.125) (layer "In2.Cu") (net 31))
  (segment (start 117.316735 98.418974) (end 117.340436 98.433867) (width 0.125) (layer "In2.Cu") (net 31))
  (segment (start 118.245511 99.678373) (end 118.276869 99.588755) (width 0.125) (layer "In2.Cu") (net 31))
  (segment (start 115.990634 98.50378) (end 115.999878 98.47736) (width 0.125) (layer "In2.Cu") (net 31))
  (segment (start 119.780002 99.002861) (end 119.847139 99.069998) (width 0.125) (layer "In2.Cu") (net 31))
  (segment (start 119.4375 98.531595) (end 119.440634 98.50378) (width 0.125) (layer "In2.Cu") (net 31))
  (segment (start 119.69813 98.832851) (end 119.729488 98.922469) (width 0.125) (layer "In2.Cu") (net 31))
  (segment (start 115.016735 99.174878) (end 115.040436 99.189771) (width 0.125) (layer "In2.Cu") (net 31))
  (segment (start 118.961497 99.918405) (end 119.013502 99.918405) (width 0.125) (layer "In2.Cu") (net 31))
  (segment (start 119.534684 98.40973) (end 119.5625 98.406595) (width 0.125) (layer "In2.Cu") (net 31))
  (segment (start 115.0875 99.2875) (end 115.0875 99.494407) (width 0.125) (layer "In2.Cu") (net 31))
  (segment (start 116.24813 99.588755) (end 116.279488 99.678373) (width 0.125) (layer "In2.Cu") (net 31))
  (segment (start 115.09813 99.588755) (end 115.129488 99.678373) (width 0.125) (layer "In2.Cu") (net 31))
  (segment (start 119.449878 98.47736) (end 119.464771 98.453659) (width 0.125) (layer "In2.Cu") (net 31))
  (segment (start 118.334563 98.433867) (end 118.358264 98.418974) (width 0.125) (layer "In2.Cu") (net 31))
  (segment (start 116.97786 99.825902) (end 117.044997 99.758765) (width 0.125) (layer "In2.Cu") (net 31))
  (segment (start 116.084684 98.40973) (end 116.1125 98.406595) (width 0.125) (layer "In2.Cu") (net 31))
  (segment (start 116.80785 99.907774) (end 116.897468 99.876416) (width 0.125) (layer "In2.Cu") (net 31))
  (segment (start 119.590315 98.40973) (end 119.616735 98.418974) (width 0.125) (layer "In2.Cu") (net 31))
  (segment (start 117.234684 98.40973) (end 117.2625 98.406595) (width 0.125) (layer "In2.Cu") (net 31))
  (segment (start 115.417149 99.907774) (end 115.511497 99.918405) (width 0.125) (layer "In2.Cu") (net 31))
  (segment (start 117.627531 99.876416) (end 117.717149 99.907774) (width 0.125) (layer "In2.Cu") (net 31))
  (segment (start 118.54813 99.588755) (end 118.579488 99.678373) (width 0.125) (layer "In2.Cu") (net 31))
  (segment (start 117.95785 99.907774) (end 118.047468 99.876416) (width 0.125) (layer "In2.Cu") (net 31))
  (segment (start 119.484563 98.433867) (end 119.508264 98.418974) (width 0.125) (layer "In2.Cu") (net 31))
  (segment (start 118.777531 99.876416) (end 118.867149 99.907774) (width 0.125) (layer "In2.Cu") (net 31))
  (segment (start 119.616735 98.418974) (end 119.640436 98.433867) (width 0.125) (layer "In2.Cu") (net 31))
  (segment (start 119.6875 98.738503) (end 119.69813 98.832851) (width 0.125) (layer "In2.Cu") (net 31))
  (segment (start 118.525121 98.47736) (end 118.534365 98.50378) (width 0.125) (layer "In2.Cu") (net 31))
  (segment (start 115.65785 99.907774) (end 115.747468 99.876416) (width 0.125) (layer "In2.Cu") (net 31))
  (segment (start 117.3875 98.531595) (end 117.3875 99.494407) (width 0.125) (layer "In2.Cu") (net 31))
  (segment (start 116.397139 99.825902) (end 116.477531 99.876416) (width 0.125) (layer "In2.Cu") (net 31))
  (segment (start 117.429488 99.678373) (end 117.480002 99.758765) (width 0.125) (layer "In2.Cu") (net 31))
  (segment (start 124.81731 99.1625) (end 130.6625 93.31731) (width 0.125) (layer "In2.Cu") (net 31))
  (segment (start 116.279488 99.678373) (end 116.330002 99.758765) (width 0.125) (layer "In2.Cu") (net 31))
  (segment (start 115.82786 99.825902) (end 115.894997 99.758765) (width 0.125) (layer "In2.Cu") (net 31))
  (segment (start 116.1125 98.406595) (end 116.140315 98.40973) (width 0.125) (layer "In2.Cu") (net 31))
  (segment (start 116.140315 98.40973) (end 116.166735 98.418974) (width 0.125) (layer "In2.Cu") (net 31))
  (segment (start 115.945511 99.678373) (end 115.976869 99.588755) (width 0.125) (layer "In2.Cu") (net 31))
  (segment (start 115.060228 99.209563) (end 115.075121 99.233264) (width 0.125) (layer "In2.Cu") (net 31))
  (segment (start 119.013502 99.918405) (end 119.10785 99.907774) (width 0.125) (layer "In2.Cu") (net 31))
  (segment (start 117.149878 98.47736) (end 117.164771 98.453659) (width 0.125) (layer "In2.Cu") (net 31))
  (segment (start 118.194997 99.758765) (end 118.245511 99.678373) (width 0.125) (layer "In2.Cu") (net 31))
  (segment (start 115.075121 99.233264) (end 115.084365 99.259684) (width 0.125) (layer "In2.Cu") (net 31))
  (segment (start 118.2875 99.494407) (end 118.2875 98.531595) (width 0.125) (layer "In2.Cu") (net 31))
  (segment (start 117.3875 99.494407) (end 117.39813 99.588755) (width 0.125) (layer "In2.Cu") (net 31))
  (segment (start 119.640436 98.433867) (end 119.660228 98.453659) (width 0.125) (layer "In2.Cu") (net 31))
  (segment (start 119.344997 99.758765) (end 119.395511 99.678373) (width 0.125) (layer "In2.Cu") (net 31))
  (segment (start 117.208264 98.418974) (end 117.234684 98.40973) (width 0.125) (layer "In2.Cu") (net 31))
  (segment (start 104.275 94.290001) (end 104.275 94.642658) (width 0.125) (layer "B.Cu") (net 31))
  (segment (start 104.275 94.642658) (end 104.0375 94.880158) (width 0.125) (layer "B.Cu") (net 31))
  (segment (start 104.16 93.95) (end 104.16 94.175001) (width 0.125) (layer "B.Cu") (net 31))
  (segment (start 104.16 94.175001) (end 104.275 94.290001) (width 0.125) (layer "B.Cu") (net 31))
  (segment (start 130.25 84.650151) (end 130.375001 84.775152) (width 0.125) (layer "F.Cu") (net 32))
  (segment (start 130.375 84.9625) (end 130.1375 85.2) (width 0.125) (layer "F.Cu") (net 32))
  (segment (start 130.375001 84.775152) (end 130.375 84.9625) (width 0.125) (layer "F.Cu") (net 32))
  (segment (start 130.25 83.45) (end 130.25 84.650151) (width 0.125) (layer "F.Cu") (net 32))
  (via (at 130.1375 85.2) (size 0.6) (drill 0.25) (layers "F.Cu" "B.Cu") (net 32))
  (via (at 104.7625 94.880158) (size 0.6) (drill 0.25) (layers "F.Cu" "B.Cu") (net 32))
  (segment (start 117.236497 98.081595) (end 117.288502 98.081595) (width 0.125) (layer "In2.Cu") (net 32))
  (segment (start 115.509684 99.59027) (end 115.5375 99.593405) (width 0.125) (layer "In2.Cu") (net 32))
  (segment (start 118.202531 98.123584) (end 118.292149 98.092226) (width 0.125) (layer "In2.Cu") (net 32))
  (segment (start 119.772468 98.123584) (end 119.85286 98.174098) (width 0.125) (layer "In2.Cu") (net 32))
  (segment (start 119.1125 99.468405) (end 119.1125 98.505593) (width 0.125) (layer "In2.Cu") (net 32))
  (segment (start 119.919997 98.241235) (end 119.970511 98.321627) (width 0.125) (layer "In2.Cu") (net 32))
  (segment (start 117.288502 98.081595) (end 117.38285 98.092226) (width 0.125) (layer "In2.Cu") (net 32))
  (segment (start 116.520511 98.321627) (end 116.551869 98.411245) (width 0.125) (layer "In2.Cu") (net 32))
  (segment (start 115.822139 98.174098) (end 115.902531 98.123584) (width 0.125) (layer "In2.Cu") (net 32))
  (segment (start 120.1375 98.8375) (end 124.68269 98.8375) (width 0.125) (layer "In2.Cu") (net 32))
  (segment (start 115.992149 98.092226) (end 116.086497 98.081595) (width 0.125) (layer "In2.Cu") (net 32))
  (segment (start 115.615436 99.566133) (end 115.635228 99.546341) (width 0.125) (layer "In2.Cu") (net 32))
  (segment (start 119.442149 98.092226) (end 119.536497 98.081595) (width 0.125) (layer "In2.Cu") (net 32))
  (segment (start 117.739771 99.546341) (end 117.759563 99.566133) (width 0.125) (layer "In2.Cu") (net 32))
  (segment (start 116.086497 98.081595) (end 116.138502 98.081595) (width 0.125) (layer "In2.Cu") (net 32))
  (segment (start 116.138502 98.081595) (end 116.23285 98.092226) (width 0.125) (layer "In2.Cu") (net 32))
  (segment (start 116.633264 99.581026) (end 116.659684 99.59027) (width 0.125) (layer "In2.Cu") (net 32))
  (segment (start 117.891735 99.581026) (end 117.915436 99.566133) (width 0.125) (layer "In2.Cu") (net 32))
  (segment (start 119.015315 99.59027) (end 119.041735 99.581026) (width 0.125) (layer "In2.Cu") (net 32))
  (segment (start 115.172468 98.879488) (end 115.25286 98.930002) (width 0.125) (layer "In2.Cu") (net 32))
  (segment (start 120.015634 98.740316) (end 120.024878 98.766736) (width 0.125) (layer "In2.Cu") (net 32))
  (segment (start 118.8625 99.468405) (end 118.865634 99.49622) (width 0.125) (layer "In2.Cu") (net 32))
  (segment (start 115.650121 99.52264) (end 115.659365 99.49622) (width 0.125) (layer "In2.Cu") (net 32))
  (segment (start 115.635228 99.546341) (end 115.650121 99.52264) (width 0.125) (layer "In2.Cu") (net 32))
  (segment (start 118.055002 98.241235) (end 118.122139 98.174098) (width 0.125) (layer "In2.Cu") (net 32))
  (segment (start 118.386497 98.081595) (end 118.438502 98.081595) (width 0.125) (layer "In2.Cu") (net 32))
  (segment (start 115.401869 99.167149) (end 115.4125 99.261497) (width 0.125) (layer "In2.Cu") (net 32))
  (segment (start 118.292149 98.092226) (end 118.386497 98.081595) (width 0.125) (layer "In2.Cu") (net 32))
  (segment (start 116.589771 99.546341) (end 116.609563 99.566133) (width 0.125) (layer "In2.Cu") (net 32))
  (segment (start 116.659684 99.59027) (end 116.6875 99.593405) (width 0.125) (layer "In2.Cu") (net 32))
  (segment (start 116.5625 99.468405) (end 116.565634 99.49622) (width 0.125) (layer "In2.Cu") (net 32))
  (segment (start 116.785228 99.546341) (end 116.800121 99.52264) (width 0.125) (layer "In2.Cu") (net 32))
  (segment (start 116.809365 99.49622) (end 116.8125 99.468405) (width 0.125) (layer "In2.Cu") (net 32))
  (segment (start 118.909563 99.566133) (end 118.933264 99.581026) (width 0.125) (layer "In2.Cu") (net 32))
  (segment (start 118.820511 98.321627) (end 118.851869 98.411245) (width 0.125) (layer "In2.Cu") (net 32))
  (segment (start 115.4125 99.261497) (end 115.4125 99.468405) (width 0.125) (layer "In2.Cu") (net 32))
  (segment (start 115.659365 99.49622) (end 115.6625 99.468405) (width 0.125) (layer "In2.Cu") (net 32))
  (segment (start 119.588502 98.081595) (end 119.68285 98.092226) (width 0.125) (layer "In2.Cu") (net 32))
  (segment (start 116.6875 99.593405) (end 116.715315 99.59027) (width 0.125) (layer "In2.Cu") (net 32))
  (segment (start 116.5625 98.505593) (end 116.5625 99.468405) (width 0.125) (layer "In2.Cu") (net 32))
  (segment (start 117.97313 98.411245) (end 118.004488 98.321627) (width 0.125) (layer "In2.Cu") (net 32))
  (segment (start 104.5625 96.08269) (end 107.31731 98.8375) (width 0.125) (layer "In2.Cu") (net 32))
  (segment (start 117.915436 99.566133) (end 117.935228 99.546341) (width 0.125) (layer "In2.Cu") (net 32))
  (segment (start 117.9625 98.505593) (end 117.97313 98.411245) (width 0.125) (layer "In2.Cu") (net 32))
  (segment (start 117.8375 99.593405) (end 117.865315 99.59027) (width 0.125) (layer "In2.Cu") (net 32))
  (segment (start 115.704488 98.321627) (end 115.755002 98.241235) (width 0.125) (layer "In2.Cu") (net 32))
  (segment (start 130.3375 93.18269) (end 130.3375 85.4) (width 0.125) (layer "In2.Cu") (net 32))
  (segment (start 119.352531 98.123584) (end 119.442149 98.092226) (width 0.125) (layer "In2.Cu") (net 32))
  (segment (start 116.469997 98.241235) (end 116.520511 98.321627) (width 0.125) (layer "In2.Cu") (net 32))
  (segment (start 115.483264 99.581026) (end 115.509684 99.59027) (width 0.125) (layer "In2.Cu") (net 32))
  (segment (start 117.472468 98.123584) (end 117.55286 98.174098) (width 0.125) (layer "In2.Cu") (net 32))
  (segment (start 120.024878 98.766736) (end 120.039771 98.790437) (width 0.125) (layer "In2.Cu") (net 32))
  (segment (start 117.715634 99.49622) (end 117.724878 99.52264) (width 0.125) (layer "In2.Cu") (net 32))
  (segment (start 117.959365 99.49622) (end 117.9625 99.468405) (width 0.125) (layer "In2.Cu") (net 32))
  (segment (start 117.9625 99.468405) (end 117.9625 98.505593) (width 0.125) (layer "In2.Cu") (net 32))
  (segment (start 117.55286 98.174098) (end 117.619997 98.241235) (width 0.125) (layer "In2.Cu") (net 32))
  (segment (start 104.5625 95.080158) (end 104.5625 96.08269) (width 0.125) (layer "In2.Cu") (net 32))
  (segment (start 116.609563 99.566133) (end 116.633264 99.581026) (width 0.125) (layer "In2.Cu") (net 32))
  (segment (start 116.551869 98.411245) (end 116.5625 98.505593) (width 0.125) (layer "In2.Cu") (net 32))
  (segment (start 117.142149 98.092226) (end 117.236497 98.081595) (width 0.125) (layer "In2.Cu") (net 32))
  (segment (start 117.7125 98.505593) (end 117.7125 99.468405) (width 0.125) (layer "In2.Cu") (net 32))
  (segment (start 115.6625 98.505593) (end 115.67313 98.411245) (width 0.125) (layer "In2.Cu") (net 32))
  (segment (start 115.319997 98.997139) (end 115.370511 99.077531) (width 0.125) (layer "In2.Cu") (net 32))
  (segment (start 115.4125 99.468405) (end 115.415634 99.49622) (width 0.125) (layer "In2.Cu") (net 32))
  (segment (start 117.38285 98.092226) (end 117.472468 98.123584) (width 0.125) (layer "In2.Cu") (net 32))
  (segment (start 115.424878 99.52264) (end 115.439771 99.546341) (width 0.125) (layer "In2.Cu") (net 32))
  (segment (start 115.415634 99.49622) (end 115.424878 99.52264) (width 0.125) (layer "In2.Cu") (net 32))
  (segment (start 117.759563 99.566133) (end 117.783264 99.581026) (width 0.125) (layer "In2.Cu") (net 32))
  (segment (start 119.12313 98.411245) (end 119.154488 98.321627) (width 0.125) (layer "In2.Cu") (net 32))
  (segment (start 117.052531 98.123584) (end 117.142149 98.092226) (width 0.125) (layer "In2.Cu") (net 32))
  (segment (start 114.988502 98.8375) (end 115.08285 98.84813) (width 0.125) (layer "In2.Cu") (net 32))
  (segment (start 116.905002 98.241235) (end 116.972139 98.174098) (width 0.125) (layer "In2.Cu") (net 32))
  (segment (start 118.851869 98.411245) (end 118.8625 98.505593) (width 0.125) (layer "In2.Cu") (net 32))
  (segment (start 116.765436 99.566133) (end 116.785228 99.546341) (width 0.125) (layer "In2.Cu") (net 32))
  (segment (start 104.7625 94.880158) (end 104.5625 95.080158) (width 0.125) (layer "In2.Cu") (net 32))
  (segment (start 115.08285 98.84813) (end 115.172468 98.879488) (width 0.125) (layer "In2.Cu") (net 32))
  (segment (start 130.3375 85.4) (end 130.1375 85.2) (width 0.125) (layer "In2.Cu") (net 32))
  (segment (start 120.083264 98.825122) (end 120.109684 98.834366) (width 0.125) (layer "In2.Cu") (net 32))
  (segment (start 116.972139 98.174098) (end 117.052531 98.123584) (width 0.125) (layer "In2.Cu") (net 32))
  (segment (start 117.950121 99.52264) (end 117.959365 99.49622) (width 0.125) (layer "In2.Cu") (net 32))
  (segment (start 107.31731 98.8375) (end 114.988502 98.8375) (width 0.125) (layer "In2.Cu") (net 32))
  (segment (start 117.935228 99.546341) (end 117.950121 99.52264) (width 0.125) (layer "In2.Cu") (net 32))
  (segment (start 116.322468 98.123584) (end 116.40286 98.174098) (width 0.125) (layer "In2.Cu") (net 32))
  (segment (start 115.67313 98.411245) (end 115.704488 98.321627) (width 0.125) (layer "In2.Cu") (net 32))
  (segment (start 120.039771 98.790437) (end 120.059563 98.810229) (width 0.125) (layer "In2.Cu") (net 32))
  (segment (start 115.370511 99.077531) (end 115.401869 99.167149) (width 0.125) (layer "In2.Cu") (net 32))
  (segment (start 119.536497 98.081595) (end 119.588502 98.081595) (width 0.125) (layer "In2.Cu") (net 32))
  (segment (start 118.70286 98.174098) (end 118.769997 98.241235) (width 0.125) (layer "In2.Cu") (net 32))
  (segment (start 118.889771 99.546341) (end 118.909563 99.566133) (width 0.125) (layer "In2.Cu") (net 32))
  (segment (start 119.205002 98.241235) (end 119.272139 98.174098) (width 0.125) (layer "In2.Cu") (net 32))
  (segment (start 116.715315 99.59027) (end 116.741735 99.581026) (width 0.125) (layer "In2.Cu") (net 32))
  (segment (start 116.574878 99.52264) (end 116.589771 99.546341) (width 0.125) (layer "In2.Cu") (net 32))
  (segment (start 116.565634 99.49622) (end 116.574878 99.52264) (width 0.125) (layer "In2.Cu") (net 32))
  (segment (start 118.933264 99.581026) (end 118.959684 99.59027) (width 0.125) (layer "In2.Cu") (net 32))
  (segment (start 118.122139 98.174098) (end 118.202531 98.123584) (width 0.125) (layer "In2.Cu") (net 32))
  (segment (start 115.459563 99.566133) (end 115.483264 99.581026) (width 0.125) (layer "In2.Cu") (net 32))
  (segment (start 116.741735 99.581026) (end 116.765436 99.566133) (width 0.125) (layer "In2.Cu") (net 32))
  (segment (start 120.0125 98.7125) (end 120.015634 98.740316) (width 0.125) (layer "In2.Cu") (net 32))
  (segment (start 118.874878 99.52264) (end 118.889771 99.546341) (width 0.125) (layer "In2.Cu") (net 32))
  (segment (start 120.001869 98.411245) (end 120.0125 98.505593) (width 0.125) (layer "In2.Cu") (net 32))
  (segment (start 115.25286 98.930002) (end 115.319997 98.997139) (width 0.125) (layer "In2.Cu") (net 32))
  (segment (start 116.8125 98.505593) (end 116.82313 98.411245) (width 0.125) (layer "In2.Cu") (net 32))
  (segment (start 116.854488 98.321627) (end 116.905002 98.241235) (width 0.125) (layer "In2.Cu") (net 32))
  (segment (start 117.701869 98.411245) (end 117.7125 98.505593) (width 0.125) (layer "In2.Cu") (net 32))
  (segment (start 119.085228 99.546341) (end 119.100121 99.52264) (width 0.125) (layer "In2.Cu") (net 32))
  (segment (start 119.154488 98.321627) (end 119.205002 98.241235) (width 0.125) (layer "In2.Cu") (net 32))
  (segment (start 117.7125 99.468405) (end 117.715634 99.49622) (width 0.125) (layer "In2.Cu") (net 32))
  (segment (start 119.041735 99.581026) (end 119.065436 99.566133) (width 0.125) (layer "In2.Cu") (net 32))
  (segment (start 117.783264 99.581026) (end 117.809684 99.59027) (width 0.125) (layer "In2.Cu") (net 32))
  (segment (start 120.109684 98.834366) (end 120.1375 98.8375) (width 0.125) (layer "In2.Cu") (net 32))
  (segment (start 119.1125 98.505593) (end 119.12313 98.411245) (width 0.125) (layer "In2.Cu") (net 32))
  (segment (start 116.23285 98.092226) (end 116.322468 98.123584) (width 0.125) (layer "In2.Cu") (net 32))
  (segment (start 117.865315 99.59027) (end 117.891735 99.581026) (width 0.125) (layer "In2.Cu") (net 32))
  (segment (start 119.109365 99.49622) (end 119.1125 99.468405) (width 0.125) (layer "In2.Cu") (net 32))
  (segment (start 115.5375 99.593405) (end 115.565315 99.59027) (width 0.125) (layer "In2.Cu") (net 32))
  (segment (start 117.619997 98.241235) (end 117.670511 98.321627) (width 0.125) (layer "In2.Cu") (net 32))
  (segment (start 117.809684 99.59027) (end 117.8375 99.593405) (width 0.125) (layer "In2.Cu") (net 32))
  (segment (start 119.970511 98.321627) (end 120.001869 98.411245) (width 0.125) (layer "In2.Cu") (net 32))
  (segment (start 115.565315 99.59027) (end 115.591735 99.581026) (width 0.125) (layer "In2.Cu") (net 32))
  (segment (start 115.755002 98.241235) (end 115.822139 98.174098) (width 0.125) (layer "In2.Cu") (net 32))
  (segment (start 119.85286 98.174098) (end 119.919997 98.241235) (width 0.125) (layer "In2.Cu") (net 32))
  (segment (start 118.959684 99.59027) (end 118.9875 99.593405) (width 0.125) (layer "In2.Cu") (net 32))
  (segment (start 116.82313 98.411245) (end 116.854488 98.321627) (width 0.125) (layer "In2.Cu") (net 32))
  (segment (start 117.670511 98.321627) (end 117.701869 98.411245) (width 0.125) (layer "In2.Cu") (net 32))
  (segment (start 118.622468 98.123584) (end 118.70286 98.174098) (width 0.125) (layer "In2.Cu") (net 32))
  (segment (start 117.724878 99.52264) (end 117.739771 99.546341) (width 0.125) (layer "In2.Cu") (net 32))
  (segment (start 119.68285 98.092226) (end 119.772468 98.123584) (width 0.125) (layer "In2.Cu") (net 32))
  (segment (start 118.9875 99.593405) (end 119.015315 99.59027) (width 0.125) (layer "In2.Cu") (net 32))
  (segment (start 115.591735 99.581026) (end 115.615436 99.566133) (width 0.125) (layer "In2.Cu") (net 32))
  (segment (start 118.769997 98.241235) (end 118.820511 98.321627) (width 0.125) (layer "In2.Cu") (net 32))
  (segment (start 116.8125 99.468405) (end 116.8125 98.505593) (width 0.125) (layer "In2.Cu") (net 32))
  (segment (start 115.6625 99.468405) (end 115.6625 98.505593) (width 0.125) (layer "In2.Cu") (net 32))
  (segment (start 115.439771 99.546341) (end 115.459563 99.566133) (width 0.125) (layer "In2.Cu") (net 32))
  (segment (start 118.865634 99.49622) (end 118.874878 99.52264) (width 0.125) (layer "In2.Cu") (net 32))
  (segment (start 116.40286 98.174098) (end 116.469997 98.241235) (width 0.125) (layer "In2.Cu") (net 32))
  (segment (start 118.004488 98.321627) (end 118.055002 98.241235) (width 0.125) (layer "In2.Cu") (net 32))
  (segment (start 119.272139 98.174098) (end 119.352531 98.123584) (width 0.125) (layer "In2.Cu") (net 32))
  (segment (start 118.53285 98.092226) (end 118.622468 98.123584) (width 0.125) (layer "In2.Cu") (net 32))
  (segment (start 120.0125 98.505593) (end 120.0125 98.7125) (width 0.125) (layer "In2.Cu") (net 32))
  (segment (start 115.902531 98.123584) (end 115.992149 98.092226) (width 0.125) (layer "In2.Cu") (net 32))
  (segment (start 116.800121 99.52264) (end 116.809365 99.49622) (width 0.125) (layer "In2.Cu") (net 32))
  (segment (start 119.100121 99.52264) (end 119.109365 99.49622) (width 0.125) (layer "In2.Cu") (net 32))
  (segment (start 124.68269 98.8375) (end 130.3375 93.18269) (width 0.125) (layer "In2.Cu") (net 32))
  (segment (start 118.438502 98.081595) (end 118.53285 98.092226) (width 0.125) (layer "In2.Cu") (net 32))
  (segment (start 118.8625 98.505593) (end 118.8625 99.468405) (width 0.125) (layer "In2.Cu") (net 32))
  (segment (start 119.065436 99.566133) (end 119.085228 99.546341) (width 0.125) (layer "In2.Cu") (net 32))
  (segment (start 120.059563 98.810229) (end 120.083264 98.825122) (width 0.125) (layer "In2.Cu") (net 32))
  (segment (start 104.64 94.175001) (end 104.525 94.290001) (width 0.125) (layer "B.Cu") (net 32))
  (segment (start 104.64 93.95) (end 104.64 94.175001) (width 0.125) (layer "B.Cu") (net 32))
  (segment (start 104.525 94.290001) (end 104.525 94.642658) (width 0.125) (layer "B.Cu") (net 32))
  (segment (start 104.525 94.642658) (end 104.7625 94.880158) (width 0.125) (layer "B.Cu") (net 32))
  (segment (start 129.124999 84.775151) (end 129.124999 84.9625) (width 0.125) (layer "F.Cu") (net 33))
  (segment (start 129.249999 84.650151) (end 129.124999 84.775151) (width 0.125) (layer "F.Cu") (net 33))
  (segment (start 129.249999 83.45) (end 129.249999 84.650151) (width 0.125) (layer "F.Cu") (net 33))
  (segment (start 129.124999 84.9625) (end 129.362499 85.2) (width 0.125) (layer "F.Cu") (net 33))
  (via (at 129.362499 85.2) (size 0.6) (drill 0.25) (layers "F.Cu" "B.Cu") (net 33))
  (via (at 105.743673 96.156327) (size 0.6) (drill 0.25) (layers "F.Cu" "B.Cu") (net 33))
  (segment (start 128.506176 87.628448) (end 128.477113 87.638617) (width 0.125) (layer "In2.Cu") (net 33))
  (segment (start 129.9148 87.038807) (end 129.925725 87.135776) (width 0.125) (layer "In2.Cu") (net 33))
  (segment (start 128.915799 87.943156) (end 128.998425 87.995073) (width 0.125) (layer "In2.Cu") (net 33))
  (segment (start 110.891003 98.564074) (end 110.794034 98.575) (width 0.125) (layer "In2.Cu") (net 33))
  (segment (start 113.465736 98.479927) (end 113.38311 98.531844) (width 0.125) (layer "In2.Cu") (net 33))
  (segment (start 108.82981 97.2125) (end 108.82981 98.139224) (width 0.125) (layer "In2.Cu") (net 33))
  (segment (start 129.151573 88.238807) (end 129.162499 88.335776) (width 0.125) (layer "In2.Cu") (net 33))
  (segment (start 129.119343 88.1467) (end 129.151573 88.238807) (width 0.125) (layer "In2.Cu") (net 33))
  (segment (start 108.243616 98.564074) (end 108.151509 98.531844) (width 0.125) (layer "In2.Cu") (net 33))
  (segment (start 128.536773 86.425001) (end 128.506176 86.428448) (width 0.125) (layer "In2.Cu") (net 33))
  (segment (start 129.88257 86.9467) (end 129.9148 87.038807) (width 0.125) (layer "In2.Cu") (net 33))
  (segment (start 113.984465 97.625033) (end 113.940967 97.555806) (width 0.125) (layer "In2.Cu") (net 33))
  (segment (start 112.42981 97.2125) (end 112.42981 98.139224) (width 0.125) (layer "In2.Cu") (net 33))
  (segment (start 112.265736 98.479927) (end 112.18311 98.531844) (width 0.125) (layer "In2.Cu") (net 33))
  (segment (start 107.901362 97.869403) (end 107.891193 97.84034) (width 0.125) (layer "In2.Cu") (net 33))
  (segment (start 110.468883 98.479927) (end 110.399882 98.410926) (width 0.125) (layer "In2.Cu") (net 33))
  (segment (start 111.278402 97.151568) (end 111.265192 97.15619) (width 0.125) (layer "In2.Cu") (net 33))
  (segment (start 107.853039 97.792498) (end 107.826969 97.776116) (width 0.125) (layer "In2.Cu") (net 33))
  (segment (start 107.874811 97.81427) (end 107.853039 97.792498) (width 0.125) (layer "In2.Cu") (net 33))
  (segment (start 113.90481 97.2125) (end 113.903242 97.198593) (width 0.125) (layer "In2.Cu") (net 33))
  (segment (start 109.115735 98.236193) (end 109.10481 98.139224) (width 0.125) (layer "In2.Cu") (net 33))
  (segment (start 112.435999 97.185383) (end 112.431377 97.198593) (width 0.125) (layer "In2.Cu") (net 33))
  (segment (start 112.418884 98.236193) (end 112.386654 98.3283) (width 0.125) (layer "In2.Cu") (net 33))
  (segment (start 112.868883 98.479927) (end 112.799882 98.410926) (width 0.125) (layer "In2.Cu") (net 33))
  (segment (start 109.103242 97.198593) (end 109.09862 97.185383) (width 0.125) (layer "In2.Cu") (net 33))
  (segment (start 109.081278 97.163636) (end 109.069427 97.15619) (width 0.125) (layer "In2.Cu") (net 33))
  (segment (start 110.794034 98.575) (end 110.740585 98.575) (width 0.125) (layer "In2.Cu") (net 33))
  (segment (start 110.256217 97.151568) (end 110.24231 97.15) (width 0.125) (layer "In2.Cu") (net 33))
  (segment (start 128.726723 87.900001) (end 128.823692 87.910926) (width 0.125) (layer "In2.Cu") (net 33))
  (segment (start 113.631377 97.198593) (end 113.62981 97.2125) (width 0.125) (layer "In2.Cu") (net 33))
  (segment (start 129.679026 87.581845) (end 129.586919 87.614075) (width 0.125) (layer "In2.Cu") (net 33))
  (segment (start 129.067426 88.064074) (end 129.119343 88.1467) (width 0.125) (layer "In2.Cu") (net 33))
  (segment (start 128.412889 86.62216) (end 128.429271 86.64823) (width 0.125) (layer "In2.Cu") (net 33))
  (segment (start 109.691003 98.564074) (end 109.594034 98.575) (width 0.125) (layer "In2.Cu") (net 33))
  (segment (start 129.925725 87.135776) (end 129.925725 87.189225) (width 0.125) (layer "In2.Cu") (net 33))
  (segment (start 114.188674 97.753346) (end 114.111504 97.726343) (width 0.125) (layer "In2.Cu") (net 33))
  (segment (start 114.042277 97.682845) (end 113.984465 97.625033) (width 0.125) (layer "In2.Cu") (net 33))
  (segment (start 108.878402 97.151568) (end 108.865192 97.15619) (width 0.125) (layer "In2.Cu") (net 33))
  (segment (start 110.30481 97.2125) (end 110.303242 97.198593) (width 0.125) (layer "In2.Cu") (net 33))
  (segment (start 113.678402 97.151568) (end 113.665192 97.15619) (width 0.125) (layer "In2.Cu") (net 33))
  (segment (start 129.88257 87.378301) (end 129.830653 87.460927) (width 0.125) (layer "In2.Cu") (net 33))
  (segment (start 111.265192 97.15619) (end 111.253341 97.163636) (width 0.125) (layer "In2.Cu") (net 33))
  (segment (start 110.643616 98.564074) (end 110.551509 98.531844) (width 0.125) (layer "In2.Cu") (net 33))
  (segment (start 128.451043 86.454999) (end 128.429271 86.476771) (width 0.125) (layer "In2.Cu") (net 33))
  (segment (start 112.681278 97.163636) (end 112.669427 97.15619) (width 0.125) (layer "In2.Cu") (net 33))
  (segment (start 128.429271 86.476771) (end 128.412889 86.502841) (width 0.125) (layer "In2.Cu") (net 33))
  (segment (start 110.053341 97.163636) (end 110.043445 97.173532) (width 0.125) (layer "In2.Cu") (net 33))
  (segment (start 109.10481 98.139224) (end 109.10481 97.2125) (width 0.125) (layer "In2.Cu") (net 33))
  (segment (start 110.315735 98.236193) (end 110.30481 98.139224) (width 0.125) (layer "In2.Cu") (net 33))
  (segment (start 128.399273 86.562501) (end 128.40272 86.593097) (width 0.125) (layer "In2.Cu") (net 33))
  (segment (start 111.065736 98.479927) (end 110.98311 98.531844) (width 0.125) (layer "In2.Cu") (net 33))
  (segment (start 113.618884 98.236193) (end 113.586654 98.3283) (width 0.125) (layer "In2.Cu") (net 33))
  (segment (start 128.477113 87.886384) (end 128.506176 87.896553) (width 0.125) (layer "In2.Cu") (net 33))
  (segment (start 111.599882 98.410926) (end 111.547965 98.3283) (width 0.125) (layer "In2.Cu") (net 33))
  (segment (start 107.90481 98.139224) (end 107.90481 97.9) (width 0.125) (layer "In2.Cu") (net 33))
  (segment (start 112.691174 97.173532) (end 112.681278 97.163636) (width 0.125) (layer "In2.Cu") (net 33))
  (segment (start 107.90481 97.9) (end 107.901362 97.869403) (width 0.125) (layer "In2.Cu") (net 33))
  (segment (start 108.82981 98.139224) (end 108.818884 98.236193) (width 0.125) (layer "In2.Cu") (net 33))
  (segment (start 111.668883 98.479927) (end 111.599882 98.410926) (width 0.125) (layer "In2.Cu") (net 33))
  (segment (start 112.091003 98.564074) (end 111.994034 98.575) (width 0.125) (layer "In2.Cu") (net 33))
  (segment (start 111.843616 98.564074) (end 111.751509 98.531844) (width 0.125) (layer "In2.Cu") (net 33))
  (segment (start 129.162499 88.335776) (end 129.162499 92.817311) (width 0.125) (layer "In2.Cu") (net 33))
  (segment (start 128.477113 86.438617) (end 128.451043 86.454999) (width 0.125) (layer "In2.Cu") (net 33))
  (segment (start 113.38311 98.531844) (end 113.291003 98.564074) (width 0.125) (layer "In2.Cu") (net 33))
  (segment (start 107.915735 98.236193) (end 107.90481 98.139224) (width 0.125) (layer "In2.Cu") (net 33))
  (segment (start 112.656217 97.151568) (end 112.64231 97.15) (width 0.125) (layer "In2.Cu") (net 33))
  (segment (start 107.999882 98.410926) (end 107.947965 98.3283) (width 0.125) (layer "In2.Cu") (net 33))
  (segment (start 113.635999 97.185383) (end 113.631377 97.198593) (width 0.125) (layer "In2.Cu") (net 33))
  (segment (start 108.151509 98.531844) (end 108.068883 98.479927) (width 0.125) (layer "In2.Cu") (net 33))
  (segment (start 108.853341 97.163636) (end 108.843445 97.173532) (width 0.125) (layer "In2.Cu") (net 33))
  (segment (start 110.035999 97.185383) (end 110.031377 97.198593) (width 0.125) (layer "In2.Cu") (net 33))
  (segment (start 128.412889 86.502841) (end 128.40272 86.531904) (width 0.125) (layer "In2.Cu") (net 33))
  (segment (start 113.69231 97.15) (end 113.678402 97.151568) (width 0.125) (layer "In2.Cu") (net 33))
  (segment (start 110.30481 98.139224) (end 110.30481 97.2125) (width 0.125) (layer "In2.Cu") (net 33))
  (segment (start 108.58311 98.531844) (end 108.491003 98.564074) (width 0.125) (layer "In2.Cu") (net 33))
  (segment (start 109.147965 98.3283) (end 109.115735 98.236193) (width 0.125) (layer "In2.Cu") (net 33))
  (segment (start 111.231377 97.198593) (end 111.22981 97.2125) (width 0.125) (layer "In2.Cu") (net 33))
  (segment (start 110.399882 98.410926) (end 110.347965 98.3283) (width 0.125) (layer "In2.Cu") (net 33))
  (segment (start 111.29231 97.15) (end 111.278402 97.151568) (width 0.125) (layer "In2.Cu") (net 33))
  (segment (start 113.043616 98.564074) (end 112.951509 98.531844) (width 0.125) (layer "In2.Cu") (net 33))
  (segment (start 113.643445 97.173532) (end 113.635999 97.185383) (width 0.125) (layer "In2.Cu") (net 33))
  (segment (start 128.823692 86.414075) (end 128.726723 86.425001) (width 0.125) (layer "In2.Cu") (net 33))
  (segment (start 109.199882 98.410926) (end 109.147965 98.3283) (width 0.125) (layer "In2.Cu") (net 33))
  (segment (start 112.70481 97.2125) (end 112.703242 97.198593) (width 0.125) (layer "In2.Cu") (net 33))
  (segment (start 107.891193 97.84034) (end 107.874811 97.81427) (width 0.125) (layer "In2.Cu") (net 33))
  (segment (start 108.865192 97.15619) (end 108.853341 97.163636) (width 0.125) (layer "In2.Cu") (net 33))
  (segment (start 109.986654 98.3283) (end 109.934737 98.410926) (width 0.125) (layer "In2.Cu") (net 33))
  (segment (start 113.903242 97.198593) (end 113.89862 97.185383) (width 0.125) (layer "In2.Cu") (net 33))
  (segment (start 113.140585 98.575) (end 113.043616 98.564074) (width 0.125) (layer "In2.Cu") (net 33))
  (segment (start 110.031377 97.198593) (end 110.02981 97.2125) (width 0.125) (layer "In2.Cu") (net 33))
  (segment (start 113.891174 97.173532) (end 113.881278 97.163636) (width 0.125) (layer "In2.Cu") (net 33))
  (segment (start 128.399273 87.762501) (end 128.40272 87.793097) (width 0.125) (layer "In2.Cu") (net 33))
  (segment (start 110.740585 98.575) (end 110.643616 98.564074) (width 0.125) (layer "In2.Cu") (net 33))
  (segment (start 108.818884 98.236193) (end 108.786654 98.3283) (width 0.125) (layer "In2.Cu") (net 33))
  (segment (start 129.119343 86.178301) (end 129.067426 86.260927) (width 0.125) (layer "In2.Cu") (net 33))
  (segment (start 111.44231 97.15) (end 111.29231 97.15) (width 0.125) (layer "In2.Cu") (net 33))
  (segment (start 107.797906 97.765947) (end 107.76731 97.7625) (width 0.125) (layer "In2.Cu") (net 33))
  (segment (start 128.998425 86.329928) (end 128.915799 86.381845) (width 0.125) (layer "In2.Cu") (net 33))
  (segment (start 111.50481 98.139224) (end 111.50481 97.2125) (width 0.125) (layer "In2.Cu") (net 33))
  (segment (start 129.925725 87.189225) (end 129.9148 87.286194) (width 0.125) (layer "In2.Cu") (net 33))
  (segment (start 108.835999 97.185383) (end 108.831377 97.198593) (width 0.125) (layer "In2.Cu") (net 33))
  (segment (start 128.536773 87.900001) (end 128.726723 87.900001) (width 0.125) (layer "In2.Cu") (net 33))
  (segment (start 129.830653 86.864074) (end 129.88257 86.9467) (width 0.125) (layer "In2.Cu") (net 33))
  (segment (start 129.761652 86.795073) (end 129.830653 86.864074) (width 0.125) (layer "In2.Cu") (net 33))
  (segment (start 129.362499 85.2) (end 129.162499 85.4) (width 0.125) (layer "In2.Cu") (net 33))
  (segment (start 109.04231 97.15) (end 108.89231 97.15) (width 0.125) (layer "In2.Cu") (net 33))
  (segment (start 129.9148 87.286194) (end 129.88257 87.378301) (width 0.125) (layer "In2.Cu") (net 33))
  (segment (start 113.534737 98.410926) (end 113.465736 98.479927) (width 0.125) (layer "In2.Cu") (net 33))
  (segment (start 108.665736 98.479927) (end 108.58311 98.531844) (width 0.125) (layer "In2.Cu") (net 33))
  (segment (start 111.22981 97.2125) (end 111.22981 98.139224) (width 0.125) (layer "In2.Cu") (net 33))
  (segment (start 106.026517 96.156327) (end 105.743673 96.156327) (width 0.125) (layer "In2.Cu") (net 33))
  (segment (start 108.786654 98.3283) (end 108.734737 98.410926) (width 0.125) (layer "In2.Cu") (net 33))
  (segment (start 108.89231 97.15) (end 108.878402 97.151568) (width 0.125) (layer "In2.Cu") (net 33))
  (segment (start 111.218884 98.236193) (end 111.186654 98.3283) (width 0.125) (layer "In2.Cu") (net 33))
  (segment (start 108.843445 97.173532) (end 108.835999 97.185383) (width 0.125) (layer "In2.Cu") (net 33))
  (segment (start 112.334737 98.410926) (end 112.265736 98.479927) (width 0.125) (layer "In2.Cu") (net 33))
  (segment (start 129.067426 86.260927) (end 128.998425 86.329928) (width 0.125) (layer "In2.Cu") (net 33))
  (segment (start 128.451043 87.654999) (end 128.429271 87.676771) (width 0.125) (layer "In2.Cu") (net 33))
  (segment (start 128.823692 87.910926) (end 128.915799 87.943156) (width 0.125) (layer "In2.Cu") (net 33))
  (segment (start 129.586919 86.710926) (end 129.679026 86.743156) (width 0.125) (layer "In2.Cu") (net 33))
  (segment (start 128.536773 86.700001) (end 129.48995 86.700001) (width 0.125) (layer "In2.Cu") (net 33))
  (segment (start 111.22981 98.139224) (end 111.218884 98.236193) (width 0.125) (layer "In2.Cu") (net 33))
  (segment (start 109.443616 98.564074) (end 109.351509 98.531844) (width 0.125) (layer "In2.Cu") (net 33))
  (segment (start 128.506176 86.428448) (end 128.477113 86.438617) (width 0.125) (layer "In2.Cu") (net 33))
  (segment (start 113.881278 97.163636) (end 113.869427 97.15619) (width 0.125) (layer "In2.Cu") (net 33))
  (segment (start 109.091174 97.173532) (end 109.081278 97.163636) (width 0.125) (layer "In2.Cu") (net 33))
  (segment (start 111.491174 97.173532) (end 111.481278 97.163636) (width 0.125) (layer "In2.Cu") (net 33))
  (segment (start 112.18311 98.531844) (end 112.091003 98.564074) (width 0.125) (layer "In2.Cu") (net 33))
  (segment (start 110.281278 97.163636) (end 110.269427 97.15619) (width 0.125) (layer "In2.Cu") (net 33))
  (segment (start 109.268883 98.479927) (end 109.199882 98.410926) (width 0.125) (layer "In2.Cu") (net 33))
  (segment (start 111.994034 98.575) (end 111.940585 98.575) (width 0.125) (layer "In2.Cu") (net 33))
  (segment (start 112.64231 97.15) (end 112.49231 97.15) (width 0.125) (layer "In2.Cu") (net 33))
  (segment (start 128.998425 87.995073) (end 129.067426 88.064074) (width 0.125) (layer "In2.Cu") (net 33))
  (segment (start 111.243445 97.173532) (end 111.235999 97.185383) (width 0.125) (layer "In2.Cu") (net 33))
  (segment (start 129.151573 86.086194) (end 129.119343 86.178301) (width 0.125) (layer "In2.Cu") (net 33))
  (segment (start 109.540585 98.575) (end 109.443616 98.564074) (width 0.125) (layer "In2.Cu") (net 33))
  (segment (start 113.940967 97.555806) (end 113.913964 97.478636) (width 0.125) (layer "In2.Cu") (net 33))
  (segment (start 128.451043 86.670002) (end 128.477113 86.686384) (width 0.125) (layer "In2.Cu") (net 33))
  (segment (start 112.69862 97.185383) (end 112.691174 97.173532) (width 0.125) (layer "In2.Cu") (net 33))
  (segment (start 128.40272 86.531904) (end 128.399273 86.562501) (width 0.125) (layer "In2.Cu") (net 33))
  (segment (start 112.465192 97.15619) (end 112.453341 97.163636) (width 0.125) (layer "In2.Cu") (net 33))
  (segment (start 111.134737 98.410926) (end 111.065736 98.479927) (width 0.125) (layer "In2.Cu") (net 33))
  (segment (start 110.24231 97.15) (end 110.09231 97.15) (width 0.125) (layer "In2.Cu") (net 33))
  (segment (start 111.50481 97.2125) (end 111.503242 97.198593) (width 0.125) (layer "In2.Cu") (net 33))
  (segment (start 109.78311 98.531844) (end 109.691003 98.564074) (width 0.125) (layer "In2.Cu") (net 33))
  (segment (start 113.653341 97.163636) (end 113.643445 97.173532) (width 0.125) (layer "In2.Cu") (net 33))
  (segment (start 110.02981 97.2125) (end 110.02981 98.139224) (width 0.125) (layer "In2.Cu") (net 33))
  (segment (start 110.078402 97.151568) (end 110.065192 97.15619) (width 0.125) (layer "In2.Cu") (net 33))
  (segment (start 111.49862 97.185383) (end 111.491174 97.173532) (width 0.125) (layer "In2.Cu") (net 33))
  (segment (start 111.481278 97.163636) (end 111.469427 97.15619) (width 0.125) (layer "In2.Cu") (net 33))
  (segment (start 112.747965 98.3283) (end 112.715735 98.236193) (width 0.125) (layer "In2.Cu") (net 33))
  (segment (start 128.40272 86.593097) (end 128.412889 86.62216) (width 0.125) (layer "In2.Cu") (net 33))
  (segment (start 112.70481 98.139224) (end 112.70481 97.2125) (width 0.125) (layer "In2.Cu") (net 33))
  (segment (start 128.40272 87.731904) (end 128.399273 87.762501) (width 0.125) (layer "In2.Cu") (net 33))
  (segment (start 113.84231 97.15) (end 113.69231 97.15) (width 0.125) (layer "In2.Cu") (net 33))
  (segment (start 111.469427 97.15619) (end 111.456217 97.151568) (width 0.125) (layer "In2.Cu") (net 33))
  (segment (start 113.869427 97.15619) (end 113.856217 97.151568) (width 0.125) (layer "In2.Cu") (net 33))
  (segment (start 129.586919 87.614075) (end 129.48995 87.625001) (width 0.125) (layer "In2.Cu") (net 33))
  (segment (start 113.62981 97.2125) (end 113.62981 98.139224) (width 0.125) (layer "In2.Cu") (net 33))
  (segment (start 111.456217 97.151568) (end 111.44231 97.15) (width 0.125) (layer "In2.Cu") (net 33))
  (segment (start 129.162499 85.4) (end 129.162499 85.989225) (width 0.125) (layer "In2.Cu") (net 33))
  (segment (start 107.63269 97.7625) (end 106.026517 96.156327) (width 0.125) (layer "In2.Cu") (net 33))
  (segment (start 109.594034 98.575) (end 109.540585 98.575) (width 0.125) (layer "In2.Cu") (net 33))
  (segment (start 128.429271 87.676771) (end 128.412889 87.702841) (width 0.125) (layer "In2.Cu") (net 33))
  (segment (start 112.715735 98.236193) (end 112.70481 98.139224) (width 0.125) (layer "In2.Cu") (net 33))
  (segment (start 110.303242 97.198593) (end 110.29862 97.185383) (width 0.125) (layer "In2.Cu") (net 33))
  (segment (start 129.830653 87.460927) (end 129.761652 87.529928) (width 0.125) (layer "In2.Cu") (net 33))
  (segment (start 128.429271 86.64823) (end 128.451043 86.670002) (width 0.125) (layer "In2.Cu") (net 33))
  (segment (start 110.043445 97.173532) (end 110.035999 97.185383) (width 0.125) (layer "In2.Cu") (net 33))
  (segment (start 113.90481 97.397392) (end 113.90481 97.2125) (width 0.125) (layer "In2.Cu") (net 33))
  (segment (start 113.89862 97.185383) (end 113.891174 97.173532) (width 0.125) (layer "In2.Cu") (net 33))
  (segment (start 110.269427 97.15619) (end 110.256217 97.151568) (width 0.125) (layer "In2.Cu") (net 33))
  (segment (start 112.951509 98.531844) (end 112.868883 98.479927) (width 0.125) (layer "In2.Cu") (net 33))
  (segment (start 112.431377 97.198593) (end 112.42981 97.2125) (width 0.125) (layer "In2.Cu") (net 33))
  (segment (start 109.351509 98.531844) (end 109.268883 98.479927) (width 0.125) (layer "In2.Cu") (net 33))
  (segment (start 110.98311 98.531844) (end 110.891003 98.564074) (width 0.125) (layer "In2.Cu") (net 33))
  (segment (start 128.40272 87.793097) (end 128.412889 87.82216) (width 0.125) (layer "In2.Cu") (net 33))
  (segment (start 109.10481 97.2125) (end 109.103242 97.198593) (width 0.125) (layer "In2.Cu") (net 33))
  (segment (start 112.453341 97.163636) (end 112.443445 97.173532) (width 0.125) (layer "In2.Cu") (net 33))
  (segment (start 110.065192 97.15619) (end 110.053341 97.163636) (width 0.125) (layer "In2.Cu") (net 33))
  (segment (start 129.48995 86.700001) (end 129.586919 86.710926) (width 0.125) (layer "In2.Cu") (net 33))
  (segment (start 112.386654 98.3283) (end 112.334737 98.410926) (width 0.125) (layer "In2.Cu") (net 33))
  (segment (start 112.703242 97.198593) (end 112.69862 97.185383) (width 0.125) (layer "In2.Cu") (net 33))
  (segment (start 111.751509 98.531844) (end 111.668883 98.479927) (width 0.125) (layer "In2.Cu") (net 33))
  (segment (start 114.111504 97.726343) (end 114.042277 97.682845) (width 0.125) (layer "In2.Cu") (net 33))
  (segment (start 129.48995 87.625001) (end 128.536773 87.625001) (width 0.125) (layer "In2.Cu") (net 33))
  (segment (start 128.429271 87.84823) (end 128.451043 87.870002) (width 0.125) (layer "In2.Cu") (net 33))
  (segment (start 129.761652 87.529928) (end 129.679026 87.581845) (width 0.125) (layer "In2.Cu") (net 33))
  (segment (start 113.665192 97.15619) (end 113.653341 97.163636) (width 0.125) (layer "In2.Cu") (net 33))
  (segment (start 129.162499 85.989225) (end 129.151573 86.086194) (width 0.125) (layer "In2.Cu") (net 33))
  (segment (start 128.536773 87.625001) (end 128.506176 87.628448) (width 0.125) (layer "In2.Cu") (net 33))
  (segment (start 129.679026 86.743156) (end 129.761652 86.795073) (width 0.125) (layer "In2.Cu") (net 33))
  (segment (start 113.856217 97.151568) (end 113.84231 97.15) (width 0.125) (layer "In2.Cu") (net 33))
  (segment (start 107.826969 97.776116) (end 107.797906 97.765947) (width 0.125) (layer "In2.Cu") (net 33))
  (segment (start 109.056217 97.151568) (end 109.04231 97.15) (width 0.125) (layer "In2.Cu") (net 33))
  (segment (start 107.76731 97.7625) (end 107.63269 97.7625) (width 0.125) (layer "In2.Cu") (net 33))
  (segment (start 108.831377 97.198593) (end 108.82981 97.2125) (width 0.125) (layer "In2.Cu") (net 33))
  (segment (start 111.253341 97.163636) (end 111.243445 97.173532) (width 0.125) (layer "In2.Cu") (net 33))
  (segment (start 110.018884 98.236193) (end 109.986654 98.3283) (width 0.125) (layer "In2.Cu") (net 33))
  (segment (start 128.915799 86.381845) (end 128.823692 86.414075) (width 0.125) (layer "In2.Cu") (net 33))
  (segment (start 128.506176 87.896553) (end 128.536773 87.900001) (width 0.125) (layer "In2.Cu") (net 33))
  (segment (start 129.162499 92.817311) (end 124.21731 97.7625) (width 0.125) (layer "In2.Cu") (net 33))
  (segment (start 128.412889 87.702841) (end 128.40272 87.731904) (width 0.125) (layer "In2.Cu") (net 33))
  (segment (start 107.947965 98.3283) (end 107.915735 98.236193) (width 0.125) (layer "In2.Cu") (net 33))
  (segment (start 112.49231 97.15) (end 112.478402 97.151568) (width 0.125) (layer "In2.Cu") (net 33))
  (segment (start 124.21731 97.7625) (end 114.269918 97.7625) (width 0.125) (layer "In2.Cu") (net 33))
  (segment (start 109.09862 97.185383) (end 109.091174 97.173532) (width 0.125) (layer "In2.Cu") (net 33))
  (segment (start 111.186654 98.3283) (end 111.134737 98.410926) (width 0.125) (layer "In2.Cu") (net 33))
  (segment (start 112.478402 97.151568) (end 112.465192 97.15619) (width 0.125) (layer "In2.Cu") (net 33))
  (segment (start 108.394034 98.575) (end 108.340585 98.575) (width 0.125) (layer "In2.Cu") (net 33))
  (segment (start 108.068883 98.479927) (end 107.999882 98.410926) (width 0.125) (layer "In2.Cu") (net 33))
  (segment (start 113.194034 98.575) (end 113.140585 98.575) (width 0.125) (layer "In2.Cu") (net 33))
  (segment (start 112.799882 98.410926) (end 112.747965 98.3283) (width 0.125) (layer "In2.Cu") (net 33))
  (segment (start 112.669427 97.15619) (end 112.656217 97.151568) (width 0.125) (layer "In2.Cu") (net 33))
  (segment (start 112.42981 98.139224) (end 112.418884 98.236193) (width 0.125) (layer "In2.Cu") (net 33))
  (segment (start 128.477113 87.638617) (end 128.451043 87.654999) (width 0.125) (layer "In2.Cu") (net 33))
  (segment (start 113.586654 98.3283) (end 113.534737 98.410926) (width 0.125) (layer "In2.Cu") (net 33))
  (segment (start 128.726723 86.425001) (end 128.536773 86.425001) (width 0.125) (layer "In2.Cu") (net 33))
  (segment (start 113.62981 98.139224) (end 113.618884 98.236193) (width 0.125) (layer "In2.Cu") (net 33))
  (segment (start 128.412889 87.82216) (end 128.429271 87.84823) (width 0.125) (layer "In2.Cu") (net 33))
  (segment (start 128.477113 86.686384) (end 128.506176 86.696553) (width 0.125) (layer "In2.Cu") (net 33))
  (segment (start 111.235999 97.185383) (end 111.231377 97.198593) (width 0.125) (layer "In2.Cu") (net 33))
  (segment (start 128.451043 87.870002) (end 128.477113 87.886384) (width 0.125) (layer "In2.Cu") (net 33))
  (segment (start 109.865736 98.479927) (end 109.78311 98.531844) (width 0.125) (layer "In2.Cu") (net 33))
  (segment (start 109.069427 97.15619) (end 109.056217 97.151568) (width 0.125) (layer "In2.Cu") (net 33))
  (segment (start 108.491003 98.564074) (end 108.394034 98.575) (width 0.125) (layer "In2.Cu") (net 33))
  (segment (start 110.29862 97.185383) (end 110.291174 97.173532) (width 0.125) (layer "In2.Cu") (net 33))
  (segment (start 128.506176 86.696553) (end 128.536773 86.700001) (width 0.125) (layer "In2.Cu") (net 33))
  (segment (start 110.02981 98.139224) (end 110.018884 98.236193) (width 0.125) (layer "In2.Cu") (net 33))
  (segment (start 113.913964 97.478636) (end 113.90481 97.397392) (width 0.125) (layer "In2.Cu") (net 33))
  (segment (start 110.347965 98.3283) (end 110.315735 98.236193) (width 0.125) (layer "In2.Cu") (net 33))
  (segment (start 109.934737 98.410926) (end 109.865736 98.479927) (width 0.125) (layer "In2.Cu") (net 33))
  (segment (start 114.269918 97.7625) (end 114.188674 97.753346) (width 0.125) (layer "In2.Cu") (net 33))
  (segment (start 111.503242 97.198593) (end 111.49862 97.185383) (width 0.125) (layer "In2.Cu") (net 33))
  (segment (start 110.09231 97.15) (end 110.078402 97.151568) (width 0.125) (layer "In2.Cu") (net 33))
  (segment (start 108.340585 98.575) (end 108.243616 98.564074) (width 0.125) (layer "In2.Cu") (net 33))
  (segment (start 113.291003 98.564074) (end 113.194034 98.575) (width 0.125) (layer "In2.Cu") (net 33))
  (segment (start 110.551509 98.531844) (end 110.468883 98.479927) (width 0.125) (layer "In2.Cu") (net 33))
  (segment (start 111.547965 98.3283) (end 111.515735 98.236193) (width 0.125) (layer "In2.Cu") (net 33))
  (segment (start 110.291174 97.173532) (end 110.281278 97.163636) (width 0.125) (layer "In2.Cu") (net 33))
  (segment (start 108.734737 98.410926) (end 108.665736 98.479927) (width 0.125) (layer "In2.Cu") (net 33))
  (segment (start 111.940585 98.575) (end 111.843616 98.564074) (width 0.125) (layer "In2.Cu") (net 33))
  (segment (start 112.443445 97.173532) (end 112.435999 97.185383) (width 0.125) (layer "In2.Cu") (net 33))
  (segment (start 111.515735 98.236193) (end 111.50481 98.139224) (width 0.125) (layer "In2.Cu") (net 33))
  (segment (start 105.46 93.95) (end 105.46 94.175001) (width 0.125) (layer "B.Cu") (net 33))
  (segment (start 105.46 94.175001) (end 105.575 94.290001) (width 0.125) (layer "B.Cu") (net 33))
  (segment (start 105.575 94.290001) (end 105.575 95.651777) (width 0.125) (layer "B.Cu") (net 33))
  (segment (start 105.743673 95.82045) (end 105.743673 96.156327) (width 0.125) (layer "B.Cu") (net 33))
  (segment (start 105.575 95.651777) (end 105.743673 95.82045) (width 0.125) (layer "B.Cu") (net 33))
  (segment (start 128.874999 84.9625) (end 128.637499 85.2) (width 0.125) (layer "F.Cu") (net 34))
  (segment (start 128.75 83.45) (end 128.75 84.650151) (width 0.125) (layer "F.Cu") (net 34))
  (segment (start 128.75 84.650151) (end 128.875 84.775151) (width 0.125) (layer "F.Cu") (net 34))
  (segment (start 128.875 84.775151) (end 128.874999 84.9625) (width 0.125) (layer "F.Cu") (net 34))
  (via (at 106.256327 95.643673) (size 0.6) (drill 0.25) (layers "F.Cu" "B.Cu") (net 34))
  (via (at 128.637499 85.2) (size 0.6) (drill 0.25) (layers "F.Cu" "B.Cu") (net 34))
  (segment (start 114.243445 97.413969) (end 114.235999 97.402118) (width 0.125) (layer "In2.Cu") (net 34))
  (segment (start 114.278402 97.435933) (end 114.265192 97.431311) (width 0.125) (layer "In2.Cu") (net 34))
  (segment (start 110.620655 97.108865) (end 110.593652 97.031695) (width 0.125) (layer "In2.Cu") (net 34))
  (segment (start 108.218884 97.776306) (end 108.186654 97.684199) (width 0.125) (layer "In2.Cu") (net 34))
  (segment (start 128.085198 87.638807) (end 128.074273 87.735776) (width 0.125) (layer "In2.Cu") (net 34))
  (segment (start 109.842277 96.904656) (end 109.784465 96.962468) (width 0.125) (layer "In2.Cu") (net 34))
  (segment (start 111.793652 97.031695) (end 111.750154 96.962468) (width 0.125) (layer "In2.Cu") (net 34))
  (segment (start 110.90481 97.190109) (end 110.90481 98.1125) (width 0.125) (layer "In2.Cu") (net 34))
  (segment (start 109.713964 97.108865) (end 109.70481 97.190109) (width 0.125) (layer "In2.Cu") (net 34))
  (segment (start 111.90765 98.236383) (end 111.88158 98.220001) (width 0.125) (layer "In2.Cu") (net 34))
  (segment (start 108.426969 98.236383) (end 108.397906 98.246552) (width 0.125) (layer "In2.Cu") (net 34))
  (segment (start 128.823882 86.02216) (end 128.8075 86.04823) (width 0.125) (layer "In2.Cu") (net 34))
  (segment (start 128.085198 86.686194) (end 128.117428 86.778301) (width 0.125) (layer "In2.Cu") (net 34))
  (segment (start 110.345945 96.834155) (end 110.264701 96.825) (width 0.125) (layer "In2.Cu") (net 34))
  (segment (start 112.950154 96.962468) (end 112.892342 96.904656) (width 0.125) (layer "In2.Cu") (net 34))
  (segment (start 129.587109 87.102841) (end 129.597278 87.131904) (width 0.125) (layer "In2.Cu") (net 34))
  (segment (start 107.794034 97.4375) (end 107.76731 97.4375) (width 0.125) (layer "In2.Cu") (net 34))
  (segment (start 108.501362 98.143096) (end 108.491193 98.172159) (width 0.125) (layer "In2.Cu") (net 34))
  (segment (start 109.393652 97.031695) (end 109.350154 96.962468) (width 0.125) (layer "In2.Cu") (net 34))
  (segment (start 110.593652 97.031695) (end 110.550154 96.962468) (width 0.125) (layer "In2.Cu") (net 34))
  (segment (start 110.891193 98.172159) (end 110.874811 98.198229) (width 0.125) (layer "In2.Cu") (net 34))
  (segment (start 109.988674 96.834155) (end 109.911504 96.861158) (width 0.125) (layer "In2.Cu") (net 34))
  (segment (start 128.834051 88.331904) (end 128.837499 88.362501) (width 0.125) (layer "In2.Cu") (net 34))
  (segment (start 110.913964 97.108865) (end 110.90481 97.190109) (width 0.125) (layer "In2.Cu") (net 34))
  (segment (start 109.064701 96.825) (end 108.869918 96.825) (width 0.125) (layer "In2.Cu") (net 34))
  (segment (start 128.759658 86.086384) (end 128.730595 86.096553) (width 0.125) (layer "In2.Cu") (net 34))
  (segment (start 114.29231 97.4375) (end 114.278402 97.435933) (width 0.125) (layer "In2.Cu") (net 34))
  (segment (start 108.186654 97.684199) (end 108.134737 97.601573) (width 0.125) (layer "In2.Cu") (net 34))
  (segment (start 108.711504 96.861158) (end 108.642277 96.904656) (width 0.125) (layer "In2.Cu") (net 34))
  (segment (start 128.823882 88.302841) (end 128.834051 88.331904) (width 0.125) (layer "In2.Cu") (net 34))
  (segment (start 111.820655 97.108865) (end 111.793652 97.031695) (width 0.125) (layer "In2.Cu") (net 34))
  (segment (start 110.70765 98.236383) (end 110.68158 98.220001) (width 0.125) (layer "In2.Cu") (net 34))
  (segment (start 111.111504 96.861158) (end 111.042277 96.904656) (width 0.125) (layer "In2.Cu") (net 34))
  (segment (start 108.584465 96.962468) (end 108.540967 97.031695) (width 0.125) (layer "In2.Cu") (net 34))
  (segment (start 110.264701 96.825) (end 110.069918 96.825) (width 0.125) (layer "In2.Cu") (net 34))
  (segment (start 128.085198 86.438807) (end 128.074273 86.535776) (width 0.125) (layer "In2.Cu") (net 34))
  (segment (start 110.550154 96.962468) (end 110.492342 96.904656) (width 0.125) (layer "In2.Cu") (net 34))
  (segment (start 128.699999 88.225001) (end 128.730595 88.228448) (width 0.125) (layer "In2.Cu") (net 34))
  (segment (start 128.169345 86.264074) (end 128.117428 86.3467) (width 0.125) (layer "In2.Cu") (net 34))
  (segment (start 113.669918 96.825) (end 113.588674 96.834155) (width 0.125) (layer "In2.Cu") (net 34))
  (segment (start 112.469918 96.825) (end 112.388674 96.834155) (width 0.125) (layer "In2.Cu") (net 34))
  (segment (start 128.510048 87.300001) (end 128.413079 87.310926) (width 0.125) (layer "In2.Cu") (net 34))
  (segment (start 113.253039 98.220001) (end 113.226969 98.236383) (width 0.125) (layer "In2.Cu") (net 34))
  (segment (start 129.463225 87.025001) (end 129.493822 87.028448) (width 0.125) (layer "In2.Cu") (net 34))
  (segment (start 114.22981 97.375) (end 114.22981 97.190109) (width 0.125) (layer "In2.Cu") (net 34))
  (segment (start 112.101362 98.143096) (end 112.091193 98.172159) (width 0.125) (layer "In2.Cu") (net 34))
  (segment (start 111.623115 96.861158) (end 111.545945 96.834155) (width 0.125) (layer "In2.Cu") (net 34))
  (segment (start 129.493822 87.296553) (end 129.463225 87.300001) (width 0.125) (layer "In2.Cu") (net 34))
  (segment (start 111.96731 98.25) (end 111.936713 98.246552) (width 0.125) (layer "In2.Cu") (net 34))
  (segment (start 112.113964 97.108865) (end 112.10481 97.190109) (width 0.125) (layer "In2.Cu") (net 34))
  (segment (start 128.320972 86.981845) (end 128.413079 87.014075) (width 0.125) (layer "In2.Cu") (net 34))
  (segment (start 110.62981 98.1125) (end 110.62981 97.190109) (width 0.125) (layer "In2.Cu") (net 34))
  (segment (start 113.274811 98.198229) (end 113.253039 98.220001) (width 0.125) (layer "In2.Cu") (net 34))
  (segment (start 110.633257 98.143096) (end 110.62981 98.1125) (width 0.125) (layer "In2.Cu") (net 34))
  (segment (start 108.474811 98.198229) (end 108.453039 98.220001) (width 0.125) (layer "In2.Cu") (net 34))
  (segment (start 112.074811 98.198229) (end 112.053039 98.220001) (width 0.125) (layer "In2.Cu") (net 34))
  (segment (start 112.664701 96.825) (end 112.469918 96.825) (width 0.125) (layer "In2.Cu") (net 34))
  (segment (start 129.570727 87.24823) (end 129.548955 87.270002) (width 0.125) (layer "In2.Cu") (net 34))
  (segment (start 107.76731 97.4375) (end 106.256327 95.926517) (width 0.125) (layer "In2.Cu") (net 34))
  (segment (start 113.384465 96.962468) (end 113.340967 97.031695) (width 0.125) (layer "In2.Cu") (net 34))
  (segment (start 129.463225 87.300001) (end 128.510048 87.300001) (width 0.125) (layer "In2.Cu") (net 34))
  (segment (start 128.837499 92.682691) (end 124.08269 97.4375) (width 0.125) (layer "In2.Cu") (net 34))
  (segment (start 113.059808 98.198229) (end 113.043426 98.172159) (width 0.125) (layer "In2.Cu") (net 34))
  (segment (start 128.637499 85.2) (end 128.837499 85.4) (width 0.125) (layer "In2.Cu") (net 34))
  (segment (start 111.750154 96.962468) (end 111.692342 96.904656) (width 0.125) (layer "In2.Cu") (net 34))
  (segment (start 128.837499 85.4) (end 128.837499 85.962501) (width 0.125) (layer "In2.Cu") (net 34))
  (segment (start 109.420655 97.108865) (end 109.393652 97.031695) (width 0.125) (layer "In2.Cu") (net 34))
  (segment (start 129.493822 87.028448) (end 129.522885 87.038617) (width 0.125) (layer "In2.Cu") (net 34))
  (segment (start 112.091193 98.172159) (end 112.074811 98.198229) (width 0.125) (layer "In2.Cu") (net 34))
  (segment (start 110.68158 98.220001) (end 110.659808 98.198229) (width 0.125) (layer "In2.Cu") (net 34))
  (segment (start 128.837499 88.362501) (end 128.837499 92.682691) (width 0.125) (layer "In2.Cu") (net 34))
  (segment (start 111.88158 98.220001) (end 111.859808 98.198229) (width 0.125) (layer "In2.Cu") (net 34))
  (segment (start 128.510048 86.100001) (end 128.413079 86.110926) (width 0.125) (layer "In2.Cu") (net 34))
  (segment (start 109.56731 98.25) (end 109.536713 98.246552) (width 0.125) (layer "In2.Cu") (net 34))
  (segment (start 124.08269 97.4375) (end 114.29231 97.4375) (width 0.125) (layer "In2.Cu") (net 34))
  (segment (start 109.70481 98.1125) (end 109.701362 98.143096) (width 0.125) (layer "In2.Cu") (net 34))
  (segment (start 109.597906 98.246552) (end 109.56731 98.25) (width 0.125) (layer "In2.Cu") (net 34))
  (segment (start 129.522885 87.286384) (end 129.493822 87.296553) (width 0.125) (layer "In2.Cu") (net 34))
  (segment (start 110.069918 96.825) (end 109.988674 96.834155) (width 0.125) (layer "In2.Cu") (net 34))
  (segment (start 113.30481 97.190109) (end 113.30481 98.1125) (width 0.125) (layer "In2.Cu") (net 34))
  (segment (start 128.074273 87.735776) (end 128.074273 87.789225) (width 0.125) (layer "In2.Cu") (net 34))
  (segment (start 106.256327 95.926517) (end 106.256327 95.643673) (width 0.125) (layer "In2.Cu") (net 34))
  (segment (start 108.22981 97.873275) (end 108.218884 97.776306) (width 0.125) (layer "In2.Cu") (net 34))
  (segment (start 110.643426 98.172159) (end 110.633257 98.143096) (width 0.125) (layer "In2.Cu") (net 34))
  (segment (start 113.340967 97.031695) (end 113.313964 97.108865) (width 0.125) (layer "In2.Cu") (net 34))
  (segment (start 128.117428 87.5467) (end 128.085198 87.638807) (width 0.125) (layer "In2.Cu") (net 34))
  (segment (start 129.548955 87.270002) (end 129.522885 87.286384) (width 0.125) (layer "In2.Cu") (net 34))
  (segment (start 128.169345 86.860927) (end 128.238346 86.929928) (width 0.125) (layer "In2.Cu") (net 34))
  (segment (start 113.301362 98.143096) (end 113.291193 98.172159) (width 0.125) (layer "In2.Cu") (net 34))
  (segment (start 128.117428 87.978301) (end 128.169345 88.060927) (width 0.125) (layer "In2.Cu") (net 34))
  (segment (start 128.510048 87.025001) (end 129.463225 87.025001) (width 0.125) (layer "In2.Cu") (net 34))
  (segment (start 108.788674 96.834155) (end 108.711504 96.861158) (width 0.125) (layer "In2.Cu") (net 34))
  (segment (start 114.193652 97.031695) (end 114.150154 96.962468) (width 0.125) (layer "In2.Cu") (net 34))
  (segment (start 107.891003 97.448425) (end 107.794034 97.4375) (width 0.125) (layer "In2.Cu") (net 34))
  (segment (start 112.993652 97.031695) (end 112.950154 96.962468) (width 0.125) (layer "In2.Cu") (net 34))
  (segment (start 128.074273 86.535776) (end 128.074273 86.589225) (width 0.125) (layer "In2.Cu") (net 34))
  (segment (start 108.642277 96.904656) (end 108.584465 96.962468) (width 0.125) (layer "In2.Cu") (net 34))
  (segment (start 110.76731 98.25) (end 110.736713 98.246552) (width 0.125) (layer "In2.Cu") (net 34))
  (segment (start 109.433257 98.143096) (end 109.42981 98.1125) (width 0.125) (layer "In2.Cu") (net 34))
  (segment (start 114.092342 96.904656) (end 114.023115 96.861158) (width 0.125) (layer "In2.Cu") (net 34))
  (segment (start 113.588674 96.834155) (end 113.511504 96.861158) (width 0.125) (layer "In2.Cu") (net 34))
  (segment (start 110.826969 98.236383) (end 110.797906 98.246552) (width 0.125) (layer "In2.Cu") (net 34))
  (segment (start 110.659808 98.198229) (end 110.643426 98.172159) (width 0.125) (layer "In2.Cu") (net 34))
  (segment (start 128.413079 86.110926) (end 128.320972 86.143156) (width 0.125) (layer "In2.Cu") (net 34))
  (segment (start 112.10481 98.1125) (end 112.101362 98.143096) (width 0.125) (layer "In2.Cu") (net 34))
  (segment (start 129.597278 87.131904) (end 129.600725 87.162501) (width 0.125) (layer "In2.Cu") (net 34))
  (segment (start 107.98311 97.480655) (end 107.891003 97.448425) (width 0.125) (layer "In2.Cu") (net 34))
  (segment (start 108.065736 97.532572) (end 107.98311 97.480655) (width 0.125) (layer "In2.Cu") (net 34))
  (segment (start 110.874811 98.198229) (end 110.853039 98.220001) (width 0.125) (layer "In2.Cu") (net 34))
  (segment (start 112.311504 96.861158) (end 112.242277 96.904656) (width 0.125) (layer "In2.Cu") (net 34))
  (segment (start 108.540967 97.031695) (end 108.513964 97.108865) (width 0.125) (layer "In2.Cu") (net 34))
  (segment (start 111.545945 96.834155) (end 111.464701 96.825) (width 0.125) (layer "In2.Cu") (net 34))
  (segment (start 112.053039 98.220001) (end 112.026969 98.236383) (width 0.125) (layer "In2.Cu") (net 34))
  (segment (start 111.997906 98.246552) (end 111.96731 98.25) (width 0.125) (layer "In2.Cu") (net 34))
  (segment (start 109.626969 98.236383) (end 109.597906 98.246552) (width 0.125) (layer "In2.Cu") (net 34))
  (segment (start 113.033257 98.143096) (end 113.02981 98.1125) (width 0.125) (layer "In2.Cu") (net 34))
  (segment (start 109.48158 98.220001) (end 109.459808 98.198229) (width 0.125) (layer "In2.Cu") (net 34))
  (segment (start 109.701362 98.143096) (end 109.691193 98.172159) (width 0.125) (layer "In2.Cu") (net 34))
  (segment (start 128.238346 87.395073) (end 128.169345 87.464074) (width 0.125) (layer "In2.Cu") (net 34))
  (segment (start 128.238346 86.195073) (end 128.169345 86.264074) (width 0.125) (layer "In2.Cu") (net 34))
  (segment (start 113.136713 98.246552) (end 113.10765 98.236383) (width 0.125) (layer "In2.Cu") (net 34))
  (segment (start 112.140967 97.031695) (end 112.113964 97.108865) (width 0.125) (layer "In2.Cu") (net 34))
  (segment (start 109.653039 98.220001) (end 109.626969 98.236383) (width 0.125) (layer "In2.Cu") (net 34))
  (segment (start 114.22981 97.190109) (end 114.220655 97.108865) (width 0.125) (layer "In2.Cu") (net 34))
  (segment (start 128.320972 86.143156) (end 128.238346 86.195073) (width 0.125) (layer "In2.Cu") (net 34))
  (segment (start 110.853039 98.220001) (end 110.826969 98.236383) (width 0.125) (layer "In2.Cu") (net 34))
  (segment (start 128.074273 87.789225) (end 128.085198 87.886194) (width 0.125) (layer "In2.Cu") (net 34))
  (segment (start 129.548955 87.054999) (end 129.570727 87.076771) (width 0.125) (layer "In2.Cu") (net 34))
  (segment (start 108.134737 97.601573) (end 108.065736 97.532572) (width 0.125) (layer "In2.Cu") (net 34))
  (segment (start 128.785728 86.070002) (end 128.759658 86.086384) (width 0.125) (layer "In2.Cu") (net 34))
  (segment (start 128.759658 88.238617) (end 128.785728 88.254999) (width 0.125) (layer "In2.Cu") (net 34))
  (segment (start 128.074273 86.589225) (end 128.085198 86.686194) (width 0.125) (layer "In2.Cu") (net 34))
  (segment (start 113.864701 96.825) (end 113.669918 96.825) (width 0.125) (layer "In2.Cu") (net 34))
  (segment (start 113.10765 98.236383) (end 113.08158 98.220001) (width 0.125) (layer "In2.Cu") (net 34))
  (segment (start 109.784465 96.962468) (end 109.740967 97.031695) (width 0.125) (layer "In2.Cu") (net 34))
  (segment (start 128.169345 88.060927) (end 128.238346 88.129928) (width 0.125) (layer "In2.Cu") (net 34))
  (segment (start 110.423115 96.861158) (end 110.345945 96.834155) (width 0.125) (layer "In2.Cu") (net 34))
  (segment (start 128.169345 87.464074) (end 128.117428 87.5467) (width 0.125) (layer "In2.Cu") (net 34))
  (segment (start 114.235999 97.402118) (end 114.231377 97.388908) (width 0.125) (layer "In2.Cu") (net 34))
  (segment (start 128.785728 88.254999) (end 128.8075 88.276771) (width 0.125) (layer "In2.Cu") (net 34))
  (segment (start 111.859808 98.198229) (end 111.843426 98.172159) (width 0.125) (layer "In2.Cu") (net 34))
  (segment (start 128.730595 86.096553) (end 128.699999 86.100001) (width 0.125) (layer "In2.Cu") (net 34))
  (segment (start 109.911504 96.861158) (end 109.842277 96.904656) (width 0.125) (layer "In2.Cu") (net 34))
  (segment (start 111.843426 98.172159) (end 111.833257 98.143096) (width 0.125) (layer "In2.Cu") (net 34))
  (segment (start 110.492342 96.904656) (end 110.423115 96.861158) (width 0.125) (layer "In2.Cu") (net 34))
  (segment (start 129.522885 87.038617) (end 129.548955 87.054999) (width 0.125) (layer "In2.Cu") (net 34))
  (segment (start 129.570727 87.076771) (end 129.587109 87.102841) (width 0.125) (layer "In2.Cu") (net 34))
  (segment (start 114.220655 97.108865) (end 114.193652 97.031695) (width 0.125) (layer "In2.Cu") (net 34))
  (segment (start 113.945945 96.834155) (end 113.864701 96.825) (width 0.125) (layer "In2.Cu") (net 34))
  (segment (start 108.869918 96.825) (end 108.788674 96.834155) (width 0.125) (layer "In2.Cu") (net 34))
  (segment (start 114.023115 96.861158) (end 113.945945 96.834155) (width 0.125) (layer "In2.Cu") (net 34))
  (segment (start 108.28158 98.220001) (end 108.259808 98.198229) (width 0.125) (layer "In2.Cu") (net 34))
  (segment (start 111.936713 98.246552) (end 111.90765 98.236383) (width 0.125) (layer "In2.Cu") (net 34))
  (segment (start 113.08158 98.220001) (end 113.059808 98.198229) (width 0.125) (layer "In2.Cu") (net 34))
  (segment (start 108.491193 98.172159) (end 108.474811 98.198229) (width 0.125) (layer "In2.Cu") (net 34))
  (segment (start 112.026969 98.236383) (end 111.997906 98.246552) (width 0.125) (layer "In2.Cu") (net 34))
  (segment (start 112.184465 96.962468) (end 112.140967 97.031695) (width 0.125) (layer "In2.Cu") (net 34))
  (segment (start 109.292342 96.904656) (end 109.223115 96.861158) (width 0.125) (layer "In2.Cu") (net 34))
  (segment (start 113.313964 97.108865) (end 113.30481 97.190109) (width 0.125) (layer "In2.Cu") (net 34))
  (segment (start 129.600725 87.162501) (end 129.597278 87.193097) (width 0.125) (layer "In2.Cu") (net 34))
  (segment (start 128.117428 86.3467) (end 128.085198 86.438807) (width 0.125) (layer "In2.Cu") (net 34))
  (segment (start 128.238346 88.129928) (end 128.320972 88.181845) (width 0.125) (layer "In2.Cu") (net 34))
  (segment (start 112.745945 96.834155) (end 112.664701 96.825) (width 0.125) (layer "In2.Cu") (net 34))
  (segment (start 109.674811 98.198229) (end 109.653039 98.220001) (width 0.125) (layer "In2.Cu") (net 34))
  (segment (start 108.336713 98.246552) (end 108.30765 98.236383) (width 0.125) (layer "In2.Cu") (net 34))
  (segment (start 109.42981 98.1125) (end 109.42981 97.190109) (width 0.125) (layer "In2.Cu") (net 34))
  (segment (start 114.231377 97.388908) (end 114.22981 97.375) (width 0.125) (layer "In2.Cu") (net 34))
  (segment (start 113.16731 98.25) (end 113.136713 98.246552) (width 0.125) (layer "In2.Cu") (net 34))
  (segment (start 109.50765 98.236383) (end 109.48158 98.220001) (width 0.125) (layer "In2.Cu") (net 34))
  (segment (start 110.62981 97.190109) (end 110.620655 97.108865) (width 0.125) (layer "In2.Cu") (net 34))
  (segment (start 112.388674 96.834155) (end 112.311504 96.861158) (width 0.125) (layer "In2.Cu") (net 34))
  (segment (start 110.797906 98.246552) (end 110.76731 98.25) (width 0.125) (layer "In2.Cu") (net 34))
  (segment (start 128.320972 87.343156) (end 128.238346 87.395073) (width 0.125) (layer "In2.Cu") (net 34))
  (segment (start 111.82981 97.190109) (end 111.820655 97.108865) (width 0.125) (layer "In2.Cu") (net 34))
  (segment (start 113.442277 96.904656) (end 113.384465 96.962468) (width 0.125) (layer "In2.Cu") (net 34))
  (segment (start 109.223115 96.861158) (end 109.145945 96.834155) (width 0.125) (layer "In2.Cu") (net 34))
  (segment (start 128.699999 86.100001) (end 128.510048 86.100001) (width 0.125) (layer "In2.Cu") (net 34))
  (segment (start 109.740967 97.031695) (end 109.713964 97.108865) (width 0.125) (layer "In2.Cu") (net 34))
  (segment (start 108.233257 98.143096) (end 108.22981 98.1125) (width 0.125) (layer "In2.Cu") (net 34))
  (segment (start 128.117428 86.778301) (end 128.169345 86.860927) (width 0.125) (layer "In2.Cu") (net 34))
  (segment (start 108.36731 98.25) (end 108.336713 98.246552) (width 0.125) (layer "In2.Cu") (net 34))
  (segment (start 128.085198 87.886194) (end 128.117428 87.978301) (width 0.125) (layer "In2.Cu") (net 34))
  (segment (start 109.691193 98.172159) (end 109.674811 98.198229) (width 0.125) (layer "In2.Cu") (net 34))
  (segment (start 113.02981 97.190109) (end 113.020655 97.108865) (width 0.125) (layer "In2.Cu") (net 34))
  (segment (start 111.692342 96.904656) (end 111.623115 96.861158) (width 0.125) (layer "In2.Cu") (net 34))
  (segment (start 114.265192 97.431311) (end 114.253341 97.423865) (width 0.125) (layer "In2.Cu") (net 34))
  (segment (start 111.82981 98.1125) (end 111.82981 97.190109) (width 0.125) (layer "In2.Cu") (net 34))
  (segment (start 114.150154 96.962468) (end 114.092342 96.904656) (width 0.125) (layer "In2.Cu") (net 34))
  (segment (start 128.834051 85.993097) (end 128.823882 86.02216) (width 0.125) (layer "In2.Cu") (net 34))
  (segment (start 109.536713 98.246552) (end 109.50765 98.236383) (width 0.125) (layer "In2.Cu") (net 34))
  (segment (start 129.587109 87.22216) (end 129.570727 87.24823) (width 0.125) (layer "In2.Cu") (net 34))
  (segment (start 128.510048 88.225001) (end 128.699999 88.225001) (width 0.125) (layer "In2.Cu") (net 34))
  (segment (start 111.188674 96.834155) (end 111.111504 96.861158) (width 0.125) (layer "In2.Cu") (net 34))
  (segment (start 108.50481 98.1125) (end 108.501362 98.143096) (width 0.125) (layer "In2.Cu") (net 34))
  (segment (start 113.02981 98.1125) (end 113.02981 97.190109) (width 0.125) (layer "In2.Cu") (net 34))
  (segment (start 128.413079 87.310926) (end 128.320972 87.343156) (width 0.125) (layer "In2.Cu") (net 34))
  (segment (start 108.513964 97.108865) (end 108.50481 97.190109) (width 0.125) (layer "In2.Cu") (net 34))
  (segment (start 112.242277 96.904656) (end 112.184465 96.962468) (width 0.125) (layer "In2.Cu") (net 34))
  (segment (start 108.259808 98.198229) (end 108.243426 98.172159) (width 0.125) (layer "In2.Cu") (net 34))
  (segment (start 108.397906 98.246552) (end 108.36731 98.25) (width 0.125) (layer "In2.Cu") (net 34))
  (segment (start 109.443426 98.172159) (end 109.433257 98.143096) (width 0.125) (layer "In2.Cu") (net 34))
  (segment (start 113.511504 96.861158) (end 113.442277 96.904656) (width 0.125) (layer "In2.Cu") (net 34))
  (segment (start 110.90481 98.1125) (end 110.901362 98.143096) (width 0.125) (layer "In2.Cu") (net 34))
  (segment (start 109.70481 97.190109) (end 109.70481 98.1125) (width 0.125) (layer "In2.Cu") (net 34))
  (segment (start 112.10481 97.190109) (end 112.10481 98.1125) (width 0.125) (layer "In2.Cu") (net 34))
  (segment (start 109.459808 98.198229) (end 109.443426 98.172159) (width 0.125) (layer "In2.Cu") (net 34))
  (segment (start 109.145945 96.834155) (end 109.064701 96.825) (width 0.125) (layer "In2.Cu") (net 34))
  (segment (start 110.901362 98.143096) (end 110.891193 98.172159) (width 0.125) (layer "In2.Cu") (net 34))
  (segment (start 129.597278 87.193097) (end 129.587109 87.22216) (width 0.125) (layer "In2.Cu") (net 34))
  (segment (start 128.238346 86.929928) (end 128.320972 86.981845) (width 0.125) (layer "In2.Cu") (net 34))
  (segment (start 113.043426 98.172159) (end 113.033257 98.143096) (width 0.125) (layer "In2.Cu") (net 34))
  (segment (start 108.453039 98.220001) (end 108.426969 98.236383) (width 0.125) (layer "In2.Cu") (net 34))
  (segment (start 110.984465 96.962468) (end 110.940967 97.031695) (width 0.125) (layer "In2.Cu") (net 34))
  (segment (start 128.8075 88.276771) (end 128.823882 88.302841) (width 0.125) (layer "In2.Cu") (net 34))
  (segment (start 111.269918 96.825) (end 111.188674 96.834155) (width 0.125) (layer "In2.Cu") (net 34))
  (segment (start 113.291193 98.172159) (end 113.274811 98.198229) (width 0.125) (layer "In2.Cu") (net 34))
  (segment (start 111.042277 96.904656) (end 110.984465 96.962468) (width 0.125) (layer "In2.Cu") (net 34))
  (segment (start 112.823115 96.861158) (end 112.745945 96.834155) (width 0.125) (layer "In2.Cu") (net 34))
  (segment (start 113.020655 97.108865) (end 112.993652 97.031695) (width 0.125) (layer "In2.Cu") (net 34))
  (segment (start 109.350154 96.962468) (end 109.292342 96.904656) (width 0.125) (layer "In2.Cu") (net 34))
  (segment (start 128.413079 88.214075) (end 128.510048 88.225001) (width 0.125) (layer "In2.Cu") (net 34))
  (segment (start 128.8075 86.04823) (end 128.785728 86.070002) (width 0.125) (layer "In2.Cu") (net 34))
  (segment (start 110.736713 98.246552) (end 110.70765 98.236383) (width 0.125) (layer "In2.Cu") (net 34))
  (segment (start 113.197906 98.246552) (end 113.16731 98.25) (width 0.125) (layer "In2.Cu") (net 34))
  (segment (start 113.226969 98.236383) (end 113.197906 98.246552) (width 0.125) (layer "In2.Cu") (net 34))
  (segment (start 128.413079 87.014075) (end 128.510048 87.025001) (width 0.125) (layer "In2.Cu") (net 34))
  (segment (start 110.940967 97.031695) (end 110.913964 97.108865) (width 0.125) (layer "In2.Cu") (net 34))
  (segment (start 108.243426 98.172159) (end 108.233257 98.143096) (width 0.125) (layer "In2.Cu") (net 34))
  (segment (start 108.30765 98.236383) (end 108.28158 98.220001) (width 0.125) (layer "In2.Cu") (net 34))
  (segment (start 113.30481 98.1125) (end 113.301362 98.143096) (width 0.125) (layer "In2.Cu") (net 34))
  (segment (start 128.730595 88.228448) (end 128.759658 88.238617) (width 0.125) (layer "In2.Cu") (net 34))
  (segment (start 111.833257 98.143096) (end 111.82981 98.1125) (width 0.125) (layer "In2.Cu") (net 34))
  (segment (start 112.892342 96.904656) (end 112.823115 96.861158) (width 0.125) (layer "In2.Cu") (net 34))
  (segment (start 108.50481 97.190109) (end 108.50481 98.1125) (width 0.125) (layer "In2.Cu") (net 34))
  (segment (start 128.837499 85.962501) (end 128.834051 85.993097) (width 0.125) (layer "In2.Cu") (net 34))
  (segment (start 108.22981 98.1125) (end 108.22981 97.873275) (width 0.125) (layer "In2.Cu") (net 34))
  (segment (start 114.253341 97.423865) (end 114.243445 97.413969) (width 0.125) (layer "In2.Cu") (net 34))
  (segment (start 111.464701 96.825) (end 111.269918 96.825) (width 0.125) (layer "In2.Cu") (net 34))
  (segment (start 128.320972 88.181845) (end 128.413079 88.214075) (width 0.125) (layer "In2.Cu") (net 34))
  (segment (start 109.42981 97.190109) (end 109.420655 97.108865) (width 0.125) (layer "In2.Cu") (net 34))
  (segment (start 105.825 95.548223) (end 105.92045 95.643673) (width 0.125) (layer "B.Cu") (net 34))
  (segment (start 105.94 93.95) (end 105.94 94.175001) (width 0.125) (layer "B.Cu") (net 34))
  (segment (start 105.92045 95.643673) (end 106.256327 95.643673) (width 0.125) (layer "B.Cu") (net 34))
  (segment (start 105.825 94.290001) (end 105.825 95.548223) (width 0.125) (layer "B.Cu") (net 34))
  (segment (start 105.94 94.175001) (end 105.825 94.290001) (width 0.125) (layer "B.Cu") (net 34))
  (segment (start 115.75 113.75) (end 115.8 113.8) (width 0.125) (layer "F.Cu") (net 35))
  (segment (start 115.75 112.45) (end 115.75 113.75) (width 0.125) (layer "F.Cu") (net 35))
  (via (at 115.8 113.8) (size 0.6) (drill 0.25) (layers "F.Cu" "B.Cu") (net 35))
  (segment (start 117.065 112.95) (end 116.9 113.115) (width 0.2) (layer "B.Cu") (net 35))
  (segment (start 115.8 113.4) (end 115.8 113.8) (width 0.125) (layer "B.Cu") (net 35))
  (segment (start 117.795 112.95) (end 117.01 112.95) (width 0.2) (layer "B.Cu") (net 35))
  (segment (start 116.085 113.115) (end 115.8 113.4) (width 0.125) (layer "B.Cu") (net 35))
  (segment (start 116.9 113.115) (end 116.085 113.115) (width 0.125) (layer "B.Cu") (net 35))
  (segment (start 115.959998 114.7) (end 116 114.7) (width 0.15) (layer "F.Cu") (net 36))
  (segment (start 115.25 112.45) (end 115.25 113.990002) (width 0.15) (layer "F.Cu") (net 36))
  (segment (start 115.25 113.990002) (end 115.959998 114.7) (width 0.15) (layer "F.Cu") (net 36))
  (via (at 116 114.7) (size 0.6) (drill 0.25) (layers "F.Cu" "B.Cu") (net 36))
  (segment (start 117.85 115.55) (end 117.065 115.55) (width 0.2) (layer "B.Cu") (net 36))
  (segment (start 116 114.7) (end 116 114.815) (width 0.15) (layer "B.Cu") (net 36))
  (segment (start 116 114.815) (end 116.9 115.715) (width 0.15) (layer "B.Cu") (net 36))
  (segment (start 154 145.25) (end 151.5 147.75) (width 0.23) (layer "B.Cu") (net 37))
  (segment (start 68.265 85.5) (end 64.5 85.5) (width 0.23) (layer "B.Cu") (net 38))
  (segment (start 61.5 151) (end 64 148.5) (width 0.23) (layer "B.Cu") (net 39))
  (segment (start 131.888922 107.95) (end 132.25 107.95) (width 0.15) (layer "F.Cu") (net 40))
  (segment (start 131.649999 109.649999) (end 131.649999 109.150001) (width 0.15) (layer "F.Cu") (net 40))
  (segment (start 131.649999 109.150001) (end 131.649999 108.188923) (width 0.15) (layer "F.Cu") (net 40))
  (segment (start 131.649999 108.188923) (end 131.888922 107.95) (width 0.15) (layer "F.Cu") (net 40))
  (segment (start 131.649999 112.349999) (end 131.649999 109.649999) (width 0.15) (layer "F.Cu") (net 40))
  (via (at 132.25 107.95) (size 0.6) (drill 0.25) (layers "F.Cu" "B.Cu") (net 40))
  (segment (start 132.1 108.1) (end 132.25 107.95) (width 0.15) (layer "B.Cu") (net 40))
  (segment (start 131.485 108.1) (end 132.1 108.1) (width 0.15) (layer "B.Cu") (net 40))
  (segment (start 132.305 107.895) (end 132.25 107.95) (width 0.15) (layer "B.Cu") (net 40))
  (segment (start 132.8 107.895) (end 132.305 107.895) (width 0.15) (layer "B.Cu") (net 40))
  (segment (start 132.2 108) (end 132.25 107.95) (width 0.15) (layer "B.Cu") (net 40))
  (segment (start 132.2 108.8508) (end 132.2 108) (width 0.15) (layer "B.Cu") (net 40))
  (segment (start 131.25 107.45) (end 131.5 107.2) (width 0.15) (layer "F.Cu") (net 41))
  (segment (start 131.25 108.55) (end 131.25 107.45) (width 0.15) (layer "F.Cu") (net 41))
  (segment (start 131.25 108.75) (end 131.25 108.2) (width 0.15) (layer "F.Cu") (net 41))
  (segment (start 131.25 108.55) (end 131.25 108.35) (width 0.15) (layer "F.Cu") (net 41))
  (segment (start 131.5 107.2) (end 132.25 107.2) (width 0.15) (layer "F.Cu") (net 41))
  (segment (start 131.25 108.75) (end 131.25 108.55) (width 0.15) (layer "F.Cu") (net 41))
  (segment (start 131.25 112.45) (end 131.25 109.7) (width 0.15) (layer "F.Cu") (net 41))
  (segment (start 131.25 109.7) (end 131.25 108.75) (width 0.15) (layer "F.Cu") (net 41))
  (via (at 132.25 107.2) (size 0.6) (drill 0.25) (layers "F.Cu" "B.Cu") (net 41))
  (segment (start 131.485 107.1) (end 132.15 107.1) (width 0.15) (layer "B.Cu") (net 41))
  (segment (start 132.8 107.305) (end 132.355 107.305) (width 0.15) (layer "B.Cu") (net 41))
  (segment (start 130.6508 106.0508) (end 128.9 106.0508) (width 0.15) (layer "B.Cu") (net 41))
  (segment (start 131.485 106.885) (end 130.6508 106.0508) (width 0.15) (layer "B.Cu") (net 41))
  (segment (start 132.355 107.305) (end 132.25 107.2) (width 0.15) (layer "B.Cu") (net 41))
  (segment (start 132.15 107.1) (end 132.25 107.2) (width 0.15) (layer "B.Cu") (net 41))
  (segment (start 110.59 95.54) (end 110.65 95.6) (width 0.15) (layer "F.Cu") (net 42))
  (segment (start 110.65 95.6) (end 110.65 96.115) (width 0.15) (layer "F.Cu") (net 42))
  (segment (start 110.59 95.05) (end 110.59 95.54) (width 0.15) (layer "F.Cu") (net 42))
  (segment (start 112.041736 86.87497) (end 113.67497 86.87497) (width 0.15) (layer "F.Cu") (net 42))
  (segment (start 113.67497 86.87497) (end 114.2 87.4) (width 0.15) (layer "F.Cu") (net 42))
  (segment (start 114.2 87.4) (end 114.2 88.15) (width 0.15) (layer "F.Cu") (net 42))
  (segment (start 101.67497 86.87497) (end 99.25 84.45) (width 0.15) (layer "F.Cu") (net 42))
  (segment (start 112.041736 86.87497) (end 101.67497 86.87497) (width 0.15) (layer "F.Cu") (net 42))
  (segment (start 99.25 84.45) (end 99.25 83.45) (width 0.15) (layer "F.Cu") (net 42))
  (via (at 110.65 95.6) (size 0.6) (drill 0.25) (layers "F.Cu" "B.Cu") (net 42))
  (via (at 114.2 88.15) (size 0.6) (drill 0.25) (layers "F.Cu" "B.Cu") (net 42))
  (segment (start 110.4 94.6) (end 110.4 95.35) (width 0.15) (layer "B.Cu") (net 42))
  (segment (start 110.7 94.3) (end 110.4 94.6) (width 0.15) (layer "B.Cu") (net 42))
  (segment (start 115.07501 93.563912) (end 114.663912 93.97501) (width 0.15) (layer "B.Cu") (net 42))
  (segment (start 114.663912 93.97501) (end 111.02499 93.97501) (width 0.15) (layer "B.Cu") (net 42))
  (segment (start 111.15 94.7008) (end 111.15 95.1) (width 0.15) (layer "B.Cu") (net 42))
  (segment (start 114.474989 88.424989) (end 114.2 88.15) (width 0.15) (layer "B.Cu") (net 42))
  (segment (start 115.07501 92.67501) (end 115.07501 91.763932) (width 0.15) (layer "B.Cu") (net 42))
  (segment (start 114.474989 91.163911) (end 114.474989 88.424989) (width 0.15) (layer "B.Cu") (net 42))
  (segment (start 111.15 95.1) (end 110.65 95.6) (width 0.15) (layer "B.Cu") (net 42))
  (segment (start 115.07501 91.763932) (end 114.474989 91.163911) (width 0.15) (layer "B.Cu") (net 42))
  (segment (start 111.02499 93.97501) (end 110.7 94.3) (width 0.15) (layer "B.Cu") (net 42))
  (segment (start 110.4 95.35) (end 110.65 95.6) (width 0.15) (layer "B.Cu") (net 42))
  (segment (start 115.07501 92.67501) (end 115.07501 93.563912) (width 0.15) (layer "B.Cu") (net 42))
  (segment (start 110.005 95.519997) (end 109.924997 95.6) (width 0.15) (layer "F.Cu") (net 43))
  (segment (start 109.924997 95.6) (end 109.924997 96.140003) (width 0.15) (layer "F.Cu") (net 43))
  (segment (start 110.005 95.05) (end 110.005 95.519997) (width 0.15) (layer "F.Cu") (net 43))
  (segment (start 113.4 87.5) (end 113.04998 87.14998) (width 0.15) (layer "F.Cu") (net 43))
  (segment (start 113.4 88.15) (end 113.4 87.5) (width 0.15) (layer "F.Cu") (net 43))
  (segment (start 101.54998 87.14998) (end 98.75 84.35) (width 0.15) (layer "F.Cu") (net 43))
  (segment (start 98.75 84.35) (end 98.75 83.45) (width 0.15) (layer "F.Cu") (net 43))
  (segment (start 113.04998 87.14998) (end 101.54998 87.14998) (width 0.15) (layer "F.Cu") (net 43))
  (via (at 109.924997 95.6) (size 0.6) (drill 0.25) (layers "F.Cu" "B.Cu") (net 43))
  (via (at 113.4 88.15) (size 0.6) (drill 0.25) (layers "F.Cu" "B.Cu") (net 43))
  (segment (start 114.199979 91.277823) (end 114.199979 88.949979) (width 0.15) (layer "B.Cu") (net 43))
  (segment (start 114.8 91.877844) (end 114.199979 91.277823) (width 0.15) (layer "B.Cu") (net 43))
  (segment (start 110.911078 93.7) (end 114.55 93.7) (width 0.15) (layer "B.Cu") (net 43))
  (segment (start 110.12499 95.400007) (end 110.12499 94.486088) (width 0.15) (layer "B.Cu") (net 43))
  (segment (start 110.230539 94.380539) (end 110.911078 93.7) (width 0.15) (layer "B.Cu") (net 43))
  (segment (start 109.924997 95.6) (end 110.12499 95.400007) (width 0.15) (layer "B.Cu") (net 43))
  (segment (start 110.12499 94.486088) (end 110.044451 94.405549) (width 0.15) (layer "B.Cu") (net 43))
  (segment (start 114.8 93.45) (end 114.8 91.877844) (width 0.15) (layer "B.Cu") (net 43))
  (segment (start 109.789702 94.1508) (end 110.044451 94.405549) (width 0.15) (layer "B.Cu") (net 43))
  (segment (start 110.019441 94.380539) (end 109.989702 94.3508) (width 0.15) (layer "B.Cu") (net 43))
  (segment (start 110.12499 94.486088) (end 110.230539 94.380539) (width 0.15) (layer "B.Cu") (net 43))
  (segment (start 114.625 93.625) (end 114.8 93.45) (width 0.15) (layer "B.Cu") (net 43))
  (segment (start 114.199979 88.949979) (end 113.4 88.15) (width 0.15) (layer "B.Cu") (net 43))
  (segment (start 114.55 93.7) (end 114.625 93.625) (width 0.15) (layer "B.Cu") (net 43))
  (segment (start 110.044451 94.405549) (end 109.989702 94.3508) (width 0.15) (layer "B.Cu") (net 43))
  (segment (start 110.230539 94.380539) (end 110.019441 94.380539) (width 0.15) (layer "B.Cu") (net 43))
  (segment (start 97.75 84.275002) (end 97.75 83.45) (width 0.15) (layer "F.Cu") (net 44))
  (segment (start 101.174998 87.7) (end 97.75 84.275002) (width 0.15) (layer "F.Cu") (net 44))
  (segment (start 109.1 87.7) (end 101.174998 87.7) (width 0.15) (layer "F.Cu") (net 44))
  (segment (start 109.3 87.9) (end 109.1 87.7) (width 0.15) (layer "F.Cu") (net 44))
  (segment (start 109.3 88.2) (end 109.3 87.9) (width 0.15) (layer "F.Cu") (net 44))
  (segment (start 114.15 95.6) (end 114.15 96.115) (width 0.15) (layer "F.Cu") (net 44))
  (segment (start 114.09 95.05) (end 114.09 95.54) (width 0.15) (layer "F.Cu") (net 44))
  (segment (start 114.09 95.54) (end 114.15 95.6) (width 0.15) (layer "F.Cu") (net 44))
  (via (at 114.15 95.6) (size 0.6) (drill 0.25) (layers "F.Cu" "B.Cu") (net 44))
  (via (at 109.3 88.2) (size 0.6) (drill 0.25) (layers "F.Cu" "B.Cu") (net 44))
  (segment (start 108.9 89.2) (end 109.3 89.2) (width 0.15) (layer "B.Cu") (net 44))
  (segment (start 113.87501 96.213912) (end 113.613914 96.475008) (width 0.15) (layer "B.Cu") (net 44))
  (segment (start 111.77501 96.47501) (end 111.67501 96.47501) (width 0.15) (layer "B.Cu") (net 44))
  (segment (start 114.15 95.6) (end 114.15 95.614999) (width 0.15) (layer "B.Cu") (net 44))
  (segment (start 114.15 95.614999) (end 113.87501 95.889989) (width 0.15) (layer "B.Cu") (net 44))
  (segment (start 109.3 89.2) (end 109.5 89) (width 0.15) (layer "B.Cu") (net 44))
  (segment (start 108.474989 95.463911) (end 108.474989 89.625011) (width 0.15) (layer "B.Cu") (net 44))
  (segment (start 111.8 97.2508) (end 111.8 96.7) (width 0.15) (layer "B.Cu") (net 44))
  (segment (start 109.486088 96.47501) (end 108.474989 95.463911) (width 0.15) (layer "B.Cu") (net 44))
  (segment (start 109.5 88.4) (end 109.3 88.2) (width 0.15) (layer "B.Cu") (net 44))
  (segment (start 108.474989 89.625011) (end 108.9 89.2) (width 0.15) (layer "B.Cu") (net 44))
  (segment (start 111.8 96.6) (end 111.92499 96.47501) (width 0.15) (layer "B.Cu") (net 44))
  (segment (start 111.8 96.6) (end 111.67501 96.47501) (width 0.15) (layer "B.Cu") (net 44))
  (segment (start 113.475012 96.475008) (end 113.47501 96.47501) (width 0.15) (layer "B.Cu") (net 44))
  (segment (start 113.47501 96.47501) (end 111.92499 96.47501) (width 0.15) (layer "B.Cu") (net 44))
  (segment (start 113.87501 95.889989) (end 113.87501 96.213912) (width 0.15) (layer "B.Cu") (net 44))
  (segment (start 113.613914 96.475008) (end 113.475012 96.475008) (width 0.15) (layer "B.Cu") (net 44))
  (segment (start 111.92499 96.47501) (end 111.77501 96.47501) (width 0.15) (layer "B.Cu") (net 44))
  (segment (start 111.8 96.7) (end 111.8 96.6) (width 0.15) (layer "B.Cu") (net 44))
  (segment (start 111.67501 96.47501) (end 109.486088 96.47501) (width 0.15) (layer "B.Cu") (net 44))
  (segment (start 109.5 89) (end 109.5 88.4) (width 0.15) (layer "B.Cu") (net 44))
  (segment (start 111.8 96.7) (end 111.8 96.5) (width 0.15) (layer "B.Cu") (net 44))
  (segment (start 111.8 96.5) (end 111.77501 96.47501) (width 0.15) (layer "B.Cu") (net 44))
  (segment (start 110.2 88.15) (end 110.2 87.7) (width 0.15) (layer "F.Cu") (net 45))
  (segment (start 98.25 84.238922) (end 98.25 83.45) (width 0.15) (layer "F.Cu") (net 45))
  (segment (start 110.2 87.7) (end 109.92499 87.42499) (width 0.15) (layer "F.Cu") (net 45))
  (segment (start 113.505 95.519997) (end 113.424997 95.6) (width 0.15) (layer "F.Cu") (net 45))
  (segment (start 113.505 95.05) (end 113.505 95.519997) (width 0.15) (layer "F.Cu") (net 45))
  (segment (start 113.424997 95.6) (end 113.424997 96.140003) (width 0.15) (layer "F.Cu") (net 45))
  (segment (start 101.436068 87.42499) (end 98.25 84.238922) (width 0.15) (layer "F.Cu") (net 45))
  (segment (start 109.92499 87.42499) (end 101.436068 87.42499) (width 0.15) (layer "F.Cu") (net 45))
  (via (at 113.424997 95.6) (size 0.6) (drill 0.25) (layers "F.Cu" "B.Cu") (net 45))
  (via (at 110.2 88.15) (size 0.6) (drill 0.25) (layers "F.Cu" "B.Cu") (net 45))
  (segment (start 113.424997 95.724997) (end 113.6 95.9) (width 0.15) (layer "B.Cu") (net 45))
  (segment (start 109 89.5) (end 109.488922 89.5) (width 0.15) (layer "B.Cu") (net 45))
  (segment (start 108.749999 89.750001) (end 109 89.5) (width 0.15) (layer "B.Cu") (net 45))
  (segment (start 110.15 88.15) (end 110.2 88.15) (width 0.15) (layer "B.Cu") (net 45))
  (segment (start 110.4 97.8) (end 110.4 97.2508) (width 0.15) (layer "B.Cu") (net 45))
  (segment (start 110.6 98) (end 110.4 97.8) (width 0.15) (layer "B.Cu") (net 45))
  (segment (start 113.5 96.2) (end 109.6 96.2) (width 0.15) (layer "B.Cu") (net 45))
  (segment (start 108.749999 95.349999) (end 108.749999 89.750001) (width 0.15) (layer "B.Cu") (net 45))
  (segment (start 113.424997 95.6) (end 113.424997 95.724997) (width 0.15) (layer "B.Cu") (net 45))
  (segment (start 113.7 94.8) (end 114.5 94.8) (width 0.15) (layer "B.Cu") (net 45))
  (segment (start 109.9 88.4) (end 110.15 88.15) (width 0.15) (layer "B.Cu") (net 45))
  (segment (start 113.6 95.9) (end 113.6 96.1) (width 0.15) (layer "B.Cu") (net 45))
  (segment (start 114.8 97.7) (end 114.5 98) (width 0.15) (layer "B.Cu") (net 45))
  (segment (start 113.6 96.1) (end 113.5 96.2) (width 0.15) (layer "B.Cu") (net 45))
  (segment (start 113.424997 95.075003) (end 113.7 94.8) (width 0.15) (layer "B.Cu") (net 45))
  (segment (start 109.9 89.088922) (end 109.9 88.4) (width 0.15) (layer "B.Cu") (net 45))
  (segment (start 113.424997 95.6) (end 113.424997 95.075003) (width 0.15) (layer "B.Cu") (net 45))
  (segment (start 114.8 95.1) (end 114.8 97.7) (width 0.15) (layer "B.Cu") (net 45))
  (segment (start 109.488922 89.5) (end 109.9 89.088922) (width 0.15) (layer "B.Cu") (net 45))
  (segment (start 109.6 96.2) (end 108.749999 95.349999) (width 0.15) (layer "B.Cu") (net 45))
  (segment (start 114.5 94.8) (end 114.8 95.1) (width 0.15) (layer "B.Cu") (net 45))
  (segment (start 114.5 98) (end 110.6 98) (width 0.15) (layer "B.Cu") (net 45))
  (segment (start 103.117554 90.894074) (end 103.083256 90.910591) (width 0.17) (layer "F.Cu") (net 46))
  (segment (start 100.110772 96.355813) (end 100.135173 96.425549) (width 0.17) (layer "F.Cu") (net 46))
  (segment (start 103.192735 90.885603) (end 103.154667 90.885603) (width 0.17) (layer "F.Cu") (net 46))
  (segment (start 103.13859 91.350358) (end 103.130119 91.387471) (width 0.17) (layer "F.Cu") (net 46))
  (segment (start 103.75 90.185) (end 103.8525 90.2875) (width 0.17) (layer "F.Cu") (net 46))
  (segment (start 100.612446 96.950947) (end 100.60017 96.952331) (width 0.17) (layer "F.Cu") (net 46))
  (segment (start 100.289281 96.579657) (end 100.359017 96.604058) (width 0.17) (layer "F.Cu") (net 46))
  (segment (start 103.01324 91.110681) (end 103.029758 91.144979) (width 0.17) (layer "F.Cu") (net 46))
  (segment (start 100.1025 96.282395) (end 100.110772 96.355813) (width 0.17) (layer "F.Cu") (net 46))
  (segment (start 103.029758 90.964088) (end 103.01324 90.998386) (width 0.17) (layer "F.Cu") (net 46))
  (segment (start 100.655339 96.897162) (end 100.653955 96.909438) (width 0.17) (layer "F.Cu") (net 46))
  (segment (start 103.229849 90.894074) (end 103.192735 90.885603) (width 0.17) (layer "F.Cu") (net 46))
  (segment (start 103.330284 90.970701) (end 103.293909 90.934326) (width 0.17) (layer "F.Cu") (net 46))
  (segment (start 100.655339 96.6675) (end 100.655339 96.897162) (width 0.17) (layer "F.Cu") (net 46))
  (segment (start 100.653955 96.909438) (end 100.649875 96.921098) (width 0.17) (layer "F.Cu") (net 46))
  (segment (start 103.154667 90.885603) (end 103.117554 90.894074) (width 0.17) (layer "F.Cu") (net 46))
  (segment (start 100.653955 96.655223) (end 100.655339 96.6675) (width 0.17) (layer "F.Cu") (net 46))
  (segment (start 100.649875 96.643563) (end 100.653955 96.655223) (width 0.17) (layer "F.Cu") (net 46))
  (segment (start 103.089867 91.211116) (end 103.113602 91.240878) (width 0.17) (layer "F.Cu") (net 46))
  (segment (start 103.130119 91.387471) (end 103.113602 91.421769) (width 0.17) (layer "F.Cu") (net 46))
  (segment (start 99.236695 98.3525) (end 99.150561 98.266366) (width 0.17) (layer "F.Cu") (net 46))
  (segment (start 103.540938 90.994435) (end 103.50664 91.010953) (width 0.17) (layer "F.Cu") (net 46))
  (segment (start 100.1025 94.438902) (end 100.1025 96.282395) (width 0.17) (layer "F.Cu") (net 46))
  (segment (start 100.135173 97.139112) (end 100.110772 97.208848) (width 0.17) (layer "F.Cu") (net 46))
  (segment (start 103.113602 91.240878) (end 103.130119 91.275176) (width 0.17) (layer "F.Cu") (net 46))
  (segment (start 103.053493 91.174742) (end 103.089867 91.211116) (width 0.17) (layer "F.Cu") (net 46))
  (segment (start 100.624106 96.617794) (end 100.634567 96.624367) (width 0.17) (layer "F.Cu") (net 46))
  (segment (start 103.293909 90.934326) (end 103.264147 90.910591) (width 0.17) (layer "F.Cu") (net 46))
  (segment (start 100.432435 96.952331) (end 100.359017 96.960603) (width 0.17) (layer "F.Cu") (net 46))
  (segment (start 103.00477 91.073568) (end 103.01324 91.110681) (width 0.17) (layer "F.Cu") (net 46))
  (segment (start 103.264147 90.910591) (end 103.229849 90.894074) (width 0.17) (layer "F.Cu") (net 46))
  (segment (start 99.688902 98.3525) (end 99.236695 98.3525) (width 0.17) (layer "F.Cu") (net 46))
  (segment (start 103.01324 90.998386) (end 103.00477 91.0355) (width 0.17) (layer "F.Cu") (net 46))
  (segment (start 102.132245 92.409157) (end 100.1025 94.438902) (width 0.17) (layer "F.Cu") (net 46))
  (segment (start 103.431458 91.019423) (end 103.394345 91.010953) (width 0.17) (layer "F.Cu") (net 46))
  (segment (start 100.135173 96.425549) (end 100.174481 96.488107) (width 0.17) (layer "F.Cu") (net 46))
  (segment (start 100.624106 96.946867) (end 100.612446 96.950947) (width 0.17) (layer "F.Cu") (net 46))
  (segment (start 100.226723 97.024312) (end 100.174481 97.076554) (width 0.17) (layer "F.Cu") (net 46))
  (segment (start 103.8525 90.688902) (end 103.570701 90.970701) (width 0.17) (layer "F.Cu") (net 46))
  (segment (start 100.110772 97.208848) (end 100.1025 97.282266) (width 0.17) (layer "F.Cu") (net 46))
  (segment (start 103.394345 91.010953) (end 103.360047 90.994435) (width 0.17) (layer "F.Cu") (net 46))
  (segment (start 103.570701 90.970701) (end 103.540938 90.994435) (width 0.17) (layer "F.Cu") (net 46))
  (segment (start 103.00477 91.0355) (end 103.00477 91.073568) (width 0.17) (layer "F.Cu") (net 46))
  (segment (start 100.60017 96.952331) (end 100.432435 96.952331) (width 0.17) (layer "F.Cu") (net 46))
  (segment (start 100.226723 96.540349) (end 100.289281 96.579657) (width 0.17) (layer "F.Cu") (net 46))
  (segment (start 100.359017 96.960603) (end 100.289281 96.985004) (width 0.17) (layer "F.Cu") (net 46))
  (segment (start 100.432435 96.612331) (end 100.60017 96.612331) (width 0.17) (layer "F.Cu") (net 46))
  (segment (start 100.643302 96.633102) (end 100.649875 96.643563) (width 0.17) (layer "F.Cu") (net 46))
  (segment (start 103.130119 91.275176) (end 103.13859 91.31229) (width 0.17) (layer "F.Cu") (net 46))
  (segment (start 100.60017 96.612331) (end 100.612446 96.613714) (width 0.17) (layer "F.Cu") (net 46))
  (segment (start 103.13859 91.31229) (end 103.13859 91.350358) (width 0.17) (layer "F.Cu") (net 46))
  (segment (start 100.289281 96.985004) (end 100.226723 97.024312) (width 0.17) (layer "F.Cu") (net 46))
  (segment (start 103.469526 91.019423) (end 103.431458 91.019423) (width 0.17) (layer "F.Cu") (net 46))
  (segment (start 103.50664 91.010953) (end 103.469526 91.019423) (width 0.17) (layer "F.Cu") (net 46))
  (segment (start 100.612446 96.613714) (end 100.624106 96.617794) (width 0.17) (layer "F.Cu") (net 46))
  (segment (start 103.083256 90.910591) (end 103.053493 90.934326) (width 0.17) (layer "F.Cu") (net 46))
  (segment (start 100.634567 96.940294) (end 100.624106 96.946867) (width 0.17) (layer "F.Cu") (net 46))
  (segment (start 103.029758 91.144979) (end 103.053493 91.174742) (width 0.17) (layer "F.Cu") (net 46))
  (segment (start 100.649875 96.921098) (end 100.643302 96.931559) (width 0.17) (layer "F.Cu") (net 46))
  (segment (start 103.8525 90.2875) (end 103.8525 90.688902) (width 0.17) (layer "F.Cu") (net 46))
  (segment (start 103.089868 91.451533) (end 102.132245 92.409157) (width 0.17) (layer "F.Cu") (net 46))
  (segment (start 100.643302 96.931559) (end 100.634567 96.940294) (width 0.17) (layer "F.Cu") (net 46))
  (segment (start 99.150561 98.266366) (end 99.150561 97.962309) (width 0.17) (layer "F.Cu") (net 46))
  (segment (start 100.174481 96.488107) (end 100.226723 96.540349) (width 0.17) (layer "F.Cu") (net 46))
  (segment (start 100.174481 97.076554) (end 100.135173 97.139112) (width 0.17) (layer "F.Cu") (net 46))
  (segment (start 100.359017 96.604058) (end 100.432435 96.612331) (width 0.17) (layer "F.Cu") (net 46))
  (segment (start 100.634567 96.624367) (end 100.643302 96.633102) (width 0.17) (layer "F.Cu") (net 46))
  (segment (start 100.1025 97.938902) (end 99.688902 98.3525) (width 0.17) (layer "F.Cu") (net 46))
  (segment (start 103.360047 90.994435) (end 103.330284 90.970701) (width 0.17) (layer "F.Cu") (net 46))
  (segment (start 103.053493 90.934326) (end 103.029758 90.964088) (width 0.17) (layer "F.Cu") (net 46))
  (segment (start 100.1025 97.282266) (end 100.1025 97.938902) (width 0.17) (layer "F.Cu") (net 46))
  (segment (start 103.113602 91.421769) (end 103.089868 91.451533) (width 0.17) (layer "F.Cu") (net 46))
  (via (at 99.150561 97.962309) (size 0.6) (drill 0.25) (layers "F.Cu" "B.Cu") (net 46))
  (segment (start 98.571211 101.09344) (end 98.518711 101.04094) (width 0.17) (layer "B.Cu") (net 46))
  (segment (start 99.150561 98.266366) (end 99.150561 97.962309) (width 0.17) (layer "B.Cu") (net 46))
  (segment (start 98.518711 100.089887) (end 99.367052 99.241546) (width 0.17) (layer "B.Cu") (net 46))
  (segment (start 98.518711 101.04094) (end 98.518711 100.089887) (width 0.17) (layer "B.Cu") (net 46))
  (segment (start 99.367052 98.482857) (end 99.150561 98.266366) (width 0.17) (layer "B.Cu") (net 46))
  (segment (start 99.367052 99.241546) (end 99.367052 98.482857) (width 0.17) (layer "B.Cu") (net 46))
  (segment (start 100.878357 97.123107) (end 100.917665 97.060549) (width 0.17) (layer "F.Cu") (net 47))
  (segment (start 100.402963 96.286098) (end 100.398883 96.274438) (width 0.17) (layer "F.Cu") (net 47))
  (segment (start 100.452669 96.317331) (end 100.440392 96.315947) (width 0.17) (layer "F.Cu") (net 47))
  (segment (start 100.826115 96.389312) (end 100.763557 96.350004) (width 0.17) (layer "F.Cu") (net 47))
  (segment (start 100.3975 94.561098) (end 104.1475 90.811098) (width 0.17) (layer "F.Cu") (net 47))
  (segment (start 100.950339 96.917395) (end 100.950339 96.647266) (width 0.17) (layer "F.Cu") (net 47))
  (segment (start 100.428732 96.311867) (end 100.418271 96.305294) (width 0.17) (layer "F.Cu") (net 47))
  (segment (start 100.398883 96.274438) (end 100.3975 96.262162) (width 0.17) (layer "F.Cu") (net 47))
  (segment (start 100.763557 96.350004) (end 100.693821 96.325603) (width 0.17) (layer "F.Cu") (net 47))
  (segment (start 100.409536 97.268102) (end 100.418271 97.259367) (width 0.17) (layer "F.Cu") (net 47))
  (segment (start 100.418271 97.259367) (end 100.428732 97.252794) (width 0.17) (layer "F.Cu") (net 47))
  (segment (start 104.1475 90.2875) (end 104.25 90.185) (width 0.17) (layer "F.Cu") (net 47))
  (segment (start 100.942066 96.990813) (end 100.950339 96.917395) (width 0.17) (layer "F.Cu") (net 47))
  (segment (start 100.917665 97.060549) (end 100.942066 96.990813) (width 0.17) (layer "F.Cu") (net 47))
  (segment (start 100.693821 97.239058) (end 100.763557 97.214657) (width 0.17) (layer "F.Cu") (net 47))
  (segment (start 100.917665 96.504112) (end 100.878357 96.441554) (width 0.17) (layer "F.Cu") (net 47))
  (segment (start 99.811098 98.6475) (end 100.3975 98.061098) (width 0.17) (layer "F.Cu") (net 47))
  (segment (start 98.941964 98.474963) (end 99.114501 98.6475) (width 0.17) (layer "F.Cu") (net 47))
  (segment (start 100.620403 96.317331) (end 100.452669 96.317331) (width 0.17) (layer "F.Cu") (net 47))
  (segment (start 104.1475 90.811098) (end 104.1475 90.2875) (width 0.17) (layer "F.Cu") (net 47))
  (segment (start 100.950339 96.647266) (end 100.942066 96.573848) (width 0.17) (layer "F.Cu") (net 47))
  (segment (start 100.402963 97.278563) (end 100.409536 97.268102) (width 0.17) (layer "F.Cu") (net 47))
  (segment (start 100.3975 96.262162) (end 100.3975 94.561098) (width 0.17) (layer "F.Cu") (net 47))
  (segment (start 100.763557 97.214657) (end 100.826115 97.175349) (width 0.17) (layer "F.Cu") (net 47))
  (segment (start 98.637907 98.474963) (end 98.941964 98.474963) (width 0.17) (layer "F.Cu") (net 47))
  (segment (start 100.826115 97.175349) (end 100.878357 97.123107) (width 0.17) (layer "F.Cu") (net 47))
  (segment (start 100.3975 97.3025) (end 100.398883 97.290223) (width 0.17) (layer "F.Cu") (net 47))
  (segment (start 100.409536 96.296559) (end 100.402963 96.286098) (width 0.17) (layer "F.Cu") (net 47))
  (segment (start 100.398883 97.290223) (end 100.402963 97.278563) (width 0.17) (layer "F.Cu") (net 47))
  (segment (start 100.440392 97.248714) (end 100.452669 97.247331) (width 0.17) (layer "F.Cu") (net 47))
  (segment (start 100.428732 97.252794) (end 100.440392 97.248714) (width 0.17) (layer "F.Cu") (net 47))
  (segment (start 100.440392 96.315947) (end 100.428732 96.311867) (width 0.17) (layer "F.Cu") (net 47))
  (segment (start 100.418271 96.305294) (end 100.409536 96.296559) (width 0.17) (layer "F.Cu") (net 47))
  (segment (start 100.693821 96.325603) (end 100.620403 96.317331) (width 0.17) (layer "F.Cu") (net 47))
  (segment (start 100.620403 97.247331) (end 100.693821 97.239058) (width 0.17) (layer "F.Cu") (net 47))
  (segment (start 99.114501 98.6475) (end 99.811098 98.6475) (width 0.17) (layer "F.Cu") (net 47))
  (segment (start 100.878357 96.441554) (end 100.826115 96.389312) (width 0.17) (layer "F.Cu") (net 47))
  (segment (start 100.942066 96.573848) (end 100.917665 96.504112) (width 0.17) (layer "F.Cu") (net 47))
  (segment (start 100.3975 98.061098) (end 100.3975 97.3025) (width 0.17) (layer "F.Cu") (net 47))
  (segment (start 100.452669 97.247331) (end 100.620403 97.247331) (width 0.17) (layer "F.Cu") (net 47))
  (via (at 98.637907 98.474963) (size 0.6) (drill 0.25) (layers "F.Cu" "B.Cu") (net 47))
  (segment (start 98.223711 101.04094) (end 98.223711 99.967691) (width 0.17) (layer "B.Cu") (net 47))
  (segment (start 98.171211 101.09344) (end 98.223711 101.04094) (width 0.17) (layer "B.Cu") (net 47))
  (segment (start 99.072052 98.605051) (end 98.941964 98.474963) (width 0.17) (layer "B.Cu") (net 47))
  (segment (start 98.223711 99.967691) (end 99.072052 99.11935) (width 0.17) (layer "B.Cu") (net 47))
  (segment (start 99.072052 99.11935) (end 99.072052 98.605051) (width 0.17) (layer "B.Cu") (net 47))
  (segment (start 98.941964 98.474963) (end 98.637907 98.474963) (width 0.17) (layer "B.Cu") (net 47))
  (segment (start 99.171009 94.142732) (end 99.082131 94.198578) (width 0.17) (layer "F.Cu") (net 48))
  (segment (start 98.14381 94.49256) (end 98.158786 94.535361) (width 0.17) (layer "F.Cu") (net 48))
  (segment (start 99.245232 94.068509) (end 99.171009 94.142732) (width 0.17) (layer "F.Cu") (net 48))
  (segment (start 99.335747 95.014445) (end 99.3475 95.118752) (width 0.17) (layer "F.Cu") (net 48))
  (segment (start 98.138733 94.4475) (end 98.14381 94.49256) (width 0.17) (layer "F.Cu") (net 48))
  (segment (start 98.182912 94.321243) (end 98.158786 94.359638) (width 0.17) (layer "F.Cu") (net 48))
  (segment (start 99.335747 93.880554) (end 99.301078 93.979631) (width 0.17) (layer "F.Cu") (net 48))
  (segment (start 98.14381 94.402439) (end 98.138733 94.4475) (width 0.17) (layer "F.Cu") (net 48))
  (segment (start 98.341233 94.245) (end 98.296172 94.250077) (width 0.17) (layer "F.Cu") (net 48))
  (segment (start 102.75 90.185) (end 102.6475 90.2875) (width 0.17) (layer "F.Cu") (net 48))
  (segment (start 98.158786 94.535361) (end 98.182912 94.573756) (width 0.17) (layer "F.Cu") (net 48))
  (segment (start 98.296172 94.644922) (end 98.341233 94.65) (width 0.17) (layer "F.Cu") (net 48))
  (segment (start 98.253371 94.629946) (end 98.296172 94.644922) (width 0.17) (layer "F.Cu") (net 48))
  (segment (start 98.158786 94.359638) (end 98.14381 94.402439) (width 0.17) (layer "F.Cu") (net 48))
  (segment (start 98.214976 94.60582) (end 98.253371 94.629946) (width 0.17) (layer "F.Cu") (net 48))
  (segment (start 99.301078 93.979631) (end 99.245232 94.068509) (width 0.17) (layer "F.Cu") (net 48))
  (segment (start 99.301078 94.915368) (end 99.335747 95.014445) (width 0.17) (layer "F.Cu") (net 48))
  (segment (start 98.983054 94.661752) (end 99.082131 94.696421) (width 0.17) (layer "F.Cu") (net 48))
  (segment (start 98.878747 94.245) (end 98.341233 94.245) (width 0.17) (layer "F.Cu") (net 48))
  (segment (start 98.983054 94.233247) (end 98.878747 94.245) (width 0.17) (layer "F.Cu") (net 48))
  (segment (start 98.296172 94.250077) (end 98.253371 94.265053) (width 0.17) (layer "F.Cu") (net 48))
  (segment (start 100.861098 92.9475) (end 99.861098 92.9475) (width 0.17) (layer "F.Cu") (net 48))
  (segment (start 99.3475 93.776247) (end 99.335747 93.880554) (width 0.17) (layer "F.Cu") (net 48))
  (segment (start 99.861098 92.9475) (end 99.3475 93.461098) (width 0.17) (layer "F.Cu") (net 48))
  (segment (start 98.214976 94.289179) (end 98.182912 94.321243) (width 0.17) (layer "F.Cu") (net 48))
  (segment (start 99.3475 95.118752) (end 99.3475 96.461097) (width 0.17) (layer "F.Cu") (net 48))
  (segment (start 99.082131 94.696421) (end 99.171009 94.752267) (width 0.17) (layer "F.Cu") (net 48))
  (segment (start 99.3475 96.461097) (end 98.356327 97.45227) (width 0.17) (layer "F.Cu") (net 48))
  (segment (start 98.253371 94.265053) (end 98.214976 94.289179) (width 0.17) (layer "F.Cu") (net 48))
  (segment (start 102.6475 90.2875) (end 102.6475 91.161098) (width 0.17) (layer "F.Cu") (net 48))
  (segment (start 99.082131 94.198578) (end 98.983054 94.233247) (width 0.17) (layer "F.Cu") (net 48))
  (segment (start 98.182912 94.573756) (end 98.214976 94.60582) (width 0.17) (layer "F.Cu") (net 48))
  (segment (start 98.356327 97.45227) (end 98.356327 97.756327) (width 0.17) (layer "F.Cu") (net 48))
  (segment (start 99.3475 93.461098) (end 99.3475 93.776247) (width 0.17) (layer "F.Cu") (net 48))
  (segment (start 98.341233 94.65) (end 98.878747 94.65) (width 0.17) (layer "F.Cu") (net 48))
  (segment (start 102.6475 91.161098) (end 100.861098 92.9475) (width 0.17) (layer "F.Cu") (net 48))
  (segment (start 99.245232 94.82649) (end 99.301078 94.915368) (width 0.17) (layer "F.Cu") (net 48))
  (segment (start 98.878747 94.65) (end 98.983054 94.661752) (width 0.17) (layer "F.Cu") (net 48))
  (segment (start 99.171009 94.752267) (end 99.245232 94.82649) (width 0.17) (layer "F.Cu") (net 48))
  (via (at 98.356327 97.756327) (size 0.6) (drill 0.25) (layers "F.Cu" "B.Cu") (net 48))
  (segment (start 98.05227 97.756327) (end 98.356327 97.756327) (width 0.17) (layer "B.Cu") (net 48))
  (segment (start 97.718711 98.089886) (end 98.05227 97.756327) (width 0.17) (layer "B.Cu") (net 48))
  (segment (start 97.771211 101.09344) (end 97.718711 101.04094) (width 0.17) (layer "B.Cu") (net 48))
  (segment (start 97.718711 101.04094) (end 97.718711 98.089886) (width 0.17) (layer "B.Cu") (net 48))
  (segment (start 100.738902 92.6525) (end 99.738902 92.6525) (width 0.17) (layer "F.Cu") (net 49))
  (segment (start 99.00832 95.021243) (end 99.032446 95.059638) (width 0.17) (layer "F.Cu") (net 49))
  (segment (start 98.020223 94.052267) (end 97.946 94.12649) (width 0.17) (layer "F.Cu") (net 49))
  (segment (start 97.890154 94.679631) (end 97.946 94.768509) (width 0.17) (layer "F.Cu") (net 49))
  (segment (start 99.0525 96.338901) (end 98.14773 97.243673) (width 0.17) (layer "F.Cu") (net 49))
  (segment (start 102.3525 91.038902) (end 100.738902 92.6525) (width 0.17) (layer "F.Cu") (net 49))
  (segment (start 98.976256 94.989179) (end 99.00832 95.021243) (width 0.17) (layer "F.Cu") (net 49))
  (segment (start 97.843733 94.418752) (end 97.843733 94.476247) (width 0.17) (layer "F.Cu") (net 49))
  (segment (start 97.855485 94.580554) (end 97.890154 94.679631) (width 0.17) (layer "F.Cu") (net 49))
  (segment (start 97.946 94.768509) (end 98.020223 94.842732) (width 0.17) (layer "F.Cu") (net 49))
  (segment (start 97.946 94.12649) (end 97.890154 94.215368) (width 0.17) (layer "F.Cu") (net 49))
  (segment (start 97.855485 94.314445) (end 97.843733 94.418752) (width 0.17) (layer "F.Cu") (net 49))
  (segment (start 98.312485 94.945) (end 98.85 94.945) (width 0.17) (layer "F.Cu") (net 49))
  (segment (start 98.85 94.945) (end 98.89506 94.950077) (width 0.17) (layer "F.Cu") (net 49))
  (segment (start 98.109101 93.996421) (end 98.020223 94.052267) (width 0.17) (layer "F.Cu") (net 49))
  (segment (start 98.312485 93.95) (end 98.208178 93.961752) (width 0.17) (layer "F.Cu") (net 49))
  (segment (start 99.0525 95.1475) (end 99.0525 96.338901) (width 0.17) (layer "F.Cu") (net 49))
  (segment (start 99.738902 92.6525) (end 99.0525 93.338902) (width 0.17) (layer "F.Cu") (net 49))
  (segment (start 98.89506 93.944922) (end 98.85 93.95) (width 0.17) (layer "F.Cu") (net 49))
  (segment (start 98.208178 93.961752) (end 98.109101 93.996421) (width 0.17) (layer "F.Cu") (net 49))
  (segment (start 99.047422 95.102439) (end 99.0525 95.1475) (width 0.17) (layer "F.Cu") (net 49))
  (segment (start 99.032446 93.835361) (end 99.00832 93.873756) (width 0.17) (layer "F.Cu") (net 49))
  (segment (start 99.032446 95.059638) (end 99.047422 95.102439) (width 0.17) (layer "F.Cu") (net 49))
  (segment (start 98.14773 97.243673) (end 97.843673 97.243673) (width 0.17) (layer "F.Cu") (net 49))
  (segment (start 98.109101 94.898578) (end 98.208178 94.933247) (width 0.17) (layer "F.Cu") (net 49))
  (segment (start 98.89506 94.950077) (end 98.937861 94.965053) (width 0.17) (layer "F.Cu") (net 49))
  (segment (start 102.25 90.185) (end 102.3525 90.2875) (width 0.17) (layer "F.Cu") (net 49))
  (segment (start 97.890154 94.215368) (end 97.855485 94.314445) (width 0.17) (layer "F.Cu") (net 49))
  (segment (start 98.85 93.95) (end 98.312485 93.95) (width 0.17) (layer "F.Cu") (net 49))
  (segment (start 98.020223 94.842732) (end 98.109101 94.898578) (width 0.17) (layer "F.Cu") (net 49))
  (segment (start 98.937861 93.929946) (end 98.89506 93.944922) (width 0.17) (layer "F.Cu") (net 49))
  (segment (start 97.843733 94.476247) (end 97.855485 94.580554) (width 0.17) (layer "F.Cu") (net 49))
  (segment (start 99.0525 93.338902) (end 99.0525 93.7475) (width 0.17) (layer "F.Cu") (net 49))
  (segment (start 98.937861 94.965053) (end 98.976256 94.989179) (width 0.17) (layer "F.Cu") (net 49))
  (segment (start 99.047422 93.79256) (end 99.032446 93.835361) (width 0.17) (layer "F.Cu") (net 49))
  (segment (start 102.3525 90.2875) (end 102.3525 91.038902) (width 0.17) (layer "F.Cu") (net 49))
  (segment (start 99.00832 93.873756) (end 98.976256 93.90582) (width 0.17) (layer "F.Cu") (net 49))
  (segment (start 98.976256 93.90582) (end 98.937861 93.929946) (width 0.17) (layer "F.Cu") (net 49))
  (segment (start 99.0525 93.7475) (end 99.047422 93.79256) (width 0.17) (layer "F.Cu") (net 49))
  (segment (start 98.208178 94.933247) (end 98.312485 94.945) (width 0.17) (layer "F.Cu") (net 49))
  (via (at 97.843673 97.243673) (size 0.6) (drill 0.25) (layers "F.Cu" "B.Cu") (net 49))
  (segment (start 97.843673 97.54773) (end 97.843673 97.243673) (width 0.17) (layer "B.Cu") (net 49))
  (segment (start 97.423711 97.967692) (end 97.843673 97.54773) (width 0.17) (layer "B.Cu") (net 49))
  (segment (start 97.423711 101.04094) (end 97.423711 97.967692) (width 0.17) (layer "B.Cu") (net 49))
  (segment (start 97.371211 101.09344) (end 97.423711 101.04094) (width 0.17) (layer "B.Cu") (net 49))
  (segment (start 139.64822 119.324997) (end 139.57955 119.256327) (width 0.125) (layer "F.Cu") (net 50))
  (segment (start 139.57955 119.256327) (end 139.243673 119.256327) (width 0.125) (layer "F.Cu") (net 50))
  (segment (start 139.57322 120.749999) (end 139.64822 120.674999) (width 0.125) (layer "F.Cu") (net 50))
  (segment (start 139.64822 120.674999) (end 139.64822 119.324997) (width 0.125) (layer "F.Cu") (net 50))
  (segment (start 139.57322 121.5) (end 139.57322 120.749999) (width 0.125) (layer "F.Cu") (net 50))
  (segment (start 122.875 117.224853) (end 122.874999 117.202853) (width 0.125) (layer "F.Cu") (net 50))
  (segment (start 122.75 117.349853) (end 122.875 117.224853) (width 0.125) (layer "F.Cu") (net 50))
  (segment (start 122.874999 117.202853) (end 122.637499 116.965353) (width 0.125) (layer "F.Cu") (net 50))
  (segment (start 122.75 118.550004) (end 122.75 117.349853) (width 0.125) (layer "F.Cu") (net 50))
  (via (at 139.243673 119.256327) (size 0.6) (drill 0.25) (layers "F.Cu" "B.Cu") (net 50))
  (via (at 122.637499 116.965353) (size 0.6) (drill 0.25) (layers "F.Cu" "B.Cu") (net 50))
  (segment (start 125.858098 119.067776) (end 125.917775 119.008099) (width 0.125) (layer "B.Cu") (net 50))
  (segment (start 127.482224 119.008099) (end 127.541901 119.067776) (width 0.125) (layer "B.Cu") (net 50))
  (segment (start 136.067274 118.481477) (end 136.085145 118.509918) (width 0.125) (layer "B.Cu") (net 50))
  (segment (start 124.067274 118.041307) (end 124.085145 118.069748) (width 0.125) (layer "B.Cu") (net 50))
  (segment (start 128.232725 118.041307) (end 128.256476 118.017556) (width 0.125) (layer "B.Cu") (net 50))
  (segment (start 125.209449 118.856979) (end 125.237323 118.936639) (width 0.125) (layer "B.Cu") (net 50))
  (segment (start 126.441901 119.067776) (end 126.513361 119.112677) (width 0.125) (layer "B.Cu") (net 50))
  (segment (start 132.5 118.773114) (end 132.5 118.575) (width 0.125) (layer "B.Cu") (net 50))
  (segment (start 128.876886 119.15) (end 129.923113 119.15) (width 0.125) (layer "B.Cu") (net 50))
  (segment (start 127.25 117.98483) (end 127.283378 117.988591) (width 0.125) (layer "B.Cu") (net 50))
  (segment (start 132.49055 118.856979) (end 132.5 118.773114) (width 0.125) (layer "B.Cu") (net 50))
  (segment (start 133.306978 119.140551) (end 133.386638 119.112677) (width 0.125) (layer "B.Cu") (net 50))
  (segment (start 132.882224 119.008099) (end 132.941901 119.067776) (width 0.125) (layer "B.Cu") (net 50))
  (segment (start 128.162676 118.936639) (end 128.19055 118.856979) (width 0.125) (layer "B.Cu") (net 50))
  (segment (start 131.782224 119.008099) (end 131.841901 119.067776) (width 0.125) (layer "B.Cu") (net 50))
  (segment (start 125.99055 118.856979) (end 126 118.773114) (width 0.125) (layer "B.Cu") (net 50))
  (segment (start 137.526778 119.15) (end 138.051778 118.625) (width 0.125) (layer "B.Cu") (net 50))
  (segment (start 125.185145 118.069748) (end 125.196239 118.101452) (width 0.125) (layer "B.Cu") (net 50))
  (segment (start 124.686638 119.112677) (end 124.758098 119.067776) (width 0.125) (layer "B.Cu") (net 50))
  (segment (start 131.696239 118.541622) (end 131.7 118.575) (width 0.125) (layer "B.Cu") (net 50))
  (segment (start 135.037323 118.936639) (end 135.082224 119.008099) (width 0.125) (layer "B.Cu") (net 50))
  (segment (start 128.467274 118.041307) (end 128.485145 118.069748) (width 0.125) (layer "B.Cu") (net 50))
  (segment (start 125.706978 119.140551) (end 125.786638 119.112677) (width 0.125) (layer "B.Cu") (net 50))
  (segment (start 123.916621 117.988591) (end 123.95 117.98483) (width 0.125) (layer "B.Cu") (net 50))
  (segment (start 131.615082 118.439855) (end 131.643523 118.457726) (width 0.125) (layer "B.Cu") (net 50))
  (segment (start 131.55 118.425) (end 131.583378 118.428761) (width 0.125) (layer "B.Cu") (net 50))
  (segment (start 130.45 118.425) (end 130.483378 118.428761) (width 0.125) (layer "B.Cu") (net 50))
  (segment (start 124.137323 118.936639) (end 124.182224 119.008099) (width 0.125) (layer "B.Cu") (net 50))
  (segment (start 126.958098 119.067776) (end 127.017775 119.008099) (width 0.125) (layer "B.Cu") (net 50))
  (segment (start 134.985145 118.509918) (end 134.996239 118.541622) (width 0.125) (layer "B.Cu") (net 50))
  (segment (start 127.776886 119.15) (end 127.823113 119.15) (width 0.125) (layer "B.Cu") (net 50))
  (segment (start 134.7 118.575) (end 134.70376 118.541622) (width 0.125) (layer "B.Cu") (net 50))
  (segment (start 126.056476 118.017556) (end 126.084917 117.999685) (width 0.125) (layer "B.Cu") (net 50))
  (segment (start 126.243523 118.017556) (end 126.267274 118.041307) (width 0.125) (layer "B.Cu") (net 50))
  (segment (start 126.285145 118.069748) (end 126.296239 118.101452) (width 0.125) (layer "B.Cu") (net 50))
  (segment (start 134.967274 118.481477) (end 134.985145 118.509918) (width 0.125) (layer "B.Cu") (net 50))
  (segment (start 133.176886 119.15) (end 133.223113 119.15) (width 0.125) (layer "B.Cu") (net 50))
  (segment (start 124.241901 119.067776) (end 124.313361 119.112677) (width 0.125) (layer "B.Cu") (net 50))
  (segment (start 133.843523 118.457726) (end 133.867274 118.481477) (width 0.125) (layer "B.Cu") (net 50))
  (segment (start 128.214854 118.069748) (end 128.232725 118.041307) (width 0.125) (layer "B.Cu") (net 50))
  (segment (start 130.356476 118.457726) (end 130.384917 118.439855) (width 0.125) (layer "B.Cu") (net 50))
  (segment (start 124.096239 118.101452) (end 124.1 118.13483) (width 0.125) (layer "B.Cu") (net 50))
  (segment (start 136.1 118.575) (end 136.1 118.773114) (width 0.125) (layer "B.Cu") (net 50))
  (segment (start 126.3 118.13483) (end 126.3 118.773114) (width 0.125) (layer "B.Cu") (net 50))
  (segment (start 138.051778 118.625) (end 138.948223 118.625) (width 0.125) (layer "B.Cu") (net 50))
  (segment (start 128.5 118.773114) (end 128.509449 118.856979) (width 0.125) (layer "B.Cu") (net 50))
  (segment (start 124.862676 118.936639) (end 124.89055 118.856979) (width 0.125) (layer "B.Cu") (net 50))
  (segment (start 133.562676 118.936639) (end 133.59055 118.856979) (width 0.125) (layer "B.Cu") (net 50))
  (segment (start 124.182224 119.008099) (end 124.241901 119.067776) (width 0.125) (layer "B.Cu") (net 50))
  (segment (start 132.785145 118.509918) (end 132.796239 118.541622) (width 0.125) (layer "B.Cu") (net 50))
  (segment (start 131.7 118.575) (end 131.7 118.773114) (width 0.125) (layer "B.Cu") (net 50))
  (segment (start 130.3 118.575) (end 130.30376 118.541622) (width 0.125) (layer "B.Cu") (net 50))
  (segment (start 133.885145 118.509918) (end 133.896239 118.541622) (width 0.125) (layer "B.Cu") (net 50))
  (segment (start 124.9 118.773114) (end 124.9 118.13483) (width 0.125) (layer "B.Cu") (net 50))
  (segment (start 127.343523 118.017556) (end 127.367274 118.041307) (width 0.125) (layer "B.Cu") (net 50))
  (segment (start 130.30376 118.541622) (end 130.314854 118.509918) (width 0.125) (layer "B.Cu") (net 50))
  (segment (start 124.758098 119.067776) (end 124.817775 119.008099) (width 0.125) (layer "B.Cu") (net 50))
  (segment (start 132.809449 118.856979) (end 132.837323 118.936639) (width 0.125) (layer "B.Cu") (net 50))
  (segment (start 126.116621 117.988591) (end 126.15 117.98483) (width 0.125) (layer "B.Cu") (net 50))
  (segment (start 135.658098 119.067776) (end 135.717775 119.008099) (width 0.125) (layer "B.Cu") (net 50))
  (segment (start 124.043523 118.017556) (end 124.067274 118.041307) (width 0.125) (layer "B.Cu") (net 50))
  (segment (start 133.909449 118.856979) (end 133.937323 118.936639) (width 0.125) (layer "B.Cu") (net 50))
  (segment (start 136.109449 118.856979) (end 136.137323 118.936639) (width 0.125) (layer "B.Cu") (net 50))
  (segment (start 123.717775 119.008099) (end 123.762676 118.936639) (width 0.125) (layer "B.Cu") (net 50))
  (segment (start 135 118.575) (end 135 118.773114) (width 0.125) (layer "B.Cu") (net 50))
  (segment (start 127.906978 119.140551) (end 127.986638 119.112677) (width 0.125) (layer "B.Cu") (net 50))
  (segment (start 136.182224 119.008099) (end 136.241901 119.067776) (width 0.125) (layer "B.Cu") (net 50))
  (segment (start 126.215082 117.999685) (end 126.243523 118.017556) (width 0.125) (layer "B.Cu") (net 50))
  (segment (start 124.956476 118.017556) (end 124.984917 117.999685) (width 0.125) (layer "B.Cu") (net 50))
  (segment (start 124.476886 119.15) (end 124.523113 119.15) (width 0.125) (layer "B.Cu") (net 50))
  (segment (start 126.337323 118.936639) (end 126.382224 119.008099) (width 0.125) (layer "B.Cu") (net 50))
  (segment (start 135.884917 118.439855) (end 135.916621 118.428761) (width 0.125) (layer "B.Cu") (net 50))
  (segment (start 131.456476 118.457726) (end 131.484917 118.439855) (width 0.125) (layer "B.Cu") (net 50))
  (segment (start 134.193021 119.140551) (end 134.276886 119.15) (width 0.125) (layer "B.Cu") (net 50))
  (segment (start 126.084917 117.999685) (end 126.116621 117.988591) (width 0.125) (layer "B.Cu") (net 50))
  (segment (start 131.709449 118.856979) (end 131.737323 118.936639) (width 0.125) (layer "B.Cu") (net 50))
  (segment (start 135.717775 119.008099) (end 135.762676 118.936639) (width 0.125) (layer "B.Cu") (net 50))
  (segment (start 136.043523 118.457726) (end 136.067274 118.481477) (width 0.125) (layer "B.Cu") (net 50))
  (segment (start 126.309449 118.856979) (end 126.337323 118.936639) (width 0.125) (layer "B.Cu") (net 50))
  (segment (start 133.867274 118.481477) (end 133.885145 118.509918) (width 0.125) (layer "B.Cu") (net 50))
  (segment (start 122.637499 116.965353) (end 122.874999 117.202853) (width 0.125) (layer "B.Cu") (net 50))
  (segment (start 126.296239 118.101452) (end 126.3 118.13483) (width 0.125) (layer "B.Cu") (net 50))
  (segment (start 130.384917 118.439855) (end 130.416621 118.428761) (width 0.125) (layer "B.Cu") (net 50))
  (segment (start 127.385145 118.069748) (end 127.396239 118.101452) (width 0.125) (layer "B.Cu") (net 50))
  (segment (start 134.69055 118.856979) (end 134.7 118.773114) (width 0.125) (layer "B.Cu") (net 50))
  (segment (start 124.89055 118.856979) (end 124.9 118.773114) (width 0.125) (layer "B.Cu") (net 50))
  (segment (start 128.383378 117.988591) (end 128.415082 117.999685) (width 0.125) (layer "B.Cu") (net 50))
  (segment (start 130.637323 118.936639) (end 130.682224 119.008099) (width 0.125) (layer "B.Cu") (net 50))
  (segment (start 126.3 118.773114) (end 126.309449 118.856979) (width 0.125) (layer "B.Cu") (net 50))
  (segment (start 134.041901 119.067776) (end 134.113361 119.112677) (width 0.125) (layer "B.Cu") (net 50))
  (segment (start 133.815082 118.439855) (end 133.843523 118.457726) (width 0.125) (layer "B.Cu") (net 50))
  (segment (start 124.984917 117.999685) (end 125.016621 117.988591) (width 0.125) (layer "B.Cu") (net 50))
  (segment (start 128.485145 118.069748) (end 128.496239 118.101452) (width 0.125) (layer "B.Cu") (net 50))
  (segment (start 126.267274 118.041307) (end 126.285145 118.069748) (width 0.125) (layer "B.Cu") (net 50))
  (segment (start 133.684917 118.439855) (end 133.716621 118.428761) (width 0.125) (layer "B.Cu") (net 50))
  (segment (start 128.582224 119.008099) (end 128.641901 119.067776) (width 0.125) (layer "B.Cu") (net 50))
  (segment (start 132.206978 119.140551) (end 132.286638 119.112677) (width 0.125) (layer "B.Cu") (net 50))
  (segment (start 123.983378 117.988591) (end 124.015082 117.999685) (width 0.125) (layer "B.Cu") (net 50))
  (segment (start 122.874999 117.202853) (end 122.874999 118.89482) (width 0.125) (layer "B.Cu") (net 50))
  (segment (start 132.358098 119.067776) (end 132.417775 119.008099) (width 0.125) (layer "B.Cu") (net 50))
  (segment (start 124.015082 117.999685) (end 124.043523 118.017556) (width 0.125) (layer "B.Cu") (net 50))
  (segment (start 131.643523 118.457726) (end 131.667274 118.481477) (width 0.125) (layer "B.Cu") (net 50))
  (segment (start 135.856476 118.457726) (end 135.884917 118.439855) (width 0.125) (layer "B.Cu") (net 50))
  (segment (start 127.409449 118.856979) (end 127.437323 118.936639) (width 0.125) (layer "B.Cu") (net 50))
  (segment (start 131.516621 118.428761) (end 131.55 118.425) (width 0.125) (layer "B.Cu") (net 50))
  (segment (start 128.496239 118.101452) (end 128.5 118.13483) (width 0.125) (layer "B.Cu") (net 50))
  (segment (start 122.874999 118.89482) (end 123.130179 119.15) (width 0.125) (layer "B.Cu") (net 50))
  (segment (start 124.085145 118.069748) (end 124.096239 118.101452) (width 0.125) (layer "B.Cu") (net 50))
  (segment (start 135.213361 119.112677) (end 135.293021 119.140551) (width 0.125) (layer "B.Cu") (net 50))
  (segment (start 133.9 118.773114) (end 133.909449 118.856979) (width 0.125) (layer "B.Cu") (net 50))
  (segment (start 126 118.773114) (end 126 118.13483) (width 0.125) (layer "B.Cu") (net 50))
  (segment (start 134.113361 119.112677) (end 134.193021 119.140551) (width 0.125) (layer "B.Cu") (net 50))
  (segment (start 132.417775 119.008099) (end 132.462676 118.936639) (width 0.125) (layer "B.Cu") (net 50))
  (segment (start 135.80376 118.541622) (end 135.814854 118.509918) (width 0.125) (layer "B.Cu") (net 50))
  (segment (start 134.70376 118.541622) (end 134.714854 118.509918) (width 0.125) (layer "B.Cu") (net 50))
  (segment (start 134.816621 118.428761) (end 134.85 118.425) (width 0.125) (layer "B.Cu") (net 50))
  (segment (start 131.317775 119.008099) (end 131.362676 118.936639) (width 0.125) (layer "B.Cu") (net 50))
  (segment (start 130.567274 118.481477) (end 130.585145 118.509918) (width 0.125) (layer "B.Cu") (net 50))
  (segment (start 133.093021 119.140551) (end 133.176886 119.15) (width 0.125) (layer "B.Cu") (net 50))
  (segment (start 131.7 118.773114) (end 131.709449 118.856979) (width 0.125) (layer "B.Cu") (net 50))
  (segment (start 127.693021 119.140551) (end 127.776886 119.15) (width 0.125) (layer "B.Cu") (net 50))
  (segment (start 125.237323 118.936639) (end 125.282224 119.008099) (width 0.125) (layer "B.Cu") (net 50))
  (segment (start 136.085145 118.509918) (end 136.096239 118.541622) (width 0.125) (layer "B.Cu") (net 50))
  (segment (start 125.493021 119.140551) (end 125.576886 119.15) (width 0.125) (layer "B.Cu") (net 50))
  (segment (start 125.917775 119.008099) (end 125.962676 118.936639) (width 0.125) (layer "B.Cu") (net 50))
  (segment (start 131.186638 119.112677) (end 131.258098 119.067776) (width 0.125) (layer "B.Cu") (net 50))
  (segment (start 125.962676 118.936639) (end 125.99055 118.856979) (width 0.125) (layer "B.Cu") (net 50))
  (segment (start 125.2 118.773114) (end 125.209449 118.856979) (width 0.125) (layer "B.Cu") (net 50))
  (segment (start 130.217775 119.008099) (end 130.262676 118.936639) (width 0.125) (layer "B.Cu") (net 50))
  (segment (start 132.286638 119.112677) (end 132.358098 119.067776) (width 0.125) (layer "B.Cu") (net 50))
  (segment (start 124.9 118.13483) (end 124.90376 118.101452) (width 0.125) (layer "B.Cu") (net 50))
  (segment (start 130.515082 118.439855) (end 130.543523 118.457726) (width 0.125) (layer "B.Cu") (net 50))
  (segment (start 124.523113 119.15) (end 124.606978 119.140551) (width 0.125) (layer "B.Cu") (net 50))
  (segment (start 132.837323 118.936639) (end 132.882224 119.008099) (width 0.125) (layer "B.Cu") (net 50))
  (segment (start 138.948223 118.625) (end 139.243673 118.92045) (width 0.125) (layer "B.Cu") (net 50))
  (segment (start 123.130179 119.15) (end 123.423113 119.15) (width 0.125) (layer "B.Cu") (net 50))
  (segment (start 134.915082 118.439855) (end 134.943523 118.457726) (width 0.125) (layer "B.Cu") (net 50))
  (segment (start 132.462676 118.936639) (end 132.49055 118.856979) (width 0.125) (layer "B.Cu") (net 50))
  (segment (start 131.40376 118.541622) (end 131.414854 118.509918) (width 0.125) (layer "B.Cu") (net 50))
  (segment (start 133.896239 118.541622) (end 133.9 118.575) (width 0.125) (layer "B.Cu") (net 50))
  (segment (start 135 118.773114) (end 135.009449 118.856979) (width 0.125) (layer "B.Cu") (net 50))
  (segment (start 124.606978 119.140551) (end 124.686638 119.112677) (width 0.125) (layer "B.Cu") (net 50))
  (segment (start 124.1 118.773114) (end 124.109449 118.856979) (width 0.125) (layer "B.Cu") (net 50))
  (segment (start 127.062676 118.936639) (end 127.09055 118.856979) (width 0.125) (layer "B.Cu") (net 50))
  (segment (start 134.558098 119.067776) (end 134.617775 119.008099) (width 0.125) (layer "B.Cu") (net 50))
  (segment (start 132.743523 118.457726) (end 132.767274 118.481477) (width 0.125) (layer "B.Cu") (net 50))
  (segment (start 127.017775 119.008099) (end 127.062676 118.936639) (width 0.125) (layer "B.Cu") (net 50))
  (segment (start 123.423113 119.15) (end 123.506978 119.140551) (width 0.125) (layer "B.Cu") (net 50))
  (segment (start 128.316621 117.988591) (end 128.35 117.98483) (width 0.125) (layer "B.Cu") (net 50))
  (segment (start 127.613361 119.112677) (end 127.693021 119.140551) (width 0.125) (layer "B.Cu") (net 50))
  (segment (start 131.4 118.773114) (end 131.4 118.575) (width 0.125) (layer "B.Cu") (net 50))
  (segment (start 125.143523 118.017556) (end 125.167274 118.041307) (width 0.125) (layer "B.Cu") (net 50))
  (segment (start 128.2 118.13483) (end 128.20376 118.101452) (width 0.125) (layer "B.Cu") (net 50))
  (segment (start 130.585145 118.509918) (end 130.596239 118.541622) (width 0.125) (layer "B.Cu") (net 50))
  (segment (start 135.082224 119.008099) (end 135.141901 119.067776) (width 0.125) (layer "B.Cu") (net 50))
  (segment (start 131.39055 118.856979) (end 131.4 118.773114) (width 0.125) (layer "B.Cu") (net 50))
  (segment (start 133.75 118.425) (end 133.783378 118.428761) (width 0.125) (layer "B.Cu") (net 50))
  (segment (start 131.737323 118.936639) (end 131.782224 119.008099) (width 0.125) (layer "B.Cu") (net 50))
  (segment (start 132.616621 118.428761) (end 132.65 118.425) (width 0.125) (layer "B.Cu") (net 50))
  (segment (start 133.937323 118.936639) (end 133.982224 119.008099) (width 0.125) (layer "B.Cu") (net 50))
  (segment (start 123.8 118.13483) (end 123.80376 118.101452) (width 0.125) (layer "B.Cu") (net 50))
  (segment (start 127.986638 119.112677) (end 128.058098 119.067776) (width 0.125) (layer "B.Cu") (net 50))
  (segment (start 134.617775 119.008099) (end 134.662676 118.936639) (width 0.125) (layer "B.Cu") (net 50))
  (segment (start 128.284917 117.999685) (end 128.316621 117.988591) (width 0.125) (layer "B.Cu") (net 50))
  (segment (start 128.793021 119.140551) (end 128.876886 119.15) (width 0.125) (layer "B.Cu") (net 50))
  (segment (start 132.8 118.773114) (end 132.809449 118.856979) (width 0.125) (layer "B.Cu") (net 50))
  (segment (start 133.614854 118.509918) (end 133.632725 118.481477) (width 0.125) (layer "B.Cu") (net 50))
  (segment (start 135.95 118.425) (end 135.983378 118.428761) (width 0.125) (layer "B.Cu") (net 50))
  (segment (start 133.632725 118.481477) (end 133.656476 118.457726) (width 0.125) (layer "B.Cu") (net 50))
  (segment (start 132.715082 118.439855) (end 132.743523 118.457726) (width 0.125) (layer "B.Cu") (net 50))
  (segment (start 131.362676 118.936639) (end 131.39055 118.856979) (width 0.125) (layer "B.Cu") (net 50))
  (segment (start 132.683378 118.428761) (end 132.715082 118.439855) (width 0.125) (layer "B.Cu") (net 50))
  (segment (start 125.623113 119.15) (end 125.706978 119.140551) (width 0.125) (layer "B.Cu") (net 50))
  (segment (start 125.786638 119.112677) (end 125.858098 119.067776) (width 0.125) (layer "B.Cu") (net 50))
  (segment (start 123.80376 118.101452) (end 123.814854 118.069748) (width 0.125) (layer "B.Cu") (net 50))
  (segment (start 132.941901 119.067776) (end 133.013361 119.112677) (width 0.125) (layer "B.Cu") (net 50))
  (segment (start 123.832725 118.041307) (end 123.856476 118.017556) (width 0.125) (layer "B.Cu") (net 50))
  (segment (start 124.313361 119.112677) (end 124.393021 119.140551) (width 0.125) (layer "B.Cu") (net 50))
  (segment (start 124.817775 119.008099) (end 124.862676 118.936639) (width 0.125) (layer "B.Cu") (net 50))
  (segment (start 133.9 118.575) (end 133.9 118.773114) (width 0.125) (layer "B.Cu") (net 50))
  (segment (start 127.1 118.773114) (end 127.1 118.13483) (width 0.125) (layer "B.Cu") (net 50))
  (segment (start 133.386638 119.112677) (end 133.458098 119.067776) (width 0.125) (layer "B.Cu") (net 50))
  (segment (start 123.506978 119.140551) (end 123.586638 119.112677) (width 0.125) (layer "B.Cu") (net 50))
  (segment (start 125.576886 119.15) (end 125.623113 119.15) (width 0.125) (layer "B.Cu") (net 50))
  (segment (start 128.713361 119.112677) (end 128.793021 119.140551) (width 0.125) (layer "B.Cu") (net 50))
  (segment (start 131.667274 118.481477) (end 131.685145 118.509918) (width 0.125) (layer "B.Cu") (net 50))
  (segment (start 128.20376 118.101452) (end 128.214854 118.069748) (width 0.125) (layer "B.Cu") (net 50))
  (segment (start 133.013361 119.112677) (end 133.093021 119.140551) (width 0.125) (layer "B.Cu") (net 50))
  (segment (start 127.823113 119.15) (end 127.906978 119.140551) (width 0.125) (layer "B.Cu") (net 50))
  (segment (start 132.8 118.575) (end 132.8 118.773114) (width 0.125) (layer "B.Cu") (net 50))
  (segment (start 134.996239 118.541622) (end 135 118.575) (width 0.125) (layer "B.Cu") (net 50))
  (segment (start 132.556476 118.457726) (end 132.584917 118.439855) (width 0.125) (layer "B.Cu") (net 50))
  (segment (start 133.60376 118.541622) (end 133.614854 118.509918) (width 0.125) (layer "B.Cu") (net 50))
  (segment (start 123.95 117.98483) (end 123.983378 117.988591) (width 0.125) (layer "B.Cu") (net 50))
  (segment (start 131.583378 118.428761) (end 131.615082 118.439855) (width 0.125) (layer "B.Cu") (net 50))
  (segment (start 127.10376 118.101452) (end 127.114854 118.069748) (width 0.125) (layer "B.Cu") (net 50))
  (segment (start 130.813361 119.112677) (end 130.893021 119.140551) (width 0.125) (layer "B.Cu") (net 50))
  (segment (start 126 118.13483) (end 126.00376 118.101452) (width 0.125) (layer "B.Cu") (net 50))
  (segment (start 134.756476 118.457726) (end 134.784917 118.439855) (width 0.125) (layer "B.Cu") (net 50))
  (segment (start 130.6 118.575) (end 130.6 118.773114) (width 0.125) (layer "B.Cu") (net 50))
  (segment (start 126.032725 118.041307) (end 126.056476 118.017556) (width 0.125) (layer "B.Cu") (net 50))
  (segment (start 133.656476 118.457726) (end 133.684917 118.439855) (width 0.125) (layer "B.Cu") (net 50))
  (segment (start 134.714854 118.509918) (end 134.732725 118.481477) (width 0.125) (layer "B.Cu") (net 50))
  (segment (start 136.015082 118.439855) (end 136.043523 118.457726) (width 0.125) (layer "B.Cu") (net 50))
  (segment (start 123.814854 118.069748) (end 123.832725 118.041307) (width 0.125) (layer "B.Cu") (net 50))
  (segment (start 129.923113 119.15) (end 130.006978 119.140551) (width 0.125) (layer "B.Cu") (net 50))
  (segment (start 127.4 118.773114) (end 127.409449 118.856979) (width 0.125) (layer "B.Cu") (net 50))
  (segment (start 135.141901 119.067776) (end 135.213361 119.112677) (width 0.125) (layer "B.Cu") (net 50))
  (segment (start 134.276886 119.15) (end 134.323113 119.15) (width 0.125) (layer "B.Cu") (net 50))
  (segment (start 135.832725 118.481477) (end 135.856476 118.457726) (width 0.125) (layer "B.Cu") (net 50))
  (segment (start 130.6 118.773114) (end 130.609449 118.856979) (width 0.125) (layer "B.Cu") (net 50))
  (segment (start 135.762676 118.936639) (end 135.79055 118.856979) (width 0.125) (layer "B.Cu") (net 50))
  (segment (start 134.943523 118.457726) (end 134.967274 118.481477) (width 0.125) (layer "B.Cu") (net 50))
  (segment (start 133.517775 119.008099) (end 133.562676 118.936639) (width 0.125) (layer "B.Cu") (net 50))
  (segment (start 135.293021 119.140551) (end 135.376886 119.15) (width 0.125) (layer "B.Cu") (net 50))
  (segment (start 126.15 117.98483) (end 126.183378 117.988591) (width 0.125) (layer "B.Cu") (net 50))
  (segment (start 131.258098 119.067776) (end 131.317775 119.008099) (width 0.125) (layer "B.Cu") (net 50))
  (segment (start 130.483378 118.428761) (end 130.515082 118.439855) (width 0.125) (layer "B.Cu") (net 50))
  (segment (start 131.484917 118.439855) (end 131.516621 118.428761) (width 0.125) (layer "B.Cu") (net 50))
  (segment (start 127.367274 118.041307) (end 127.385145 118.069748) (width 0.125) (layer "B.Cu") (net 50))
  (segment (start 132.767274 118.481477) (end 132.785145 118.509918) (width 0.125) (layer "B.Cu") (net 50))
  (segment (start 123.8 118.773114) (end 123.8 118.13483) (width 0.125) (layer "B.Cu") (net 50))
  (segment (start 132.514854 118.509918) (end 132.532725 118.481477) (width 0.125) (layer "B.Cu") (net 50))
  (segment (start 127.4 118.13483) (end 127.4 118.773114) (width 0.125) (layer "B.Cu") (net 50))
  (segment (start 134.486638 119.112677) (end 134.558098 119.067776) (width 0.125) (layer "B.Cu") (net 50))
  (segment (start 131.4 118.575) (end 131.40376 118.541622) (width 0.125) (layer "B.Cu") (net 50))
  (segment (start 130.682224 119.008099) (end 130.741901 119.067776) (width 0.125) (layer "B.Cu") (net 50))
  (segment (start 130.416621 118.428761) (end 130.45 118.425) (width 0.125) (layer "B.Cu") (net 50))
  (segment (start 135.009449 118.856979) (end 135.037323 118.936639) (width 0.125) (layer "B.Cu") (net 50))
  (segment (start 130.314854 118.509918) (end 130.332725 118.481477) (width 0.125) (layer "B.Cu") (net 50))
  (segment (start 133.716621 118.428761) (end 133.75 118.425) (width 0.125) (layer "B.Cu") (net 50))
  (segment (start 135.8 118.773114) (end 135.8 118.575) (width 0.125) (layer "B.Cu") (net 50))
  (segment (start 130.3 118.773114) (end 130.3 118.575) (width 0.125) (layer "B.Cu") (net 50))
  (segment (start 128.509449 118.856979) (end 128.537323 118.936639) (width 0.125) (layer "B.Cu") (net 50))
  (segment (start 134.85 118.425) (end 134.883378 118.428761) (width 0.125) (layer "B.Cu") (net 50))
  (segment (start 127.541901 119.067776) (end 127.613361 119.112677) (width 0.125) (layer "B.Cu") (net 50))
  (segment (start 136.1 118.773114) (end 136.109449 118.856979) (width 0.125) (layer "B.Cu") (net 50))
  (segment (start 127.1 118.13483) (end 127.10376 118.101452) (width 0.125) (layer "B.Cu") (net 50))
  (segment (start 136.476886 119.15) (end 137.526778 119.15) (width 0.125) (layer "B.Cu") (net 50))
  (segment (start 126.513361 119.112677) (end 126.593021 119.140551) (width 0.125) (layer "B.Cu") (net 50))
  (segment (start 124.914854 118.069748) (end 124.932725 118.041307) (width 0.125) (layer "B.Cu") (net 50))
  (segment (start 126.886638 119.112677) (end 126.958098 119.067776) (width 0.125) (layer "B.Cu") (net 50))
  (segment (start 126.014854 118.069748) (end 126.032725 118.041307) (width 0.125) (layer "B.Cu") (net 50))
  (segment (start 135.506978 119.140551) (end 135.586638 119.112677) (width 0.125) (layer "B.Cu") (net 50))
  (segment (start 134.406978 119.140551) (end 134.486638 119.112677) (width 0.125) (layer "B.Cu") (net 50))
  (segment (start 127.315082 117.999685) (end 127.343523 118.017556) (width 0.125) (layer "B.Cu") (net 50))
  (segment (start 133.59055 118.856979) (end 133.6 118.773114) (width 0.125) (layer "B.Cu") (net 50))
  (segment (start 136.137323 118.936639) (end 136.182224 119.008099) (width 0.125) (layer "B.Cu") (net 50))
  (segment (start 131.913361 119.112677) (end 131.993021 119.140551) (width 0.125) (layer "B.Cu") (net 50))
  (segment (start 126.806978 119.140551) (end 126.886638 119.112677) (width 0.125) (layer "B.Cu") (net 50))
  (segment (start 131.106978 119.140551) (end 131.186638 119.112677) (width 0.125) (layer "B.Cu") (net 50))
  (segment (start 131.023113 119.15) (end 131.106978 119.140551) (width 0.125) (layer "B.Cu") (net 50))
  (segment (start 128.256476 118.017556) (end 128.284917 117.999685) (width 0.125) (layer "B.Cu") (net 50))
  (segment (start 128.35 117.98483) (end 128.383378 117.988591) (width 0.125) (layer "B.Cu") (net 50))
  (segment (start 127.132725 118.041307) (end 127.156476 118.017556) (width 0.125) (layer "B.Cu") (net 50))
  (segment (start 135.586638 119.112677) (end 135.658098 119.067776) (width 0.125) (layer "B.Cu") (net 50))
  (segment (start 128.443523 118.017556) (end 128.467274 118.041307) (width 0.125) (layer "B.Cu") (net 50))
  (segment (start 127.437323 118.936639) (end 127.482224 119.008099) (width 0.125) (layer "B.Cu") (net 50))
  (segment (start 126.676886 119.15) (end 126.723113 119.15) (width 0.125) (layer "B.Cu") (net 50))
  (segment (start 130.006978 119.140551) (end 130.086638 119.112677) (width 0.125) (layer "B.Cu") (net 50))
  (segment (start 125.016621 117.988591) (end 125.05 117.98483) (width 0.125) (layer "B.Cu") (net 50))
  (segment (start 126.723113 119.15) (end 126.806978 119.140551) (width 0.125) (layer "B.Cu") (net 50))
  (segment (start 124.109449 118.856979) (end 124.137323 118.936639) (width 0.125) (layer "B.Cu") (net 50))
  (segment (start 125.083378 117.988591) (end 125.115082 117.999685) (width 0.125) (layer "B.Cu") (net 50))
  (segment (start 131.414854 118.509918) (end 131.432725 118.481477) (width 0.125) (layer "B.Cu") (net 50))
  (segment (start 125.2 118.13483) (end 125.2 118.773114) (width 0.125) (layer "B.Cu") (net 50))
  (segment (start 128.415082 117.999685) (end 128.443523 118.017556) (width 0.125) (layer "B.Cu") (net 50))
  (segment (start 134.662676 118.936639) (end 134.69055 118.856979) (width 0.125) (layer "B.Cu") (net 50))
  (segment (start 139.243673 118.92045) (end 139.243673 119.256327) (width 0.125) (layer "B.Cu") (net 50))
  (segment (start 124.393021 119.140551) (end 124.476886 119.15) (width 0.125) (layer "B.Cu") (net 50))
  (segment (start 130.976886 119.15) (end 131.023113 119.15) (width 0.125) (layer "B.Cu") (net 50))
  (segment (start 133.6 118.773114) (end 133.6 118.575) (width 0.125) (layer "B.Cu") (net 50))
  (segment (start 130.596239 118.541622) (end 130.6 118.575) (width 0.125) (layer "B.Cu") (net 50))
  (segment (start 127.09055 118.856979) (end 127.1 118.773114) (width 0.125) (layer "B.Cu") (net 50))
  (segment (start 132.5 118.575) (end 132.50376 118.541622) (width 0.125) (layer "B.Cu") (net 50))
  (segment (start 132.65 118.425) (end 132.683378 118.428761) (width 0.125) (layer "B.Cu") (net 50))
  (segment (start 123.762676 118.936639) (end 123.79055 118.856979) (width 0.125) (layer "B.Cu") (net 50))
  (segment (start 132.50376 118.541622) (end 132.514854 118.509918) (width 0.125) (layer "B.Cu") (net 50))
  (segment (start 133.6 118.575) (end 133.60376 118.541622) (width 0.125) (layer "B.Cu") (net 50))
  (segment (start 132.584917 118.439855) (end 132.616621 118.428761) (width 0.125) (layer "B.Cu") (net 50))
  (segment (start 130.741901 119.067776) (end 130.813361 119.112677) (width 0.125) (layer "B.Cu") (net 50))
  (segment (start 127.283378 117.988591) (end 127.315082 117.999685) (width 0.125) (layer "B.Cu") (net 50))
  (segment (start 134.323113 119.15) (end 134.406978 119.140551) (width 0.125) (layer "B.Cu") (net 50))
  (segment (start 135.983378 118.428761) (end 136.015082 118.439855) (width 0.125) (layer "B.Cu") (net 50))
  (segment (start 128.117775 119.008099) (end 128.162676 118.936639) (width 0.125) (layer "B.Cu") (net 50))
  (segment (start 127.184917 117.999685) (end 127.216621 117.988591) (width 0.125) (layer "B.Cu") (net 50))
  (segment (start 123.856476 118.017556) (end 123.884917 117.999685) (width 0.125) (layer "B.Cu") (net 50))
  (segment (start 130.543523 118.457726) (end 130.567274 118.481477) (width 0.125) (layer "B.Cu") (net 50))
  (segment (start 133.458098 119.067776) (end 133.517775 119.008099) (width 0.125) (layer "B.Cu") (net 50))
  (segment (start 135.79055 118.856979) (end 135.8 118.773114) (width 0.125) (layer "B.Cu") (net 50))
  (segment (start 123.586638 119.112677) (end 123.658098 119.067776) (width 0.125) (layer "B.Cu") (net 50))
  (segment (start 128.5 118.13483) (end 128.5 118.773114) (width 0.125) (layer "B.Cu") (net 50))
  (segment (start 133.783378 118.428761) (end 133.815082 118.439855) (width 0.125) (layer "B.Cu") (net 50))
  (segment (start 126.382224 119.008099) (end 126.441901 119.067776) (width 0.125) (layer "B.Cu") (net 50))
  (segment (start 130.086638 119.112677) (end 130.158098 119.067776) (width 0.125) (layer "B.Cu") (net 50))
  (segment (start 130.332725 118.481477) (end 130.356476 118.457726) (width 0.125) (layer "B.Cu") (net 50))
  (segment (start 134.784917 118.439855) (end 134.816621 118.428761) (width 0.125) (layer "B.Cu") (net 50))
  (segment (start 124.932725 118.041307) (end 124.956476 118.017556) (width 0.125) (layer "B.Cu") (net 50))
  (segment (start 125.282224 119.008099) (end 125.341901 119.067776) (width 0.125) (layer "B.Cu") (net 50))
  (segment (start 135.814854 118.509918) (end 135.832725 118.481477) (width 0.125) (layer "B.Cu") (net 50))
  (segment (start 135.8 118.575) (end 135.80376 118.541622) (width 0.125) (layer "B.Cu") (net 50))
  (segment (start 123.79055 118.856979) (end 123.8 118.773114) (width 0.125) (layer "B.Cu") (net 50))
  (segment (start 124.90376 118.101452) (end 124.914854 118.069748) (width 0.125) (layer "B.Cu") (net 50))
  (segment (start 126.183378 117.988591) (end 126.215082 117.999685) (width 0.125) (layer "B.Cu") (net 50))
  (segment (start 131.685145 118.509918) (end 131.696239 118.541622) (width 0.125) (layer "B.Cu") (net 50))
  (segment (start 134.883378 118.428761) (end 134.915082 118.439855) (width 0.125) (layer "B.Cu") (net 50))
  (segment (start 132.532725 118.481477) (end 132.556476 118.457726) (width 0.125) (layer "B.Cu") (net 50))
  (segment (start 127.156476 118.017556) (end 127.184917 117.999685) (width 0.125) (layer "B.Cu") (net 50))
  (segment (start 132.123113 119.15) (end 132.206978 119.140551) (width 0.125) (layer "B.Cu") (net 50))
  (segment (start 136.393021 119.140551) (end 136.476886 119.15) (width 0.125) (layer "B.Cu") (net 50))
  (segment (start 136.241901 119.067776) (end 136.313361 119.112677) (width 0.125) (layer "B.Cu") (net 50))
  (segment (start 124.1 118.13483) (end 124.1 118.773114) (width 0.125) (layer "B.Cu") (net 50))
  (segment (start 135.376886 119.15) (end 135.423113 119.15) (width 0.125) (layer "B.Cu") (net 50))
  (segment (start 130.893021 119.140551) (end 130.976886 119.15) (width 0.125) (layer "B.Cu") (net 50))
  (segment (start 128.058098 119.067776) (end 128.117775 119.008099) (width 0.125) (layer "B.Cu") (net 50))
  (segment (start 128.2 118.773114) (end 128.2 118.13483) (width 0.125) (layer "B.Cu") (net 50))
  (segment (start 132.796239 118.541622) (end 132.8 118.575) (width 0.125) (layer "B.Cu") (net 50))
  (segment (start 128.19055 118.856979) (end 128.2 118.773114) (width 0.125) (layer "B.Cu") (net 50))
  (segment (start 133.982224 119.008099) (end 134.041901 119.067776) (width 0.125) (layer "B.Cu") (net 50))
  (segment (start 127.216621 117.988591) (end 127.25 117.98483) (width 0.125) (layer "B.Cu") (net 50))
  (segment (start 123.658098 119.067776) (end 123.717775 119.008099) (width 0.125) (layer "B.Cu") (net 50))
  (segment (start 127.396239 118.101452) (end 127.4 118.13483) (width 0.125) (layer "B.Cu") (net 50))
  (segment (start 128.537323 118.936639) (end 128.582224 119.008099) (width 0.125) (layer "B.Cu") (net 50))
  (segment (start 135.423113 119.15) (end 135.506978 119.140551) (width 0.125) (layer "B.Cu") (net 50))
  (segment (start 127.114854 118.069748) (end 127.132725 118.041307) (width 0.125) (layer "B.Cu") (net 50))
  (segment (start 131.993021 119.140551) (end 132.076886 119.15) (width 0.125) (layer "B.Cu") (net 50))
  (segment (start 130.609449 118.856979) (end 130.637323 118.936639) (width 0.125) (layer "B.Cu") (net 50))
  (segment (start 130.29055 118.856979) (end 130.3 118.773114) (width 0.125) (layer "B.Cu") (net 50))
  (segment (start 130.158098 119.067776) (end 130.217775 119.008099) (width 0.125) (layer "B.Cu") (net 50))
  (segment (start 136.096239 118.541622) (end 136.1 118.575) (width 0.125) (layer "B.Cu") (net 50))
  (segment (start 131.841901 119.067776) (end 131.913361 119.112677) (width 0.125) (layer "B.Cu") (net 50))
  (segment (start 125.413361 119.112677) (end 125.493021 119.140551) (width 0.125) (layer "B.Cu") (net 50))
  (segment (start 131.432725 118.481477) (end 131.456476 118.457726) (width 0.125) (layer "B.Cu") (net 50))
  (segment (start 123.884917 117.999685) (end 123.916621 117.988591) (width 0.125) (layer "B.Cu") (net 50))
  (segment (start 125.115082 117.999685) (end 125.143523 118.017556) (width 0.125) (layer "B.Cu") (net 50))
  (segment (start 125.196239 118.101452) (end 125.2 118.13483) (width 0.125) (layer "B.Cu") (net 50))
  (segment (start 134.7 118.773114) (end 134.7 118.575) (width 0.125) (layer "B.Cu") (net 50))
  (segment (start 130.262676 118.936639) (end 130.29055 118.856979) (width 0.125) (layer "B.Cu") (net 50))
  (segment (start 125.341901 119.067776) (end 125.413361 119.112677) (width 0.125) (layer "B.Cu") (net 50))
  (segment (start 125.167274 118.041307) (end 125.185145 118.069748) (width 0.125) (layer "B.Cu") (net 50))
  (segment (start 132.076886 119.15) (end 132.123113 119.15) (width 0.125) (layer "B.Cu") (net 50))
  (segment (start 135.916621 118.428761) (end 135.95 118.425) (width 0.125) (layer "B.Cu") (net 50))
  (segment (start 134.732725 118.481477) (end 134.756476 118.457726) (width 0.125) (layer "B.Cu") (net 50))
  (segment (start 133.223113 119.15) (end 133.306978 119.140551) (width 0.125) (layer "B.Cu") (net 50))
  (segment (start 125.05 117.98483) (end 125.083378 117.988591) (width 0.125) (layer "B.Cu") (net 50))
  (segment (start 136.313361 119.112677) (end 136.393021 119.140551) (width 0.125) (layer "B.Cu") (net 50))
  (segment (start 126.593021 119.140551) (end 126.676886 119.15) (width 0.125) (layer "B.Cu") (net 50))
  (segment (start 126.00376 118.101452) (end 126.014854 118.069748) (width 0.125) (layer "B.Cu") (net 50))
  (segment (start 128.641901 119.067776) (end 128.713361 119.112677) (width 0.125) (layer "B.Cu") (net 50))
  (segment (start 129.25 118.550004) (end 129.25 117.349853) (width 0.125) (layer "F.Cu") (net 51))
  (segment (start 129.125 117.224853) (end 129.125 117.204109) (width 0.125) (layer "F.Cu") (net 51))
  (segment (start 129.125 117.204109) (end 129.3625 116.966609) (width 0.125) (layer "F.Cu") (net 51))
  (segment (start 129.25 117.349853) (end 129.125 117.224853) (width 0.125) (layer "F.Cu") (net 51))
  (segment (start 139.17322 121.5) (end 139.17322 120.749999) (width 0.125) (layer "F.Cu") (net 51))
  (segment (start 139.17322 120.749999) (end 139.09822 120.674999) (width 0.125) (layer "F.Cu") (net 51))
  (segment (start 137.873346 119.136864) (end 137.954136 119.097957) (width 0.125) (layer "F.Cu") (net 51))
  (segment (start 137.005749 119.501493) (end 136.988746 119.5368) (width 0.125) (layer "F.Cu") (net 51))
  (segment (start 139.09822 119.921443) (end 139.09822 119.973468) (width 0.125) (layer "F.Cu") (net 51))
  (segment (start 137.173519 119.768498) (end 137.211724 119.759778) (width 0.125) (layer "F.Cu") (net 51))
  (segment (start 138.041558 119.078004) (end 138.131229 119.078004) (width 0.125) (layer "F.Cu") (net 51))
  (segment (start 137.005749 119.687705) (end 137.030182 119.718343) (width 0.125) (layer "F.Cu") (net 51))
  (segment (start 137.670521 118.617295) (end 137.670521 118.706966) (width 0.125) (layer "F.Cu") (net 51))
  (segment (start 137.247031 119.742776) (end 137.277669 119.718343) (width 0.125) (layer "F.Cu") (net 51))
  (segment (start 139.09822 119.973468) (end 139.09822 120.674999) (width 0.125) (layer "F.Cu") (net 51))
  (segment (start 137.650567 118.794388) (end 137.611661 118.875179) (width 0.125) (layer "F.Cu") (net 51))
  (segment (start 136.980026 119.614193) (end 136.988746 119.652398) (width 0.125) (layer "F.Cu") (net 51))
  (segment (start 136.980026 119.575005) (end 136.980026 119.614193) (width 0.125) (layer "F.Cu") (net 51))
  (segment (start 137.06082 119.742776) (end 137.096126 119.759778) (width 0.125) (layer "F.Cu") (net 51))
  (segment (start 137.954136 119.097957) (end 138.041558 119.078004) (width 0.125) (layer "F.Cu") (net 51))
  (segment (start 137.611661 118.449082) (end 137.650567 118.529873) (width 0.125) (layer "F.Cu") (net 51))
  (segment (start 138.369549 119.192773) (end 139.09822 119.921443) (width 0.125) (layer "F.Cu") (net 51))
  (segment (start 137.555752 118.378975) (end 137.611661 118.449082) (width 0.125) (layer "F.Cu") (net 51))
  (segment (start 137.611661 118.875179) (end 137.555752 118.945286) (width 0.125) (layer "F.Cu") (net 51))
  (segment (start 137.096126 119.759778) (end 137.134331 119.768498) (width 0.125) (layer "F.Cu") (net 51))
  (segment (start 137.803238 119.192773) (end 137.873346 119.136864) (width 0.125) (layer "F.Cu") (net 51))
  (segment (start 136.988746 119.5368) (end 136.980026 119.575005) (width 0.125) (layer "F.Cu") (net 51))
  (segment (start 137.555752 118.945286) (end 137.030182 119.470855) (width 0.125) (layer "F.Cu") (net 51))
  (segment (start 137.030182 119.470855) (end 137.005749 119.501493) (width 0.125) (layer "F.Cu") (net 51))
  (segment (start 137.030182 119.718343) (end 137.06082 119.742776) (width 0.125) (layer "F.Cu") (net 51))
  (segment (start 137.356327 117.843673) (end 137.356327 118.17955) (width 0.125) (layer "F.Cu") (net 51))
  (segment (start 138.131229 119.078004) (end 138.218651 119.097957) (width 0.125) (layer "F.Cu") (net 51))
  (segment (start 137.356327 118.17955) (end 137.555752 118.378975) (width 0.125) (layer "F.Cu") (net 51))
  (segment (start 138.299442 119.136864) (end 138.369549 119.192773) (width 0.125) (layer "F.Cu") (net 51))
  (segment (start 137.670521 118.706966) (end 137.650567 118.794388) (width 0.125) (layer "F.Cu") (net 51))
  (segment (start 137.277669 119.718343) (end 137.803238 119.192773) (width 0.125) (layer "F.Cu") (net 51))
  (segment (start 136.988746 119.652398) (end 137.005749 119.687705) (width 0.125) (layer "F.Cu") (net 51))
  (segment (start 137.134331 119.768498) (end 137.173519 119.768498) (width 0.125) (layer "F.Cu") (net 51))
  (segment (start 137.650567 118.529873) (end 137.670521 118.617295) (width 0.125) (layer "F.Cu") (net 51))
  (segment (start 137.211724 119.759778) (end 137.247031 119.742776) (width 0.125) (layer "F.Cu") (net 51))
  (segment (start 138.218651 119.097957) (end 138.299442 119.136864) (width 0.125) (layer "F.Cu") (net 51))
  (via (at 129.3625 116.966609) (size 0.6) (drill 0.25) (layers "F.Cu" "B.Cu") (net 51))
  (via (at 137.356327 117.843673) (size 0.6) (drill 0.25) (layers "F.Cu" "B.Cu") (net 51))
  (segment (start 134.896865 117.577816) (end 134.9 117.55) (width 0.125) (layer "B.Cu") (net 51))
  (segment (start 129.9 117.55) (end 129.9 116.003332) (width 0.125) (layer "B.Cu") (net 51))
  (segment (start 130.896865 117.577816) (end 130.9 117.55) (width 0.125) (layer "B.Cu") (net 51))
  (segment (start 132.100026 114.634991) (end 132.174707 114.608859) (width 0.125) (layer "B.Cu") (net 51))
  (segment (start 130.872728 117.627937) (end 130.887621 117.604236) (width 0.125) (layer "B.Cu") (net 51))
  (segment (start 131.449973 115.634991) (end 131.516967 115.677086) (width 0.125) (layer "B.Cu") (net 51))
  (segment (start 135.677271 117.627937) (end 135.697063 117.647729) (width 0.125) (layer "B.Cu") (net 51))
  (segment (start 135.296668 114.6) (end 135.375292 114.608859) (width 0.125) (layer "B.Cu") (net 51))
  (segment (start 130.977085 115.733033) (end 131.033032 115.677086) (width 0.125) (layer "B.Cu") (net 51))
  (segment (start 134.747184 117.671866) (end 134.775 117.675) (width 0.125) (layer "B.Cu") (net 51))
  (segment (start 134.93499 114.800027) (end 134.977085 114.733033) (width 0.125) (layer "B.Cu") (net 51))
  (segment (start 133.449973 116.584991) (end 133.516967 116.627086) (width 0.125) (layer "B.Cu") (net 51))
  (segment (start 134.100026 116.534991) (end 134.174707 116.508859) (width 0.125) (layer "B.Cu") (net 51))
  (segment (start 133.852936 117.647729) (end 133.872728 117.627937) (width 0.125) (layer "B.Cu") (net 51))
  (segment (start 133.9 116.853332) (end 133.908858 116.774708) (width 0.125) (layer "B.Cu") (net 51))
  (segment (start 131.908858 114.874708) (end 131.93499 114.800027) (width 0.125) (layer "B.Cu") (net 51))
  (segment (start 130.802815 117.671866) (end 130.829235 117.662622) (width 0.125) (layer "B.Cu") (net 51))
  (segment (start 132.896865 117.577816) (end 132.9 117.55) (width 0.125) (layer "B.Cu") (net 51))
  (segment (start 130.697063 117.647729) (end 130.720764 117.662622) (width 0.125) (layer "B.Cu") (net 51))
  (segment (start 135.174707 114.608859) (end 135.253331 114.6) (width 0.125) (layer "B.Cu") (net 51))
  (segment (start 131.802815 117.671866) (end 131.829235 117.662622) (width 0.125) (layer "B.Cu") (net 51))
  (segment (start 134.677271 117.627937) (end 134.697063 117.647729) (width 0.125) (layer "B.Cu") (net 51))
  (segment (start 133.677271 117.627937) (end 133.697063 117.647729) (width 0.125) (layer "B.Cu") (net 51))
  (segment (start 134.908858 114.874708) (end 134.93499 114.800027) (width 0.125) (layer "B.Cu") (net 51))
  (segment (start 130.908858 115.874708) (end 130.93499 115.800027) (width 0.125) (layer "B.Cu") (net 51))
  (segment (start 129.977085 115.783033) (end 130.033032 115.727086) (width 0.125) (layer "B.Cu") (net 51))
  (segment (start 130.720764 117.662622) (end 130.747184 117.671866) (width 0.125) (layer "B.Cu") (net 51))
  (segment (start 133.697063 117.647729) (end 133.720764 117.662622) (width 0.125) (layer "B.Cu") (net 51))
  (segment (start 130.296668 115.65) (end 130.375292 115.658859) (width 0.125) (layer "B.Cu") (net 51))
  (segment (start 131.9 117.55) (end 131.9 114.953332) (width 0.125) (layer "B.Cu") (net 51))
  (segment (start 133.829235 117.662622) (end 133.852936 117.647729) (width 0.125) (layer "B.Cu") (net 51))
  (segment (start 132.775 117.675) (end 132.802815 117.671866) (width 0.125) (layer "B.Cu") (net 51))
  (segment (start 132.572914 114.733033) (end 132.615009 114.800027) (width 0.125) (layer "B.Cu") (net 51))
  (segment (start 133.747184 117.671866) (end 133.775 117.675) (width 0.125) (layer "B.Cu") (net 51))
  (segment (start 131.174707 115.608859) (end 131.253331 115.6) (width 0.125) (layer "B.Cu") (net 51))
  (segment (start 130.677271 117.627937) (end 130.697063 117.647729) (width 0.125) (layer "B.Cu") (net 51))
  (segment (start 132.615009 114.800027) (end 132.641141 114.874708) (width 0.125) (layer "B.Cu") (net 51))
  (segment (start 131.747184 117.671866) (end 131.775 117.675) (width 0.125) (layer "B.Cu") (net 51))
  (segment (start 134.516967 116.577086) (end 134.572914 116.633033) (width 0.125) (layer "B.Cu") (net 51))
  (segment (start 131.296668 115.6) (end 131.375292 115.608859) (width 0.125) (layer "B.Cu") (net 51))
  (segment (start 133.662378 117.604236) (end 133.677271 117.627937) (width 0.125) (layer "B.Cu") (net 51))
  (segment (start 133.572914 116.683033) (end 133.615009 116.750027) (width 0.125) (layer "B.Cu") (net 51))
  (segment (start 135.641141 114.874708) (end 135.65 114.953332) (width 0.125) (layer "B.Cu") (net 51))
  (segment (start 134.174707 116.508859) (end 134.253331 116.5) (width 0.125) (layer "B.Cu") (net 51))
  (segment (start 134.662378 117.604236) (end 134.677271 117.627937) (width 0.125) (layer "B.Cu") (net 51))
  (segment (start 135.449973 114.634991) (end 135.516967 114.677086) (width 0.125) (layer "B.Cu") (net 51))
  (segment (start 132.697063 117.647729) (end 132.720764 117.662622) (width 0.125) (layer "B.Cu") (net 51))
  (segment (start 135.662378 117.604236) (end 135.677271 117.627937) (width 0.125) (layer "B.Cu") (net 51))
  (segment (start 132.296668 114.6) (end 132.375292 114.608859) (width 0.125) (layer "B.Cu") (net 51))
  (segment (start 131.852936 117.647729) (end 131.872728 117.627937) (width 0.125) (layer "B.Cu") (net 51))
  (segment (start 130.653134 117.577816) (end 130.662378 117.604236) (width 0.125) (layer "B.Cu") (net 51))
  (segment (start 131.65 115.953332) (end 131.65 117.55) (width 0.125) (layer "B.Cu") (net 51))
  (segment (start 132.516967 114.677086) (end 132.572914 114.733033) (width 0.125) (layer "B.Cu") (net 51))
  (segment (start 129.125 117.204109) (end 129.125 117.348222) (width 0.125) (layer "B.Cu") (net 51))
  (segment (start 134.977085 114.733033) (end 135.033032 114.677086) (width 0.125) (layer "B.Cu") (net 51))
  (segment (start 134.9 114.953332) (end 134.908858 114.874708) (width 0.125) (layer "B.Cu") (net 51))
  (segment (start 131.9 114.953332) (end 131.908858 114.874708) (width 0.125) (layer "B.Cu") (net 51))
  (segment (start 134.887621 117.604236) (end 134.896865 117.577816) (width 0.125) (layer "B.Cu") (net 51))
  (segment (start 132.747184 117.671866) (end 132.775 117.675) (width 0.125) (layer "B.Cu") (net 51))
  (segment (start 133.93499 116.700027) (end 133.977085 116.633033) (width 0.125) (layer "B.Cu") (net 51))
  (segment (start 134.615009 116.700027) (end 134.641141 116.774708) (width 0.125) (layer "B.Cu") (net 51))
  (segment (start 133.908858 116.774708) (end 133.93499 116.700027) (width 0.125) (layer "B.Cu") (net 51))
  (segment (start 133.720764 117.662622) (end 133.747184 117.671866) (width 0.125) (layer "B.Cu") (net 51))
  (segment (start 130.887621 117.604236) (end 130.896865 117.577816) (width 0.125) (layer "B.Cu") (net 51))
  (segment (start 131.615009 115.800027) (end 131.641141 115.874708) (width 0.125) (layer "B.Cu") (net 51))
  (segment (start 132.887621 117.604236) (end 132.896865 117.577816) (width 0.125) (layer "B.Cu") (net 51))
  (segment (start 132.802815 117.671866) (end 132.829235 117.662622) (width 0.125) (layer "B.Cu") (net 51))
  (segment (start 132.720764 117.662622) (end 132.747184 117.671866) (width 0.125) (layer "B.Cu") (net 51))
  (segment (start 130.375292 115.658859) (end 130.449973 115.684991) (width 0.125) (layer "B.Cu") (net 51))
  (segment (start 130.829235 117.662622) (end 130.852936 117.647729) (width 0.125) (layer "B.Cu") (net 51))
  (segment (start 133.253331 116.55) (end 133.296668 116.55) (width 0.125) (layer "B.Cu") (net 51))
  (segment (start 135.65 117.55) (end 135.653134 117.577816) (width 0.125) (layer "B.Cu") (net 51))
  (segment (start 135.720764 117.662622) (end 135.747184 117.671866) (width 0.125) (layer "B.Cu") (net 51))
  (segment (start 132.93499 116.750027) (end 132.977085 116.683033) (width 0.125) (layer "B.Cu") (net 51))
  (segment (start 134.852936 117.647729) (end 134.872728 117.627937) (width 0.125) (layer "B.Cu") (net 51))
  (segment (start 129.852936 117.647729) (end 129.872728 117.627937) (width 0.125) (layer "B.Cu") (net 51))
  (segment (start 135.100026 114.634991) (end 135.174707 114.608859) (width 0.125) (layer "B.Cu") (net 51))
  (segment (start 131.253331 115.6) (end 131.296668 115.6) (width 0.125) (layer "B.Cu") (net 51))
  (segment (start 131.887621 117.604236) (end 131.896865 117.577816) (width 0.125) (layer "B.Cu") (net 51))
  (segment (start 132.65 114.953332) (end 132.65 117.55) (width 0.125) (layer "B.Cu") (net 51))
  (segment (start 131.516967 115.677086) (end 131.572914 115.733033) (width 0.125) (layer "B.Cu") (net 51))
  (segment (start 135.747184 117.671866) (end 135.775 117.675) (width 0.125) (layer "B.Cu") (net 51))
  (segment (start 135.375292 114.608859) (end 135.449973 114.634991) (width 0.125) (layer "B.Cu") (net 51))
  (segment (start 133.977085 116.633033) (end 134.033032 116.577086) (width 0.125) (layer "B.Cu") (net 51))
  (segment (start 133.65 117.55) (end 133.653134 117.577816) (width 0.125) (layer "B.Cu") (net 51))
  (segment (start 134.802815 117.671866) (end 134.829235 117.662622) (width 0.125) (layer "B.Cu") (net 51))
  (segment (start 130.852936 117.647729) (end 130.872728 117.627937) (width 0.125) (layer "B.Cu") (net 51))
  (segment (start 131.100026 115.634991) (end 131.174707 115.608859) (width 0.125) (layer "B.Cu") (net 51))
  (segment (start 129.125 117.348222) (end 129.451778 117.675) (width 0.125) (layer "B.Cu") (net 51))
  (segment (start 129.896865 117.577816) (end 129.9 117.55) (width 0.125) (layer "B.Cu") (net 51))
  (segment (start 134.296668 116.5) (end 134.375292 116.508859) (width 0.125) (layer "B.Cu") (net 51))
  (segment (start 133.896865 117.577816) (end 133.9 117.55) (width 0.125) (layer "B.Cu") (net 51))
  (segment (start 133.9 117.55) (end 133.9 116.853332) (width 0.125) (layer "B.Cu") (net 51))
  (segment (start 130.174707 115.658859) (end 130.253331 115.65) (width 0.125) (layer "B.Cu") (net 51))
  (segment (start 133.100026 116.584991) (end 133.174707 116.558859) (width 0.125) (layer "B.Cu") (net 51))
  (segment (start 130.615009 115.850027) (end 130.641141 115.924708) (width 0.125) (layer "B.Cu") (net 51))
  (segment (start 130.775 117.675) (end 130.802815 117.671866) (width 0.125) (layer "B.Cu") (net 51))
  (segment (start 132.375292 114.608859) (end 132.449973 114.634991) (width 0.125) (layer "B.Cu") (net 51))
  (segment (start 131.641141 115.874708) (end 131.65 115.953332) (width 0.125) (layer "B.Cu") (net 51))
  (segment (start 132.977085 116.683033) (end 133.033032 116.627086) (width 0.125) (layer "B.Cu") (net 51))
  (segment (start 135.65 114.953332) (end 135.65 117.55) (width 0.125) (layer "B.Cu") (net 51))
  (segment (start 135.697063 117.647729) (end 135.720764 117.662622) (width 0.125) (layer "B.Cu") (net 51))
  (segment (start 130.572914 115.783033) (end 130.615009 115.850027) (width 0.125) (layer "B.Cu") (net 51))
  (segment (start 133.653134 117.577816) (end 133.662378 117.604236) (width 0.125) (layer "B.Cu") (net 51))
  (segment (start 134.572914 116.633033) (end 134.615009 116.700027) (width 0.125) (layer "B.Cu") (net 51))
  (segment (start 132.872728 117.627937) (end 132.887621 117.604236) (width 0.125) (layer "B.Cu") (net 51))
  (segment (start 129.775 117.675) (end 129.802815 117.671866) (width 0.125) (layer "B.Cu") (net 51))
  (segment (start 134.720764 117.662622) (end 134.747184 117.671866) (width 0.125) (layer "B.Cu") (net 51))
  (segment (start 134.65 116.853332) (end 134.65 117.55) (width 0.125) (layer "B.Cu") (net 51))
  (segment (start 130.662378 117.604236) (end 130.677271 117.627937) (width 0.125) (layer "B.Cu") (net 51))
  (segment (start 135.516967 114.677086) (end 135.572914 114.733033) (width 0.125) (layer "B.Cu") (net 51))
  (segment (start 133.516967 116.627086) (end 133.572914 116.683033) (width 0.125) (layer "B.Cu") (net 51))
  (segment (start 134.641141 116.774708) (end 134.65 116.853332) (width 0.125) (layer "B.Cu") (net 51))
  (segment (start 133.033032 116.627086) (end 133.100026 116.584991) (width 0.125) (layer "B.Cu") (net 51))
  (segment (start 135.253331 114.6) (end 135.296668 114.6) (width 0.125) (layer "B.Cu") (net 51))
  (segment (start 130.641141 115.924708) (end 130.65 116.003332) (width 0.125) (layer "B.Cu") (net 51))
  (segment (start 133.174707 116.558859) (end 133.253331 116.55) (width 0.125) (layer "B.Cu") (net 51))
  (segment (start 134.872728 117.627937) (end 134.887621 117.604236) (width 0.125) (layer "B.Cu") (net 51))
  (segment (start 133.872728 117.627937) (end 133.887621 117.604236) (width 0.125) (layer "B.Cu") (net 51))
  (segment (start 133.615009 116.750027) (end 133.641141 116.824708) (width 0.125) (layer "B.Cu") (net 51))
  (segment (start 131.677271 117.627937) (end 131.697063 117.647729) (width 0.125) (layer "B.Cu") (net 51))
  (segment (start 135.653134 117.577816) (end 135.662378 117.604236) (width 0.125) (layer "B.Cu") (net 51))
  (segment (start 132.662378 117.604236) (end 132.677271 117.627937) (width 0.125) (layer "B.Cu") (net 51))
  (segment (start 132.829235 117.662622) (end 132.852936 117.647729) (width 0.125) (layer "B.Cu") (net 51))
  (segment (start 129.93499 115.850027) (end 129.977085 115.783033) (width 0.125) (layer "B.Cu") (net 51))
  (segment (start 131.775 117.675) (end 131.802815 117.671866) (width 0.125) (layer "B.Cu") (net 51))
  (segment (start 134.9 117.55) (end 134.9 114.953332) (width 0.125) (layer "B.Cu") (net 51))
  (segment (start 131.033032 115.677086) (end 131.100026 115.634991) (width 0.125) (layer "B.Cu") (net 51))
  (segment (start 132.65 117.55) (end 132.653134 117.577816) (width 0.125) (layer "B.Cu") (net 51))
  (segment (start 129.9 116.003332) (end 129.908858 115.924708) (width 0.125) (layer "B.Cu") (net 51))
  (segment (start 132.908858 116.824708) (end 132.93499 116.750027) (width 0.125) (layer "B.Cu") (net 51))
  (segment (start 134.033032 116.577086) (end 134.100026 116.534991) (width 0.125) (layer "B.Cu") (net 51))
  (segment (start 132.174707 114.608859) (end 132.253331 114.6) (width 0.125) (layer "B.Cu") (net 51))
  (segment (start 133.887621 117.604236) (end 133.896865 117.577816) (width 0.125) (layer "B.Cu") (net 51))
  (segment (start 132.449973 114.634991) (end 132.516967 114.677086) (width 0.125) (layer "B.Cu") (net 51))
  (segment (start 135.572914 114.733033) (end 135.615009 114.800027) (width 0.125) (layer "B.Cu") (net 51))
  (segment (start 129.451778 117.675) (end 129.775 117.675) (width 0.125) (layer "B.Cu") (net 51))
  (segment (start 134.829235 117.662622) (end 134.852936 117.647729) (width 0.125) (layer "B.Cu") (net 51))
  (segment (start 135.033032 114.677086) (end 135.100026 114.634991) (width 0.125) (layer "B.Cu") (net 51))
  (segment (start 134.653134 117.577816) (end 134.662378 117.604236) (width 0.125) (layer "B.Cu") (net 51))
  (segment (start 131.896865 117.577816) (end 131.9 117.55) (width 0.125) (layer "B.Cu") (net 51))
  (segment (start 130.747184 117.671866) (end 130.775 117.675) (width 0.125) (layer "B.Cu") (net 51))
  (segment (start 131.572914 115.733033) (end 131.615009 115.800027) (width 0.125) (layer "B.Cu") (net 51))
  (segment (start 132.653134 117.577816) (end 132.662378 117.604236) (width 0.125) (layer "B.Cu") (net 51))
  (segment (start 130.9 115.953332) (end 130.908858 115.874708) (width 0.125) (layer "B.Cu") (net 51))
  (segment (start 131.829235 117.662622) (end 131.852936 117.647729) (width 0.125) (layer "B.Cu") (net 51))
  (segment (start 131.65 117.55) (end 131.653134 117.577816) (width 0.125) (layer "B.Cu") (net 51))
  (segment (start 131.977085 114.733033) (end 132.033032 114.677086) (width 0.125) (layer "B.Cu") (net 51))
  (segment (start 130.9 117.55) (end 130.9 115.953332) (width 0.125) (layer "B.Cu") (net 51))
  (segment (start 133.641141 116.824708) (end 133.65 116.903332) (width 0.125) (layer "B.Cu") (net 51))
  (segment (start 130.100026 115.684991) (end 130.174707 115.658859) (width 0.125) (layer "B.Cu") (net 51))
  (segment (start 130.253331 115.65) (end 130.296668 115.65) (width 0.125) (layer "B.Cu") (net 51))
  (segment (start 137.02045 117.843673) (end 136.851777 117.675) (width 0.125) (layer "B.Cu") (net 51))
  (segment (start 132.9 116.903332) (end 132.908858 116.824708) (width 0.125) (layer "B.Cu") (net 51))
  (segment (start 130.93499 115.800027) (end 130.977085 115.733033) (width 0.125) (layer "B.Cu") (net 51))
  (segment (start 130.516967 115.727086) (end 130.572914 115.783033) (width 0.125) (layer "B.Cu") (net 51))
  (segment (start 131.662378 117.604236) (end 131.677271 117.627937) (width 0.125) (layer "B.Cu") (net 51))
  (segment (start 132.033032 114.677086) (end 132.100026 114.634991) (width 0.125) (layer "B.Cu") (net 51))
  (segment (start 131.720764 117.662622) (end 131.747184 117.671866) (width 0.125) (layer "B.Cu") (net 51))
  (segment (start 136.851777 117.675) (end 135.775 117.675) (width 0.125) (layer "B.Cu") (net 51))
  (segment (start 137.356327 117.843673) (end 137.02045 117.843673) (width 0.125) (layer "B.Cu") (net 51))
  (segment (start 134.449973 116.534991) (end 134.516967 116.577086) (width 0.125) (layer "B.Cu") (net 51))
  (segment (start 134.253331 116.5) (end 134.296668 116.5) (width 0.125) (layer "B.Cu") (net 51))
  (segment (start 134.697063 117.647729) (end 134.720764 117.662622) (width 0.125) (layer "B.Cu") (net 51))
  (segment (start 134.65 117.55) (end 134.653134 117.577816) (width 0.125) (layer "B.Cu") (net 51))
  (segment (start 132.253331 114.6) (end 132.296668 114.6) (width 0.125) (layer "B.Cu") (net 51))
  (segment (start 129.3625 116.966609) (end 129.125 117.204109) (width 0.125) (layer "B.Cu") (net 51))
  (segment (start 131.375292 115.608859) (end 131.449973 115.634991) (width 0.125) (layer "B.Cu") (net 51))
  (segment (start 129.887621 117.604236) (end 129.896865 117.577816) (width 0.125) (layer "B.Cu") (net 51))
  (segment (start 131.872728 117.627937) (end 131.887621 117.604236) (width 0.125) (layer "B.Cu") (net 51))
  (segment (start 132.677271 117.627937) (end 132.697063 117.647729) (width 0.125) (layer "B.Cu") (net 51))
  (segment (start 130.033032 115.727086) (end 130.100026 115.684991) (width 0.125) (layer "B.Cu") (net 51))
  (segment (start 129.829235 117.662622) (end 129.852936 117.647729) (width 0.125) (layer "B.Cu") (net 51))
  (segment (start 129.802815 117.671866) (end 129.829235 117.662622) (width 0.125) (layer "B.Cu") (net 51))
  (segment (start 129.908858 115.924708) (end 129.93499 115.850027) (width 0.125) (layer "B.Cu") (net 51))
  (segment (start 130.65 117.55) (end 130.653134 117.577816) (width 0.125) (layer "B.Cu") (net 51))
  (segment (start 133.775 117.675) (end 133.802815 117.671866) (width 0.125) (layer "B.Cu") (net 51))
  (segment (start 132.641141 114.874708) (end 132.65 114.953332) (width 0.125) (layer "B.Cu") (net 51))
  (segment (start 134.375292 116.508859) (end 134.449973 116.534991) (width 0.125) (layer "B.Cu") (net 51))
  (segment (start 133.65 116.903332) (end 133.65 117.55) (width 0.125) (layer "B.Cu") (net 51))
  (segment (start 133.375292 116.558859) (end 133.449973 116.584991) (width 0.125) (layer "B.Cu") (net 51))
  (segment (start 131.653134 117.577816) (end 131.662378 117.604236) (width 0.125) (layer "B.Cu") (net 51))
  (segment (start 135.615009 114.800027) (end 135.641141 114.874708) (width 0.125) (layer "B.Cu") (net 51))
  (segment (start 129.872728 117.627937) (end 129.887621 117.604236) (width 0.125) (layer "B.Cu") (net 51))
  (segment (start 134.775 117.675) (end 134.802815 117.671866) (width 0.125) (layer "B.Cu") (net 51))
  (segment (start 132.9 117.55) (end 132.9 116.903332) (width 0.125) (layer "B.Cu") (net 51))
  (segment (start 133.296668 116.55) (end 133.375292 116.558859) (width 0.125) (layer "B.Cu") (net 51))
  (segment (start 131.93499 114.800027) (end 131.977085 114.733033) (width 0.125) (layer "B.Cu") (net 51))
  (segment (start 133.802815 117.671866) (end 133.829235 117.662622) (width 0.125) (layer "B.Cu") (net 51))
  (segment (start 131.697063 117.647729) (end 131.720764 117.662622) (width 0.125) (layer "B.Cu") (net 51))
  (segment (start 130.65 116.003332) (end 130.65 117.55) (width 0.125) (layer "B.Cu") (net 51))
  (segment (start 130.449973 115.684991) (end 130.516967 115.727086) (width 0.125) (layer "B.Cu") (net 51))
  (segment (start 132.852936 117.647729) (end 132.872728 117.627937) (width 0.125) (layer "B.Cu") (net 51))
  (segment (start 139.756327 119.07955) (end 139.756327 118.743673) (width 0.125) (layer "F.Cu") (net 52))
  (segment (start 139.97322 121.5) (end 139.97322 120.749999) (width 0.125) (layer "F.Cu") (net 52))
  (segment (start 139.89822 119.221443) (end 139.756327 119.07955) (width 0.125) (layer "F.Cu") (net 52))
  (segment (start 139.89822 120.674999) (end 139.89822 119.221443) (width 0.125) (layer "F.Cu") (net 52))
  (segment (start 139.97322 120.749999) (end 139.89822 120.674999) (width 0.125) (layer "F.Cu") (net 52))
  (segment (start 123.124999 117.202853) (end 123.362499 116.965353) (width 0.125) (layer "F.Cu") (net 52))
  (segment (start 123.124999 117.224853) (end 123.124999 117.202853) (width 0.125) (layer "F.Cu") (net 52))
  (segment (start 123.249999 117.349853) (end 123.124999 117.224853) (width 0.125) (layer "F.Cu") (net 52))
  (segment (start 123.249999 118.550004) (end 123.249999 117.349853) (width 0.125) (layer "F.Cu") (net 52))
  (via (at 139.756327 118.743673) (size 0.6) (drill 0.25) (layers "F.Cu" "B.Cu") (net 52))
  (via (at 123.362499 116.965353) (size 0.6) (drill 0.25) (layers "F.Cu" "B.Cu") (net 52))
  (segment (start 135.366621 118.89624) (end 135.4 118.9) (width 0.125) (layer "B.Cu") (net 52))
  (segment (start 131.808098 118.257225) (end 131.867775 118.316902) (width 0.125) (layer "B.Cu") (net 52))
  (segment (start 134.008098 118.257225) (end 134.067775 118.316902) (width 0.125) (layer "B.Cu") (net 52))
  (segment (start 123.493523 118.867275) (end 123.517274 118.843524) (width 0.125) (layer "B.Cu") (net 52))
  (segment (start 136.466621 118.89624) (end 136.5 118.9) (width 0.125) (layer "B.Cu") (net 52))
  (segment (start 125.026886 117.73483) (end 125.073113 117.73483) (width 0.125) (layer "B.Cu") (net 52))
  (segment (start 131.232224 118.316902) (end 131.291901 118.257225) (width 0.125) (layer "B.Cu") (net 52))
  (segment (start 127.935145 118.815083) (end 127.946239 118.783379) (width 0.125) (layer "B.Cu") (net 52))
  (segment (start 135.559449 118.468022) (end 135.587323 118.388362) (width 0.125) (layer "B.Cu") (net 52))
  (segment (start 125.665082 118.885146) (end 125.693523 118.867275) (width 0.125) (layer "B.Cu") (net 52))
  (segment (start 125.717274 118.843524) (end 125.735145 118.815083) (width 0.125) (layer "B.Cu") (net 52))
  (segment (start 125.412676 117.948192) (end 125.44055 118.027852) (width 0.125) (layer "B.Cu") (net 52))
  (segment (start 139.051777 118.375) (end 139.42045 118.743673) (width 0.125) (layer "B.Cu") (net 52))
  (segment (start 127.946239 118.783379) (end 127.95 118.75) (width 0.125) (layer "B.Cu") (net 52))
  (segment (start 133.856978 118.18445) (end 133.936638 118.212324) (width 0.125) (layer "B.Cu") (net 52))
  (segment (start 133.106476 118.867275) (end 133.134917 118.885146) (width 0.125) (layer "B.Cu") (net 52))
  (segment (start 127.612676 117.948192) (end 127.64055 118.027852) (width 0.125) (layer "B.Cu") (net 52))
  (segment (start 135.691901 118.257225) (end 135.763361 118.212324) (width 0.125) (layer "B.Cu") (net 52))
  (segment (start 130.191901 118.257225) (end 130.263361 118.212324) (width 0.125) (layer "B.Cu") (net 52))
  (segment (start 126.55376 118.783379) (end 126.564854 118.815083) (width 0.125) (layer "B.Cu") (net 52))
  (segment (start 126.835145 118.815083) (end 126.846239 118.783379) (width 0.125) (layer "B.Cu") (net 52))
  (segment (start 135.433378 118.89624) (end 135.465082 118.885146) (width 0.125) (layer "B.Cu") (net 52))
  (segment (start 130.85376 118.783379) (end 130.864854 118.815083) (width 0.125) (layer "B.Cu") (net 52))
  (segment (start 127.893523 118.867275) (end 127.917274 118.843524) (width 0.125) (layer "B.Cu") (net 52))
  (segment (start 133.643021 118.18445) (end 133.726886 118.175) (width 0.125) (layer "B.Cu") (net 52))
  (segment (start 126.336638 117.772154) (end 126.408098 117.817055) (width 0.125) (layer "B.Cu") (net 52))
  (segment (start 134.591901 118.257225) (end 134.663361 118.212324) (width 0.125) (layer "B.Cu") (net 52))
  (segment (start 127.508098 117.817055) (end 127.567775 117.876732) (width 0.125) (layer "B.Cu") (net 52))
  (segment (start 136.056978 118.18445) (end 136.136638 118.212324) (width 0.125) (layer "B.Cu") (net 52))
  (segment (start 130.132224 118.316902) (end 130.191901 118.257225) (width 0.125) (layer "B.Cu") (net 52))
  (segment (start 128.866621 118.89624) (end 128.9 118.9) (width 0.125) (layer "B.Cu") (net 52))
  (segment (start 123.587323 117.948192) (end 123.632224 117.876732) (width 0.125) (layer "B.Cu") (net 52))
  (segment (start 133.082725 118.843524) (end 133.106476 118.867275) (width 0.125) (layer "B.Cu") (net 52))
  (segment (start 127.65 118.111717) (end 127.65 118.75) (width 0.125) (layer "B.Cu") (net 52))
  (segment (start 125.963361 117.772154) (end 126.043021 117.74428) (width 0.125) (layer "B.Cu") (net 52))
  (segment (start 129.965082 118.885146) (end 129.993523 118.867275) (width 0.125) (layer "B.Cu") (net 52))
  (segment (start 126.55 118.75) (end 126.55376 118.783379) (width 0.125) (layer "B.Cu") (net 52))
  (segment (start 131.117274 118.843524) (end 131.135145 118.815083) (width 0.125) (layer "B.Cu") (net 52))
  (segment (start 134.15376 118.783379) (end 134.164854 118.815083) (width 0.125) (layer "B.Cu") (net 52))
  (segment (start 134.435145 118.815083) (end 134.446239 118.783379) (width 0.125) (layer "B.Cu") (net 52))
  (segment (start 128.75 118.75) (end 128.75376 118.783379) (width 0.125) (layer "B.Cu") (net 52))
  (segment (start 129.933378 118.89624) (end 129.965082 118.885146) (width 0.125) (layer "B.Cu") (net 52))
  (segment (start 126.7 118.9) (end 126.733378 118.89624) (width 0.125) (layer "B.Cu") (net 52))
  (segment (start 127.65376 118.783379) (end 127.664854 118.815083) (width 0.125) (layer "B.Cu") (net 52))
  (segment (start 125.6 118.9) (end 125.633378 118.89624) (width 0.125) (layer "B.Cu") (net 52))
  (segment (start 123.843021 117.74428) (end 123.926886 117.73483) (width 0.125) (layer "B.Cu") (net 52))
  (segment (start 128.806476 118.867275) (end 128.834917 118.885146) (width 0.125) (layer "B.Cu") (net 52))
  (segment (start 128.608098 117.817055) (end 128.667775 117.876732) (width 0.125) (layer "B.Cu") (net 52))
  (segment (start 128.536638 117.772154) (end 128.608098 117.817055) (width 0.125) (layer "B.Cu") (net 52))
  (segment (start 125.746239 118.783379) (end 125.75 118.75) (width 0.125) (layer "B.Cu") (net 52))
  (segment (start 136.136638 118.212324) (end 136.208098 118.257225) (width 0.125) (layer "B.Cu") (net 52))
  (segment (start 134.206476 118.867275) (end 134.234917 118.885146) (width 0.125) (layer "B.Cu") (net 52))
  (segment (start 134.14055 118.468022) (end 134.15 118.551887) (width 0.125) (layer "B.Cu") (net 52))
  (segment (start 134.15 118.551887) (end 134.15 118.75) (width 0.125) (layer "B.Cu") (net 52))
  (segment (start 124.65 118.111717) (end 124.659449 118.027852) (width 0.125) (layer "B.Cu") (net 52))
  (segment (start 127.959449 118.027852) (end 127.987323 117.948192) (width 0.125) (layer "B.Cu") (net 52))
  (segment (start 133.012676 118.388362) (end 133.04055 118.468022) (width 0.125) (layer "B.Cu") (net 52))
  (segment (start 133.35 118.75) (end 133.35 118.551887) (width 0.125) (layer "B.Cu") (net 52))
  (segment (start 131.656978 118.18445) (end 131.736638 118.212324) (width 0.125) (layer "B.Cu") (net 52))
  (segment (start 131.443021 118.18445) (end 131.526886 118.175) (width 0.125) (layer "B.Cu") (net 52))
  (segment (start 134.487323 118.388362) (end 134.532224 118.316902) (width 0.125) (layer "B.Cu") (net 52))
  (segment (start 131.15 118.75) (end 131.15 118.551887) (width 0.125) (layer "B.Cu") (net 52))
  (segment (start 123.973113 117.73483) (end 124.056978 117.74428) (width 0.125) (layer "B.Cu") (net 52))
  (segment (start 128.163361 117.772154) (end 128.243021 117.74428) (width 0.125) (layer "B.Cu") (net 52))
  (segment (start 127.143021 117.74428) (end 127.226886 117.73483) (width 0.125) (layer "B.Cu") (net 52))
  (segment (start 137.423222 118.9) (end 137.948222 118.375) (width 0.125) (layer "B.Cu") (net 52))
  (segment (start 130.767775 118.316902) (end 130.812676 118.388362) (width 0.125) (layer "B.Cu") (net 52))
  (segment (start 130.934917 118.885146) (end 130.966621 118.89624) (width 0.125) (layer "B.Cu") (net 52))
  (segment (start 128.9 118.9) (end 129.9 118.9) (width 0.125) (layer "B.Cu") (net 52))
  (segment (start 126.733378 118.89624) (end 126.765082 118.885146) (width 0.125) (layer "B.Cu") (net 52))
  (segment (start 123.517274 118.843524) (end 123.535145 118.815083) (width 0.125) (layer "B.Cu") (net 52))
  (segment (start 127.356978 117.74428) (end 127.436638 117.772154) (width 0.125) (layer "B.Cu") (net 52))
  (segment (start 134.663361 118.212324) (end 134.743021 118.18445) (width 0.125) (layer "B.Cu") (net 52))
  (segment (start 126.887323 117.948192) (end 126.932224 117.876732) (width 0.125) (layer "B.Cu") (net 52))
  (segment (start 126.606476 118.867275) (end 126.634917 118.885146) (width 0.125) (layer "B.Cu") (net 52))
  (segment (start 133.05376 118.783379) (end 133.064854 118.815083) (width 0.125) (layer "B.Cu") (net 52))
  (segment (start 131.159449 118.468022) (end 131.187323 118.388362) (width 0.125) (layer "B.Cu") (net 52))
  (segment (start 127.64055 118.027852) (end 127.65 118.111717) (width 0.125) (layer "B.Cu") (net 52))
  (segment (start 131.912676 118.388362) (end 131.94055 118.468022) (width 0.125) (layer "B.Cu") (net 52))
  (segment (start 132.235145 118.815083) (end 132.246239 118.783379) (width 0.125) (layer "B.Cu") (net 52))
  (segment (start 134.826886 118.175) (end 134.873113 118.175) (width 0.125) (layer "B.Cu") (net 52))
  (segment (start 124.466621 118.89624) (end 124.5 118.9) (width 0.125) (layer "B.Cu") (net 52))
  (segment (start 135.282725 118.843524) (end 135.306476 118.867275) (width 0.125) (layer "B.Cu") (net 52))
  (segment (start 135.926886 118.175) (end 135.973113 118.175) (width 0.125) (layer "B.Cu") (net 52))
  (segment (start 130.708098 118.257225) (end 130.767775 118.316902) (width 0.125) (layer "B.Cu") (net 52))
  (segment (start 124.533378 118.89624) (end 124.565082 118.885146) (width 0.125) (layer "B.Cu") (net 52))
  (segment (start 131.291901 118.257225) (end 131.363361 118.212324) (width 0.125) (layer "B.Cu") (net 52))
  (segment (start 132.034917 118.885146) (end 132.066621 118.89624) (width 0.125) (layer "B.Cu") (net 52))
  (segment (start 132.332224 118.316902) (end 132.391901 118.257225) (width 0.125) (layer "B.Cu") (net 52))
  (segment (start 134.266621 118.89624) (end 134.3 118.9) (width 0.125) (layer "B.Cu") (net 52))
  (segment (start 136.35 118.551887) (end 136.35 118.75) (width 0.125) (layer "B.Cu") (net 52))
  (segment (start 133.491901 118.257225) (end 133.563361 118.212324) (width 0.125) (layer "B.Cu") (net 52))
  (segment (start 127.682725 118.843524) (end 127.706476 118.867275) (width 0.125) (layer "B.Cu") (net 52))
  (segment (start 130.473113 118.175) (end 130.556978 118.18445) (width 0.125) (layer "B.Cu") (net 52))
  (segment (start 132.626886 118.175) (end 132.673113 118.175) (width 0.125) (layer "B.Cu") (net 52))
  (segment (start 124.863361 117.772154) (end 124.943021 117.74428) (width 0.125) (layer "B.Cu") (net 52))
  (segment (start 135.167775 118.316902) (end 135.212676 118.388362) (width 0.125) (layer "B.Cu") (net 52))
  (segment (start 135.306476 118.867275) (end 135.334917 118.885146) (width 0.125) (layer "B.Cu") (net 52))
  (segment (start 130.05 118.551887) (end 130.059449 118.468022) (width 0.125) (layer "B.Cu") (net 52))
  (segment (start 125.735145 118.815083) (end 125.746239 118.783379) (width 0.125) (layer "B.Cu") (net 52))
  (segment (start 132.25 118.551887) (end 132.259449 118.468022) (width 0.125) (layer "B.Cu") (net 52))
  (segment (start 126.859449 118.027852) (end 126.887323 117.948192) (width 0.125) (layer "B.Cu") (net 52))
  (segment (start 136.382725 118.843524) (end 136.406476 118.867275) (width 0.125) (layer "B.Cu") (net 52))
  (segment (start 126.564854 118.815083) (end 126.582725 118.843524) (width 0.125) (layer "B.Cu") (net 52))
  (segment (start 132.543021 118.18445) (end 132.626886 118.175) (width 0.125) (layer "B.Cu") (net 52))
  (segment (start 130.882725 118.843524) (end 130.906476 118.867275) (width 0.125) (layer "B.Cu") (net 52))
  (segment (start 128.091901 117.817055) (end 128.163361 117.772154) (width 0.125) (layer "B.Cu") (net 52))
  (segment (start 133.335145 118.815083) (end 133.346239 118.783379) (width 0.125) (layer "B.Cu") (net 52))
  (segment (start 126.408098 117.817055) (end 126.467775 117.876732) (width 0.125) (layer "B.Cu") (net 52))
  (segment (start 133.936638 118.212324) (end 134.008098 118.257225) (width 0.125) (layer "B.Cu") (net 52))
  (segment (start 125.633378 118.89624) (end 125.665082 118.885146) (width 0.125) (layer "B.Cu") (net 52))
  (segment (start 132.193523 118.867275) (end 132.217274 118.843524) (width 0.125) (layer "B.Cu") (net 52))
  (segment (start 134.417274 118.843524) (end 134.435145 118.815083) (width 0.125) (layer "B.Cu") (net 52))
  (segment (start 125.759449 118.027852) (end 125.787323 117.948192) (width 0.125) (layer "B.Cu") (net 52))
  (segment (start 136.35 118.75) (end 136.35376 118.783379) (width 0.125) (layer "B.Cu") (net 52))
  (segment (start 130.84055 118.468022) (end 130.85 118.551887) (width 0.125) (layer "B.Cu") (net 52))
  (segment (start 134.067775 118.316902) (end 134.112676 118.388362) (width 0.125) (layer "B.Cu") (net 52))
  (segment (start 124.35 118.75) (end 124.35376 118.783379) (width 0.125) (layer "B.Cu") (net 52))
  (segment (start 134.743021 118.18445) (end 134.826886 118.175) (width 0.125) (layer "B.Cu") (net 52))
  (segment (start 130.864854 118.815083) (end 130.882725 118.843524) (width 0.125) (layer "B.Cu") (net 52))
  (segment (start 134.112676 118.388362) (end 134.14055 118.468022) (width 0.125) (layer "B.Cu") (net 52))
  (segment (start 135.55 118.551887) (end 135.559449 118.468022) (width 0.125) (layer "B.Cu") (net 52))
  (segment (start 126.793523 118.867275) (end 126.817274 118.843524) (width 0.125) (layer "B.Cu") (net 52))
  (segment (start 135.212676 118.388362) (end 135.24055 118.468022) (width 0.125) (layer "B.Cu") (net 52))
  (segment (start 124.635145 118.815083) (end 124.646239 118.783379) (width 0.125) (layer "B.Cu") (net 52))
  (segment (start 134.45 118.75) (end 134.45 118.551887) (width 0.125) (layer "B.Cu") (net 52))
  (segment (start 125.75 118.111717) (end 125.759449 118.027852) (width 0.125) (layer "B.Cu") (net 52))
  (segment (start 123.433378 118.89624) (end 123.465082 118.885146) (width 0.125) (layer "B.Cu") (net 52))
  (segment (start 132.463361 118.212324) (end 132.543021 118.18445) (width 0.125) (layer "B.Cu") (net 52))
  (segment (start 125.787323 117.948192) (end 125.832224 117.876732) (width 0.125) (layer "B.Cu") (net 52))
  (segment (start 131.573113 118.175) (end 131.656978 118.18445) (width 0.125) (layer "B.Cu") (net 52))
  (segment (start 132.133378 118.89624) (end 132.165082 118.885146) (width 0.125) (layer "B.Cu") (net 52))
  (segment (start 135.25376 118.783379) (end 135.264854 118.815083) (width 0.125) (layer "B.Cu") (net 52))
  (segment (start 131.964854 118.815083) (end 131.982725 118.843524) (width 0.125) (layer "B.Cu") (net 52))
  (segment (start 123.535145 118.815083) (end 123.546239 118.783379) (width 0.125) (layer "B.Cu") (net 52))
  (segment (start 126.173113 117.73483) (end 126.256978 117.74428) (width 0.125) (layer "B.Cu") (net 52))
  (segment (start 135.546239 118.783379) (end 135.55 118.75) (width 0.125) (layer "B.Cu") (net 52))
  (segment (start 131.146239 118.783379) (end 131.15 118.75) (width 0.125) (layer "B.Cu") (net 52))
  (segment (start 127.567775 117.876732) (end 127.612676 117.948192) (width 0.125) (layer "B.Cu") (net 52))
  (segment (start 124.382725 118.843524) (end 124.406476 118.867275) (width 0.125) (layer "B.Cu") (net 52))
  (segment (start 135.535145 118.815083) (end 135.546239 118.783379) (width 0.125) (layer "B.Cu") (net 52))
  (segment (start 131.95 118.75) (end 131.95376 118.783379) (width 0.125) (layer "B.Cu") (net 52))
  (segment (start 132.756978 118.18445) (end 132.836638 118.212324) (width 0.125) (layer "B.Cu") (net 52))
  (segment (start 130.046239 118.783379) (end 130.05 118.75) (width 0.125) (layer "B.Cu") (net 52))
  (segment (start 133.265082 118.885146) (end 133.293523 118.867275) (width 0.125) (layer "B.Cu") (net 52))
  (segment (start 133.05 118.551887) (end 133.05 118.75) (width 0.125) (layer "B.Cu") (net 52))
  (segment (start 125.308098 117.817055) (end 125.367775 117.876732) (width 0.125) (layer "B.Cu") (net 52))
  (segment (start 135.25 118.551887) (end 135.25 118.75) (width 0.125) (layer "B.Cu") (net 52))
  (segment (start 132.25 118.75) (end 132.25 118.551887) (width 0.125) (layer "B.Cu") (net 52))
  (segment (start 128.243021 117.74428) (end 128.326886 117.73483) (width 0.125) (layer "B.Cu") (net 52))
  (segment (start 123.691901 117.817055) (end 123.763361 117.772154) (width 0.125) (layer "B.Cu") (net 52))
  (segment (start 133.387323 118.388362) (end 133.432224 118.316902) (width 0.125) (layer "B.Cu") (net 52))
  (segment (start 128.032224 117.876732) (end 128.091901 117.817055) (width 0.125) (layer "B.Cu") (net 52))
  (segment (start 132.066621 118.89624) (end 132.1 118.9) (width 0.125) (layer "B.Cu") (net 52))
  (segment (start 126.846239 118.783379) (end 126.85 118.75) (width 0.125) (layer "B.Cu") (net 52))
  (segment (start 132.673113 118.175) (end 132.756978 118.18445) (width 0.125) (layer "B.Cu") (net 52))
  (segment (start 126.043021 117.74428) (end 126.126886 117.73483) (width 0.125) (layer "B.Cu") (net 52))
  (segment (start 134.333378 118.89624) (end 134.365082 118.885146) (width 0.125) (layer "B.Cu") (net 52))
  (segment (start 132.165082 118.885146) (end 132.193523 118.867275) (width 0.125) (layer "B.Cu") (net 52))
  (segment (start 134.45 118.551887) (end 134.459449 118.468022) (width 0.125) (layer "B.Cu") (net 52))
  (segment (start 128.667775 117.876732) (end 128.712676 117.948192) (width 0.125) (layer "B.Cu") (net 52))
  (segment (start 132.006476 118.867275) (end 132.034917 118.885146) (width 0.125) (layer "B.Cu") (net 52))
  (segment (start 133.359449 118.468022) (end 133.387323 118.388362) (width 0.125) (layer "B.Cu") (net 52))
  (segment (start 130.85 118.551887) (end 130.85 118.75) (width 0.125) (layer "B.Cu") (net 52))
  (segment (start 132.259449 118.468022) (end 132.287323 118.388362) (width 0.125) (layer "B.Cu") (net 52))
  (segment (start 126.256978 117.74428) (end 126.336638 117.772154) (width 0.125) (layer "B.Cu") (net 52))
  (segment (start 125.693523 118.867275) (end 125.717274 118.843524) (width 0.125) (layer "B.Cu") (net 52))
  (segment (start 131.526886 118.175) (end 131.573113 118.175) (width 0.125) (layer "B.Cu") (net 52))
  (segment (start 139.42045 118.743673) (end 139.756327 118.743673) (width 0.125) (layer "B.Cu") (net 52))
  (segment (start 132.836638 118.212324) (end 132.908098 118.257225) (width 0.125) (layer "B.Cu") (net 52))
  (segment (start 123.55 118.75) (end 123.55 118.111717) (width 0.125) (layer "B.Cu") (net 52))
  (segment (start 132.908098 118.257225) (end 132.967775 118.316902) (width 0.125) (layer "B.Cu") (net 52))
  (segment (start 133.05 118.75) (end 133.05376 118.783379) (width 0.125) (layer "B.Cu") (net 52))
  (segment (start 130.059449 118.468022) (end 130.087323 118.388362) (width 0.125) (layer "B.Cu") (net 52))
  (segment (start 126.85 118.75) (end 126.85 118.111717) (width 0.125) (layer "B.Cu") (net 52))
  (segment (start 127.664854 118.815083) (end 127.682725 118.843524) (width 0.125) (layer "B.Cu") (net 52))
  (segment (start 134.164854 118.815083) (end 134.182725 118.843524) (width 0.125) (layer "B.Cu") (net 52))
  (segment (start 125.236638 117.772154) (end 125.308098 117.817055) (width 0.125) (layer "B.Cu") (net 52))
  (segment (start 131.95376 118.783379) (end 131.964854 118.815083) (width 0.125) (layer "B.Cu") (net 52))
  (segment (start 135.587323 118.388362) (end 135.632224 118.316902) (width 0.125) (layer "B.Cu") (net 52))
  (segment (start 128.782725 118.843524) (end 128.806476 118.867275) (width 0.125) (layer "B.Cu") (net 52))
  (segment (start 131.135145 118.815083) (end 131.146239 118.783379) (width 0.125) (layer "B.Cu") (net 52))
  (segment (start 134.873113 118.175) (end 134.956978 118.18445) (width 0.125) (layer "B.Cu") (net 52))
  (segment (start 128.712676 117.948192) (end 128.74055 118.027852) (width 0.125) (layer "B.Cu") (net 52))
  (segment (start 132.391901 118.257225) (end 132.463361 118.212324) (width 0.125) (layer "B.Cu") (net 52))
  (segment (start 124.5 118.9) (end 124.533378 118.89624) (width 0.125) (layer "B.Cu") (net 52))
  (segment (start 127.063361 117.772154) (end 127.143021 117.74428) (width 0.125) (layer "B.Cu") (net 52))
  (segment (start 127.95 118.75) (end 127.95 118.111717) (width 0.125) (layer "B.Cu") (net 52))
  (segment (start 127.8 118.9) (end 127.833378 118.89624) (width 0.125) (layer "B.Cu") (net 52))
  (segment (start 133.563361 118.212324) (end 133.643021 118.18445) (width 0.125) (layer "B.Cu") (net 52))
  (segment (start 123.233735 118.9) (end 123.4 118.9) (width 0.125) (layer "B.Cu") (net 52))
  (segment (start 126.55 118.111717) (end 126.55 118.75) (width 0.125) (layer "B.Cu") (net 52))
  (segment (start 129.9 118.9) (end 129.933378 118.89624) (width 0.125) (layer "B.Cu") (net 52))
  (segment (start 128.75376 118.783379) (end 128.764854 118.815083) (width 0.125) (layer "B.Cu") (net 52))
  (segment (start 124.434917 118.885146) (end 124.466621 118.89624) (width 0.125) (layer "B.Cu") (net 52))
  (segment (start 128.456978 117.74428) (end 128.536638 117.772154) (width 0.125) (layer "B.Cu") (net 52))
  (segment (start 127.436638 117.772154) (end 127.508098 117.817055) (width 0.125) (layer "B.Cu") (net 52))
  (segment (start 133.233378 118.89624) (end 133.265082 118.885146) (width 0.125) (layer "B.Cu") (net 52))
  (segment (start 123.632224 117.876732) (end 123.691901 117.817055) (width 0.125) (layer "B.Cu") (net 52))
  (segment (start 135.264854 118.815083) (end 135.282725 118.843524) (width 0.125) (layer "B.Cu") (net 52))
  (segment (start 123.763361 117.772154) (end 123.843021 117.74428) (width 0.125) (layer "B.Cu") (net 52))
  (segment (start 123.124999 118.791264) (end 123.233735 118.9) (width 0.125) (layer "B.Cu") (net 52))
  (segment (start 125.464854 118.815083) (end 125.482725 118.843524) (width 0.125) (layer "B.Cu") (net 52))
  (segment (start 124.208098 117.817055) (end 124.267775 117.876732) (width 0.125) (layer "B.Cu") (net 52))
  (segment (start 135.334917 118.885146) (end 135.366621 118.89624) (width 0.125) (layer "B.Cu") (net 52))
  (segment (start 127.65 118.75) (end 127.65376 118.783379) (width 0.125) (layer "B.Cu") (net 52))
  (segment (start 127.734917 118.885146) (end 127.766621 118.89624) (width 0.125) (layer "B.Cu") (net 52))
  (segment (start 136.364854 118.815083) (end 136.382725 118.843524) (width 0.125) (layer "B.Cu") (net 52))
  (segment (start 124.732224 117.876732) (end 124.791901 117.817055) (width 0.125) (layer "B.Cu") (net 52))
  (segment (start 126.666621 118.89624) (end 126.7 118.9) (width 0.125) (layer "B.Cu") (net 52))
  (segment (start 132.217274 118.843524) (end 132.235145 118.815083) (width 0.125) (layer "B.Cu") (net 52))
  (segment (start 131.093523 118.867275) (end 131.117274 118.843524) (width 0.125) (layer "B.Cu") (net 52))
  (segment (start 134.234917 118.885146) (end 134.266621 118.89624) (width 0.125) (layer "B.Cu") (net 52))
  (segment (start 125.45 118.111717) (end 125.45 118.75) (width 0.125) (layer "B.Cu") (net 52))
  (segment (start 133.35 118.551887) (end 133.359449 118.468022) (width 0.125) (layer "B.Cu") (net 52))
  (segment (start 132.246239 118.783379) (end 132.25 118.75) (width 0.125) (layer "B.Cu") (net 52))
  (segment (start 126.512676 117.948192) (end 126.54055 118.027852) (width 0.125) (layer "B.Cu") (net 52))
  (segment (start 135.036638 118.212324) (end 135.108098 118.257225) (width 0.125) (layer "B.Cu") (net 52))
  (segment (start 124.34055 118.027852) (end 124.35 118.111717) (width 0.125) (layer "B.Cu") (net 52))
  (segment (start 130.85 118.75) (end 130.85376 118.783379) (width 0.125) (layer "B.Cu") (net 52))
  (segment (start 134.956978 118.18445) (end 135.036638 118.212324) (width 0.125) (layer "B.Cu") (net 52))
  (segment (start 135.843021 118.18445) (end 135.926886 118.175) (width 0.125) (layer "B.Cu") (net 52))
  (segment (start 125.45 118.75) (end 125.45376 118.783379) (width 0.125) (layer "B.Cu") (net 52))
  (segment (start 135.4 118.9) (end 135.433378 118.89624) (width 0.125) (layer "B.Cu") (net 52))
  (segment (start 124.659449 118.027852) (end 124.687323 117.948192) (width 0.125) (layer "B.Cu") (net 52))
  (segment (start 126.765082 118.885146) (end 126.793523 118.867275) (width 0.125) (layer "B.Cu") (net 52))
  (segment (start 124.565082 118.885146) (end 124.593523 118.867275) (width 0.125) (layer "B.Cu") (net 52))
  (segment (start 133.166621 118.89624) (end 133.2 118.9) (width 0.125) (layer "B.Cu") (net 52))
  (segment (start 126.991901 117.817055) (end 127.063361 117.772154) (width 0.125) (layer "B.Cu") (net 52))
  (segment (start 124.791901 117.817055) (end 124.863361 117.772154) (width 0.125) (layer "B.Cu") (net 52))
  (segment (start 124.593523 118.867275) (end 124.617274 118.843524) (width 0.125) (layer "B.Cu") (net 52))
  (segment (start 136.312676 118.388362) (end 136.34055 118.468022) (width 0.125) (layer "B.Cu") (net 52))
  (segment (start 124.65 118.75) (end 124.65 118.111717) (width 0.125) (layer "B.Cu") (net 52))
  (segment (start 123.559449 118.027852) (end 123.587323 117.948192) (width 0.125) (layer "B.Cu") (net 52))
  (segment (start 131.065082 118.885146) (end 131.093523 118.867275) (width 0.125) (layer "B.Cu") (net 52))
  (segment (start 134.3 118.9) (end 134.333378 118.89624) (width 0.125) (layer "B.Cu") (net 52))
  (segment (start 130.812676 118.388362) (end 130.84055 118.468022) (width 0.125) (layer "B.Cu") (net 52))
  (segment (start 125.832224 117.876732) (end 125.891901 117.817055) (width 0.125) (layer "B.Cu") (net 52))
  (segment (start 132.967775 118.316902) (end 133.012676 118.388362) (width 0.125) (layer "B.Cu") (net 52))
  (segment (start 135.108098 118.257225) (end 135.167775 118.316902) (width 0.125) (layer "B.Cu") (net 52))
  (segment (start 130.556978 118.18445) (end 130.636638 118.212324) (width 0.125) (layer "B.Cu") (net 52))
  (segment (start 125.75 118.75) (end 125.75 118.111717) (width 0.125) (layer "B.Cu") (net 52))
  (segment (start 130.035145 118.815083) (end 130.046239 118.783379) (width 0.125) (layer "B.Cu") (net 52))
  (segment (start 127.766621 118.89624) (end 127.8 118.9) (width 0.125) (layer "B.Cu") (net 52))
  (segment (start 135.25 118.75) (end 135.25376 118.783379) (width 0.125) (layer "B.Cu") (net 52))
  (segment (start 125.156978 117.74428) (end 125.236638 117.772154) (width 0.125) (layer "B.Cu") (net 52))
  (segment (start 123.55 118.111717) (end 123.559449 118.027852) (width 0.125) (layer "B.Cu") (net 52))
  (segment (start 136.34055 118.468022) (end 136.35 118.551887) (width 0.125) (layer "B.Cu") (net 52))
  (segment (start 124.687323 117.948192) (end 124.732224 117.876732) (width 0.125) (layer "B.Cu") (net 52))
  (segment (start 124.056978 117.74428) (end 124.136638 117.772154) (width 0.125) (layer "B.Cu") (net 52))
  (segment (start 133.346239 118.783379) (end 133.35 118.75) (width 0.125) (layer "B.Cu") (net 52))
  (segment (start 127.273113 117.73483) (end 127.356978 117.74428) (width 0.125) (layer "B.Cu") (net 52))
  (segment (start 130.263361 118.212324) (end 130.343021 118.18445) (width 0.125) (layer "B.Cu") (net 52))
  (segment (start 133.064854 118.815083) (end 133.082725 118.843524) (width 0.125) (layer "B.Cu") (net 52))
  (segment (start 133.432224 118.316902) (end 133.491901 118.257225) (width 0.125) (layer "B.Cu") (net 52))
  (segment (start 127.833378 118.89624) (end 127.865082 118.885146) (width 0.125) (layer "B.Cu") (net 52))
  (segment (start 130.906476 118.867275) (end 130.934917 118.885146) (width 0.125) (layer "B.Cu") (net 52))
  (segment (start 133.293523 118.867275) (end 133.317274 118.843524) (width 0.125) (layer "B.Cu") (net 52))
  (segment (start 124.312676 117.948192) (end 124.34055 118.027852) (width 0.125) (layer "B.Cu") (net 52))
  (segment (start 131.867775 118.316902) (end 131.912676 118.388362) (width 0.125) (layer "B.Cu") (net 52))
  (segment (start 136.5 118.9) (end 137.423222 118.9) (width 0.125) (layer "B.Cu") (net 52))
  (segment (start 134.393523 118.867275) (end 134.417274 118.843524) (width 0.125) (layer "B.Cu") (net 52))
  (segment (start 135.465082 118.885146) (end 135.493523 118.867275) (width 0.125) (layer "B.Cu") (net 52))
  (segment (start 124.617274 118.843524) (end 124.635145 118.815083) (width 0.125) (layer "B.Cu") (net 52))
  (segment (start 136.434917 118.885146) (end 136.466621 118.89624) (width 0.125) (layer "B.Cu") (net 52))
  (segment (start 126.817274 118.843524) (end 126.835145 118.815083) (width 0.125) (layer "B.Cu") (net 52))
  (segment (start 133.317274 118.843524) (end 133.335145 118.815083) (width 0.125) (layer "B.Cu") (net 52))
  (segment (start 125.44055 118.027852) (end 125.45 118.111717) (width 0.125) (layer "B.Cu") (net 52))
  (segment (start 136.267775 118.316902) (end 136.312676 118.388362) (width 0.125) (layer "B.Cu") (net 52))
  (segment (start 135.973113 118.175) (end 136.056978 118.18445) (width 0.125) (layer "B.Cu") (net 52))
  (segment (start 125.482725 118.843524) (end 125.506476 118.867275) (width 0.125) (layer "B.Cu") (net 52))
  (segment (start 123.546239 118.783379) (end 123.55 118.75) (width 0.125) (layer "B.Cu") (net 52))
  (segment (start 130.636638 118.212324) (end 130.708098 118.257225) (width 0.125) (layer "B.Cu") (net 52))
  (segment (start 131 118.9) (end 131.033378 118.89624) (width 0.125) (layer "B.Cu") (net 52))
  (segment (start 127.706476 118.867275) (end 127.734917 118.885146) (width 0.125) (layer "B.Cu") (net 52))
  (segment (start 137.948222 118.375) (end 139.051777 118.375) (width 0.125) (layer "B.Cu") (net 52))
  (segment (start 130.05 118.75) (end 130.05 118.551887) (width 0.125) (layer "B.Cu") (net 52))
  (segment (start 124.646239 118.783379) (end 124.65 118.75) (width 0.125) (layer "B.Cu") (net 52))
  (segment (start 131.94055 118.468022) (end 131.95 118.551887) (width 0.125) (layer "B.Cu") (net 52))
  (segment (start 125.566621 118.89624) (end 125.6 118.9) (width 0.125) (layer "B.Cu") (net 52))
  (segment (start 125.891901 117.817055) (end 125.963361 117.772154) (width 0.125) (layer "B.Cu") (net 52))
  (segment (start 126.126886 117.73483) (end 126.173113 117.73483) (width 0.125) (layer "B.Cu") (net 52))
  (segment (start 125.534917 118.885146) (end 125.566621 118.89624) (width 0.125) (layer "B.Cu") (net 52))
  (segment (start 133.2 118.9) (end 133.233378 118.89624) (width 0.125) (layer "B.Cu") (net 52))
  (segment (start 136.208098 118.257225) (end 136.267775 118.316902) (width 0.125) (layer "B.Cu") (net 52))
  (segment (start 133.04055 118.468022) (end 133.05 118.551887) (width 0.125) (layer "B.Cu") (net 52))
  (segment (start 135.24055 118.468022) (end 135.25 118.551887) (width 0.125) (layer "B.Cu") (net 52))
  (segment (start 126.54055 118.027852) (end 126.55 118.111717) (width 0.125) (layer "B.Cu") (net 52))
  (segment (start 124.35376 118.783379) (end 124.364854 118.815083) (width 0.125) (layer "B.Cu") (net 52))
  (segment (start 127.917274 118.843524) (end 127.935145 118.815083) (width 0.125) (layer "B.Cu") (net 52))
  (segment (start 133.726886 118.175) (end 133.773113 118.175) (width 0.125) (layer "B.Cu") (net 52))
  (segment (start 125.45376 118.783379) (end 125.464854 118.815083) (width 0.125) (layer "B.Cu") (net 52))
  (segment (start 134.446239 118.783379) (end 134.45 118.75) (width 0.125) (layer "B.Cu") (net 52))
  (segment (start 126.634917 118.885146) (end 126.666621 118.89624) (width 0.125) (layer "B.Cu") (net 52))
  (segment (start 123.926886 117.73483) (end 123.973113 117.73483) (width 0.125) (layer "B.Cu") (net 52))
  (segment (start 131.033378 118.89624) (end 131.065082 118.885146) (width 0.125) (layer "B.Cu") (net 52))
  (segment (start 130.087323 118.388362) (end 130.132224 118.316902) (width 0.125) (layer "B.Cu") (net 52))
  (segment (start 134.15 118.75) (end 134.15376 118.783379) (width 0.125) (layer "B.Cu") (net 52))
  (segment (start 134.365082 118.885146) (end 134.393523 118.867275) (width 0.125) (layer "B.Cu") (net 52))
  (segment (start 131.187323 118.388362) (end 131.232224 118.316902) (width 0.125) (layer "B.Cu") (net 52))
  (segment (start 135.55 118.75) (end 135.55 118.551887) (width 0.125) (layer "B.Cu") (net 52))
  (segment (start 131.15 118.551887) (end 131.159449 118.468022) (width 0.125) (layer "B.Cu") (net 52))
  (segment (start 131.736638 118.212324) (end 131.808098 118.257225) (width 0.125) (layer "B.Cu") (net 52))
  (segment (start 135.517274 118.843524) (end 135.535145 118.815083) (width 0.125) (layer "B.Cu") (net 52))
  (segment (start 127.95 118.111717) (end 127.959449 118.027852) (width 0.125) (layer "B.Cu") (net 52))
  (segment (start 134.532224 118.316902) (end 134.591901 118.257225) (width 0.125) (layer "B.Cu") (net 52))
  (segment (start 123.124999 117.202853) (end 123.124999 118.791264) (width 0.125) (layer "B.Cu") (net 52))
  (segment (start 126.467775 117.876732) (end 126.512676 117.948192) (width 0.125) (layer "B.Cu") (net 52))
  (segment (start 124.136638 117.772154) (end 124.208098 117.817055) (width 0.125) (layer "B.Cu") (net 52))
  (segment (start 135.493523 118.867275) (end 135.517274 118.843524) (width 0.125) (layer "B.Cu") (net 52))
  (segment (start 123.362499 116.965353) (end 123.124999 117.202853) (width 0.125) (layer "B.Cu") (net 52))
  (segment (start 132.287323 118.388362) (end 132.332224 118.316902) (width 0.125) (layer "B.Cu") (net 52))
  (segment (start 135.632224 118.316902) (end 135.691901 118.257225) (width 0.125) (layer "B.Cu") (net 52))
  (segment (start 127.226886 117.73483) (end 127.273113 117.73483) (width 0.125) (layer "B.Cu") (net 52))
  (segment (start 128.326886 117.73483) (end 128.373113 117.73483) (width 0.125) (layer "B.Cu") (net 52))
  (segment (start 125.367775 117.876732) (end 125.412676 117.948192) (width 0.125) (layer "B.Cu") (net 52))
  (segment (start 125.073113 117.73483) (end 125.156978 117.74428) (width 0.125) (layer "B.Cu") (net 52))
  (segment (start 132.1 118.9) (end 132.133378 118.89624) (width 0.125) (layer "B.Cu") (net 52))
  (segment (start 128.74055 118.027852) (end 128.75 118.111717) (width 0.125) (layer "B.Cu") (net 52))
  (segment (start 126.85 118.111717) (end 126.859449 118.027852) (width 0.125) (layer "B.Cu") (net 52))
  (segment (start 124.943021 117.74428) (end 125.026886 117.73483) (width 0.125) (layer "B.Cu") (net 52))
  (segment (start 126.582725 118.843524) (end 126.606476 118.867275) (width 0.125) (layer "B.Cu") (net 52))
  (segment (start 131.363361 118.212324) (end 131.443021 118.18445) (width 0.125) (layer "B.Cu") (net 52))
  (segment (start 128.75 118.111717) (end 128.75 118.75) (width 0.125) (layer "B.Cu") (net 52))
  (segment (start 130.966621 118.89624) (end 131 118.9) (width 0.125) (layer "B.Cu") (net 52))
  (segment (start 128.373113 117.73483) (end 128.456978 117.74428) (width 0.125) (layer "B.Cu") (net 52))
  (segment (start 127.865082 118.885146) (end 127.893523 118.867275) (width 0.125) (layer "B.Cu") (net 52))
  (segment (start 124.35 118.111717) (end 124.35 118.75) (width 0.125) (layer "B.Cu") (net 52))
  (segment (start 134.182725 118.843524) (end 134.206476 118.867275) (width 0.125) (layer "B.Cu") (net 52))
  (segment (start 130.017274 118.843524) (end 130.035145 118.815083) (width 0.125) (layer "B.Cu") (net 52))
  (segment (start 124.267775 117.876732) (end 124.312676 117.948192) (width 0.125) (layer "B.Cu") (net 52))
  (segment (start 135.763361 118.212324) (end 135.843021 118.18445) (width 0.125) (layer "B.Cu") (net 52))
  (segment (start 130.426886 118.175) (end 130.473113 118.175) (width 0.125) (layer "B.Cu") (net 52))
  (segment (start 136.35376 118.783379) (end 136.364854 118.815083) (width 0.125) (layer "B.Cu") (net 52))
  (segment (start 133.773113 118.175) (end 133.856978 118.18445) (width 0.125) (layer "B.Cu") (net 52))
  (segment (start 124.364854 118.815083) (end 124.382725 118.843524) (width 0.125) (layer "B.Cu") (net 52))
  (segment (start 129.993523 118.867275) (end 130.017274 118.843524) (width 0.125) (layer "B.Cu") (net 52))
  (segment (start 127.987323 117.948192) (end 128.032224 117.876732) (width 0.125) (layer "B.Cu") (net 52))
  (segment (start 131.95 118.551887) (end 131.95 118.75) (width 0.125) (layer "B.Cu") (net 52))
  (segment (start 131.982725 118.843524) (end 132.006476 118.867275) (width 0.125) (layer "B.Cu") (net 52))
  (segment (start 125.506476 118.867275) (end 125.534917 118.885146) (width 0.125) (layer "B.Cu") (net 52))
  (segment (start 126.932224 117.876732) (end 126.991901 117.817055) (width 0.125) (layer "B.Cu") (net 52))
  (segment (start 128.764854 118.815083) (end 128.782725 118.843524) (width 0.125) (layer "B.Cu") (net 52))
  (segment (start 130.343021 118.18445) (end 130.426886 118.175) (width 0.125) (layer "B.Cu") (net 52))
  (segment (start 124.406476 118.867275) (end 124.434917 118.885146) (width 0.125) (layer "B.Cu") (net 52))
  (segment (start 136.406476 118.867275) (end 136.434917 118.885146) (width 0.125) (layer "B.Cu") (net 52))
  (segment (start 133.134917 118.885146) (end 133.166621 118.89624) (width 0.125) (layer "B.Cu") (net 52))
  (segment (start 123.465082 118.885146) (end 123.493523 118.867275) (width 0.125) (layer "B.Cu") (net 52))
  (segment (start 128.834917 118.885146) (end 128.866621 118.89624) (width 0.125) (layer "B.Cu") (net 52))
  (segment (start 134.459449 118.468022) (end 134.487323 118.388362) (width 0.125) (layer "B.Cu") (net 52))
  (segment (start 123.4 118.9) (end 123.433378 118.89624) (width 0.125) (layer "B.Cu") (net 52))
  (segment (start 141.49822 118.678557) (end 143.42045 116.756327) (width 0.125) (layer "F.Cu") (net 53))
  (segment (start 143.42045 116.756327) (end 143.756327 116.756327) (width 0.125) (layer "F.Cu") (net 53))
  (segment (start 141.57322 120.749999) (end 141.49822 120.674999) (width 0.125) (layer "F.Cu") (net 53))
  (segment (start 141.57322 121.5) (end 141.57322 120.749999) (width 0.125) (layer "F.Cu") (net 53))
  (segment (start 141.49822 120.674999) (end 141.49822 118.678557) (width 0.125) (layer "F.Cu") (net 53))
  (segment (start 125.875 117.204109) (end 125.6375 116.966609) (width 0.125) (layer "F.Cu") (net 53))
  (segment (start 125.749999 117.349853) (end 125.875 117.224852) (width 0.125) (layer "F.Cu") (net 53))
  (segment (start 125.875 117.224852) (end 125.875 117.204109) (width 0.125) (layer "F.Cu") (net 53))
  (segment (start 125.749999 118.550004) (end 125.749999 117.349853) (width 0.125) (layer "F.Cu") (net 53))
  (via (at 143.756327 116.756327) (size 0.6) (drill 0.25) (layers "F.Cu" "B.Cu") (net 53))
  (via (at 125.6375 116.966609) (size 0.6) (drill 0.25) (layers "F.Cu" "B.Cu") (net 53))
  (segment (start 125.910396 115.443301) (end 125.883961 115.367753) (width 0.125) (layer "B.Cu") (net 53))
  (segment (start 129.275 111.682666) (end 129.275 112.3) (width 0.125) (layer "B.Cu") (net 53))
  (segment (start 129.475 112.35) (end 129.486126 112.348746) (width 0.125) (layer "B.Cu") (net 53))
  (segment (start 129.506174 112.339091) (end 129.514091 112.331174) (width 0.125) (layer "B.Cu") (net 53))
  (segment (start 126.435474 115.658458) (end 126.408134 115.648892) (width 0.125) (layer "B.Cu") (net 53))
  (segment (start 125.95298 114.411072) (end 125.910396 114.343301) (width 0.125) (layer "B.Cu") (net 53))
  (segment (start 128.313873 112.348746) (end 128.325 112.35) (width 0.125) (layer "B.Cu") (net 53))
  (segment (start 130.552992 112.035021) (end 130.586668 111.981426) (width 0.125) (layer "B.Cu") (net 53))
  (segment (start 128.325 112.35) (end 128.475 112.35) (width 0.125) (layer "B.Cu") (net 53))
  (segment (start 126.480481 114.59435) (end 126.46 114.573869) (width 0.125) (layer "B.Cu") (net 53))
  (segment (start 129.114978 111.427993) (end 129.168573 111.461669) (width 0.125) (layer "B.Cu") (net 53))
  (segment (start 128.275 112.157665) (end 128.275 112.3) (width 0.125) (layer "B.Cu") (net 53))
  (segment (start 129.514091 112.331174) (end 129.520048 112.321694) (width 0.125) (layer "B.Cu") (net 53))
  (segment (start 126.152895 115.95461) (end 126.23243 115.945649) (width 0.125) (layer "B.Cu") (net 53))
  (segment (start 128.525 111.682666) (end 128.532087 111.619767) (width 0.125) (layer "B.Cu") (net 53))
  (segment (start 143.756327 114.079549) (end 143.756327 116.756327) (width 0.125) (layer "B.Cu") (net 53))
  (segment (start 128.525 112.3) (end 128.525 111.682666) (width 0.125) (layer "B.Cu") (net 53))
  (segment (start 126.379351 115.945649) (end 126.408134 115.942405) (width 0.125) (layer "B.Cu") (net 53))
  (segment (start 126.495892 114.772421) (end 126.505458 114.745081) (width 0.125) (layer "B.Cu") (net 53))
  (segment (start 130.631426 111.936668) (end 130.685021 111.902992) (width 0.125) (layer "B.Cu") (net 53))
  (segment (start 128.055233 111.882087) (end 128.114978 111.902992) (width 0.125) (layer "B.Cu") (net 53))
  (segment (start 126.23243 115.645649) (end 126.152895 115.636687) (width 0.125) (layer "B.Cu") (net 53))
  (segment (start 129.525 112.3) (end 129.525 111.682666) (width 0.125) (layer "B.Cu") (net 53))
  (segment (start 129.744766 111.407088) (end 129.807665 111.4) (width 0.125) (layer "B.Cu") (net 53))
  (segment (start 130.496694 112.345048) (end 130.506174 112.339091) (width 0.125) (layer "B.Cu") (net 53))
  (segment (start 125.95298 116.080225) (end 126.009576 116.023629) (width 0.125) (layer "B.Cu") (net 53))
  (segment (start 130.275 111.682666) (end 130.275 112.3) (width 0.125) (layer "B.Cu") (net 53))
  (segment (start 128.552992 111.560022) (end 128.586668 111.506427) (width 0.125) (layer "B.Cu") (net 53))
  (segment (start 125.910396 115.047996) (end 125.95298 114.980225) (width 0.125) (layer "B.Cu") (net 53))
  (segment (start 126.23243 114.845649) (end 126.379351 114.845649) (width 0.125) (layer "B.Cu") (net 53))
  (segment (start 126.379351 115.645649) (end 126.23243 115.645649) (width 0.125) (layer "B.Cu") (net 53))
  (segment (start 129.279951 112.321694) (end 129.285908 112.331174) (width 0.125) (layer "B.Cu") (net 53))
  (segment (start 126.505458 115.746216) (end 126.495892 115.718876) (width 0.125) (layer "B.Cu") (net 53))
  (segment (start 129.293825 112.339091) (end 129.303305 112.345048) (width 0.125) (layer "B.Cu") (net 53))
  (segment (start 129.213331 111.506427) (end 129.247007 111.560022) (width 0.125) (layer "B.Cu") (net 53))
  (segment (start 125.910396 116.147996) (end 125.95298 116.080225) (width 0.125) (layer "B.Cu") (net 53))
  (segment (start 129.586668 111.506427) (end 129.631426 111.461669) (width 0.125) (layer "B.Cu") (net 53))
  (segment (start 126.408134 115.648892) (end 126.379351 115.645649) (width 0.125) (layer "B.Cu") (net 53))
  (segment (start 130.586668 111.981426) (end 130.631426 111.936668) (width 0.125) (layer "B.Cu") (net 53))
  (segment (start 128.285908 112.331174) (end 128.293825 112.339091) (width 0.125) (layer "B.Cu") (net 53))
  (segment (start 129.325 112.35) (end 129.475 112.35) (width 0.125) (layer "B.Cu") (net 53))
  (segment (start 129.267912 111.619767) (end 129.275 111.682666) (width 0.125) (layer "B.Cu") (net 53))
  (segment (start 126.009576 114.467668) (end 125.95298 114.411072) (width 0.125) (layer "B.Cu") (net 53))
  (segment (start 129.275 112.3) (end 129.276253 112.311126) (width 0.125) (layer "B.Cu") (net 53))
  (segment (start 126.077347 115.610252) (end 126.009576 115.567668) (width 0.125) (layer "B.Cu") (net 53))
  (segment (start 125.875 113.448222) (end 127.448222 111.875) (width 0.125) (layer "B.Cu") (net 53))
  (segment (start 125.875 114.188218) (end 125.875 113.448222) (width 0.125) (layer "B.Cu") (net 53))
  (segment (start 126.505458 114.646216) (end 126.495892 114.618876) (width 0.125) (layer "B.Cu") (net 53))
  (segment (start 128.168573 111.936668) (end 128.213331 111.981426) (width 0.125) (layer "B.Cu") (net 53))
  (segment (start 128.631426 111.461669) (end 128.685021 111.427993) (width 0.125) (layer "B.Cu") (net 53))
  (segment (start 125.875 116.303079) (end 125.883961 116.223544) (width 0.125) (layer "B.Cu") (net 53))
  (segment (start 141.551778 111.875) (end 143.756327 114.079549) (width 0.125) (layer "B.Cu") (net 53))
  (segment (start 125.6375 116.966609) (end 125.875 116.729109) (width 0.125) (layer "B.Cu") (net 53))
  (segment (start 129.303305 112.345048) (end 129.313873 112.348746) (width 0.125) (layer "B.Cu") (net 53))
  (segment (start 129.523746 112.311126) (end 129.525 112.3) (width 0.125) (layer "B.Cu") (net 53))
  (segment (start 129.685021 111.427993) (end 129.744766 111.407088) (width 0.125) (layer "B.Cu") (net 53))
  (segment (start 126.480481 115.896947) (end 126.495892 115.872421) (width 0.125) (layer "B.Cu") (net 53))
  (segment (start 125.95298 114.980225) (end 126.009576 114.923629) (width 0.125) (layer "B.Cu") (net 53))
  (segment (start 129.496694 112.345048) (end 129.506174 112.339091) (width 0.125) (layer "B.Cu") (net 53))
  (segment (start 126.009576 114.923629) (end 126.077347 114.881045) (width 0.125) (layer "B.Cu") (net 53))
  (segment (start 129.247007 111.560022) (end 129.267912 111.619767) (width 0.125) (layer "B.Cu") (net 53))
  (segment (start 128.496694 112.345048) (end 128.506174 112.339091) (width 0.125) (layer "B.Cu") (net 53))
  (segment (start 130.520048 112.321694) (end 130.523746 112.311126) (width 0.125) (layer "B.Cu") (net 53))
  (segment (start 126.23243 115.945649) (end 126.379351 115.945649) (width 0.125) (layer "B.Cu") (net 53))
  (segment (start 126.435474 114.558458) (end 126.408134 114.548892) (width 0.125) (layer "B.Cu") (net 53))
  (segment (start 126.077347 114.881045) (end 126.152895 114.85461) (width 0.125) (layer "B.Cu") (net 53))
  (segment (start 126.495892 115.718876) (end 126.480481 115.69435) (width 0.125) (layer "B.Cu") (net 53))
  (segment (start 125.883961 116.223544) (end 125.910396 116.147996) (width 0.125) (layer "B.Cu") (net 53))
  (segment (start 125.910396 114.343301) (end 125.883961 114.267753) (width 0.125) (layer "B.Cu") (net 53))
  (segment (start 128.114978 111.902992) (end 128.168573 111.936668) (width 0.125) (layer "B.Cu") (net 53))
  (segment (start 130.275 112.3) (end 130.276253 112.311126) (width 0.125) (layer "B.Cu") (net 53))
  (segment (start 128.992334 111.4) (end 129.055233 111.407088) (width 0.125) (layer "B.Cu") (net 53))
  (segment (start 128.276253 112.311126) (end 128.279951 112.321694) (width 0.125) (layer "B.Cu") (net 53))
  (segment (start 130.303305 112.345048) (end 130.313873 112.348746) (width 0.125) (layer "B.Cu") (net 53))
  (segment (start 130.744766 111.882087) (end 130.807665 111.875) (width 0.125) (layer "B.Cu") (net 53))
  (segment (start 125.883961 114.267753) (end 125.875 114.188218) (width 0.125) (layer "B.Cu") (net 53))
  (segment (start 128.275 112.3) (end 128.276253 112.311126) (width 0.125) (layer "B.Cu") (net 53))
  (segment (start 126.009576 116.023629) (end 126.077347 115.981045) (width 0.125) (layer "B.Cu") (net 53))
  (segment (start 126.46 114.817428) (end 126.480481 114.796947) (width 0.125) (layer "B.Cu") (net 53))
  (segment (start 126.508702 114.675) (end 126.505458 114.646216) (width 0.125) (layer "B.Cu") (net 53))
  (segment (start 129.520048 112.321694) (end 129.523746 112.311126) (width 0.125) (layer "B.Cu") (net 53))
  (segment (start 126.505458 115.845081) (end 126.508702 115.816298) (width 0.125) (layer "B.Cu") (net 53))
  (segment (start 127.992334 111.875) (end 128.055233 111.882087) (width 0.125) (layer "B.Cu") (net 53))
  (segment (start 130.114978 111.427993) (end 130.168573 111.461669) (width 0.125) (layer "B.Cu") (net 53))
  (segment (start 129.313873 112.348746) (end 129.325 112.35) (width 0.125) (layer "B.Cu") (net 53))
  (segment (start 128.520048 112.321694) (end 128.523746 112.311126) (width 0.125) (layer "B.Cu") (net 53))
  (segment (start 125.875 115.288218) (end 125.875 115.203079) (width 0.125) (layer "B.Cu") (net 53))
  (segment (start 130.285908 112.331174) (end 130.293825 112.339091) (width 0.125) (layer "B.Cu") (net 53))
  (segment (start 128.293825 112.339091) (end 128.303305 112.345048) (width 0.125) (layer "B.Cu") (net 53))
  (segment (start 126.23243 114.545649) (end 126.152895 114.536687) (width 0.125) (layer "B.Cu") (net 53))
  (segment (start 126.495892 114.618876) (end 126.480481 114.59435) (width 0.125) (layer "B.Cu") (net 53))
  (segment (start 130.486126 112.348746) (end 130.496694 112.345048) (width 0.125) (layer "B.Cu") (net 53))
  (segment (start 128.586668 111.506427) (end 128.631426 111.461669) (width 0.125) (layer "B.Cu") (net 53))
  (segment (start 126.379351 114.845649) (end 126.408134 114.842405) (width 0.125) (layer "B.Cu") (net 53))
  (segment (start 129.552992 111.560022) (end 129.586668 111.506427) (width 0.125) (layer "B.Cu") (net 53))
  (segment (start 126.152895 115.636687) (end 126.077347 115.610252) (width 0.125) (layer "B.Cu") (net 53))
  (segment (start 130.293825 112.339091) (end 130.303305 112.345048) (width 0.125) (layer "B.Cu") (net 53))
  (segment (start 129.276253 112.311126) (end 129.279951 112.321694) (width 0.125) (layer "B.Cu") (net 53))
  (segment (start 128.514091 112.331174) (end 128.520048 112.321694) (width 0.125) (layer "B.Cu") (net 53))
  (segment (start 126.077347 115.981045) (end 126.152895 115.95461) (width 0.125) (layer "B.Cu") (net 53))
  (segment (start 130.514091 112.331174) (end 130.520048 112.321694) (width 0.125) (layer "B.Cu") (net 53))
  (segment (start 125.875 116.729109) (end 125.875 116.303079) (width 0.125) (layer "B.Cu") (net 53))
  (segment (start 126.495892 115.872421) (end 126.505458 115.845081) (width 0.125) (layer "B.Cu") (net 53))
  (segment (start 129.992334 111.4) (end 130.055233 111.407088) (width 0.125) (layer "B.Cu") (net 53))
  (segment (start 126.46 115.917428) (end 126.480481 115.896947) (width 0.125) (layer "B.Cu") (net 53))
  (segment (start 128.267912 112.094766) (end 128.275 112.157665) (width 0.125) (layer "B.Cu") (net 53))
  (segment (start 130.532087 112.094766) (end 130.552992 112.035021) (width 0.125) (layer "B.Cu") (net 53))
  (segment (start 130.247007 111.560022) (end 130.267912 111.619767) (width 0.125) (layer "B.Cu") (net 53))
  (segment (start 126.505458 114.745081) (end 126.508702 114.716298) (width 0.125) (layer "B.Cu") (net 53))
  (segment (start 130.313873 112.348746) (end 130.325 112.35) (width 0.125) (layer "B.Cu") (net 53))
  (segment (start 125.875 115.203079) (end 125.883961 115.123544) (width 0.125) (layer "B.Cu") (net 53))
  (segment (start 126.435474 114.832839) (end 126.46 114.817428) (width 0.125) (layer "B.Cu") (net 53))
  (segment (start 126.152895 114.85461) (end 126.23243 114.845649) (width 0.125) (layer "B.Cu") (net 53))
  (segment (start 126.379351 114.545649) (end 126.23243 114.545649) (width 0.125) (layer "B.Cu") (net 53))
  (segment (start 128.506174 112.339091) (end 128.514091 112.331174) (width 0.125) (layer "B.Cu") (net 53))
  (segment (start 130.267912 111.619767) (end 130.275 111.682666) (width 0.125) (layer "B.Cu") (net 53))
  (segment (start 128.475 112.35) (end 128.486126 112.348746) (width 0.125) (layer "B.Cu") (net 53))
  (segment (start 129.807665 111.4) (end 129.992334 111.4) (width 0.125) (layer "B.Cu") (net 53))
  (segment (start 130.055233 111.407088) (end 130.114978 111.427993) (width 0.125) (layer "B.Cu") (net 53))
  (segment (start 130.685021 111.902992) (end 130.744766 111.882087) (width 0.125) (layer "B.Cu") (net 53))
  (segment (start 126.508702 115.816298) (end 126.508702 115.775) (width 0.125) (layer "B.Cu") (net 53))
  (segment (start 125.95298 115.511072) (end 125.910396 115.443301) (width 0.125) (layer "B.Cu") (net 53))
  (segment (start 129.285908 112.331174) (end 129.293825 112.339091) (width 0.125) (layer "B.Cu") (net 53))
  (segment (start 126.508702 114.716298) (end 126.508702 114.675) (width 0.125) (layer "B.Cu") (net 53))
  (segment (start 126.077347 114.510252) (end 126.009576 114.467668) (width 0.125) (layer "B.Cu") (net 53))
  (segment (start 128.279951 112.321694) (end 128.285908 112.331174) (width 0.125) (layer "B.Cu") (net 53))
  (segment (start 125.883961 115.123544) (end 125.910396 115.047996) (width 0.125) (layer "B.Cu") (net 53))
  (segment (start 128.744766 111.407088) (end 128.807665 111.4) (width 0.125) (layer "B.Cu") (net 53))
  (segment (start 126.480481 114.796947) (end 126.495892 114.772421) (width 0.125) (layer "B.Cu") (net 53))
  (segment (start 129.055233 111.407088) (end 129.114978 111.427993) (width 0.125) (layer "B.Cu") (net 53))
  (segment (start 128.532087 111.619767) (end 128.552992 111.560022) (width 0.125) (layer "B.Cu") (net 53))
  (segment (start 130.475 112.35) (end 130.486126 112.348746) (width 0.125) (layer "B.Cu") (net 53))
  (segment (start 130.506174 112.339091) (end 130.514091 112.331174) (width 0.125) (layer "B.Cu") (net 53))
  (segment (start 125.883961 115.367753) (end 125.875 115.288218) (width 0.125) (layer "B.Cu") (net 53))
  (segment (start 130.523746 112.311126) (end 130.525 112.3) (width 0.125) (layer "B.Cu") (net 53))
  (segment (start 128.523746 112.311126) (end 128.525 112.3) (width 0.125) (layer "B.Cu") (net 53))
  (segment (start 126.46 115.673869) (end 126.435474 115.658458) (width 0.125) (layer "B.Cu") (net 53))
  (segment (start 130.525 112.3) (end 130.525 112.157665) (width 0.125) (layer "B.Cu") (net 53))
  (segment (start 126.152895 114.536687) (end 126.077347 114.510252) (width 0.125) (layer "B.Cu") (net 53))
  (segment (start 126.46 114.573869) (end 126.435474 114.558458) (width 0.125) (layer "B.Cu") (net 53))
  (segment (start 127.448222 111.875) (end 127.992334 111.875) (width 0.125) (layer "B.Cu") (net 53))
  (segment (start 130.279951 112.321694) (end 130.285908 112.331174) (width 0.125) (layer "B.Cu") (net 53))
  (segment (start 128.807665 111.4) (end 128.992334 111.4) (width 0.125) (layer "B.Cu") (net 53))
  (segment (start 126.408134 115.942405) (end 126.435474 115.932839) (width 0.125) (layer "B.Cu") (net 53))
  (segment (start 128.247007 112.035021) (end 128.267912 112.094766) (width 0.125) (layer "B.Cu") (net 53))
  (segment (start 126.408134 114.842405) (end 126.435474 114.832839) (width 0.125) (layer "B.Cu") (net 53))
  (segment (start 130.213331 111.506427) (end 130.247007 111.560022) (width 0.125) (layer "B.Cu") (net 53))
  (segment (start 128.213331 111.981426) (end 128.247007 112.035021) (width 0.125) (layer "B.Cu") (net 53))
  (segment (start 130.276253 112.311126) (end 130.279951 112.321694) (width 0.125) (layer "B.Cu") (net 53))
  (segment (start 126.435474 115.932839) (end 126.46 115.917428) (width 0.125) (layer "B.Cu") (net 53))
  (segment (start 129.168573 111.461669) (end 129.213331 111.506427) (width 0.125) (layer "B.Cu") (net 53))
  (segment (start 128.685021 111.427993) (end 128.744766 111.407088) (width 0.125) (layer "B.Cu") (net 53))
  (segment (start 130.525 112.157665) (end 130.532087 112.094766) (width 0.125) (layer "B.Cu") (net 53))
  (segment (start 128.303305 112.345048) (end 128.313873 112.348746) (width 0.125) (layer "B.Cu") (net 53))
  (segment (start 129.486126 112.348746) (end 129.496694 112.345048) (width 0.125) (layer "B.Cu") (net 53))
  (segment (start 130.168573 111.461669) (end 130.213331 111.506427) (width 0.125) (layer "B.Cu") (net 53))
  (segment (start 129.525 111.682666) (end 129.532087 111.619767) (width 0.125) (layer "B.Cu") (net 53))
  (segment (start 129.532087 111.619767) (end 129.552992 111.560022) (width 0.125) (layer "B.Cu") (net 53))
  (segment (start 130.325 112.35) (end 130.475 112.35) (width 0.125) (layer "B.Cu") (net 53))
  (segment (start 130.807665 111.875) (end 141.551778 111.875) (width 0.125) (layer "B.Cu") (net 53))
  (segment (start 126.508702 115.775) (end 126.505458 115.746216) (width 0.125) (layer "B.Cu") (net 53))
  (segment (start 126.408134 114.548892) (end 126.379351 114.545649) (width 0.125) (layer "B.Cu") (net 53))
  (segment (start 126.009576 115.567668) (end 125.95298 115.511072) (width 0.125) (layer "B.Cu") (net 53))
  (segment (start 128.486126 112.348746) (end 128.496694 112.345048) (width 0.125) (layer "B.Cu") (net 53))
  (segment (start 129.631426 111.461669) (end 129.685021 111.427993) (width 0.125) (layer "B.Cu") (net 53))
  (segment (start 126.480481 115.69435) (end 126.46 115.673869) (width 0.125) (layer "B.Cu") (net 53))
  (segment (start 144.743673 117.92045) (end 144.743673 118.256327) (width 0.125) (layer "F.Cu") (net 54))
  (segment (start 144.051778 117.625) (end 144.448223 117.625) (width 0.125) (layer "F.Cu") (net 54))
  (segment (start 142.29822 120.674999) (end 142.29822 119.378558) (width 0.125) (layer "F.Cu") (net 54))
  (segment (start 142.29822 119.378558) (end 144.051778 117.625) (width 0.125) (layer "F.Cu") (net 54))
  (segment (start 142.37322 120.749999) (end 142.29822 120.674999) (width 0.125) (layer "F.Cu") (net 54))
  (segment (start 144.448223 117.625) (end 144.743673 117.92045) (width 0.125) (layer "F.Cu") (net 54))
  (segment (start 142.37322 121.5) (end 142.37322 120.749999) (width 0.125) (layer "F.Cu") (net 54))
  (segment (start 124.749999 117.349853) (end 124.624999 117.224853) (width 0.125) (layer "F.Cu") (net 54))
  (segment (start 124.749999 118.550004) (end 124.749999 117.349853) (width 0.125) (layer "F.Cu") (net 54))
  (segment (start 124.624999 117.204109) (end 124.862499 116.966609) (width 0.125) (layer "F.Cu") (net 54))
  (segment (start 124.624999 117.224853) (end 124.624999 117.204109) (width 0.125) (layer "F.Cu") (net 54))
  (via (at 144.743673 118.256327) (size 0.6) (drill 0.25) (layers "F.Cu" "B.Cu") (net 54))
  (via (at 124.862499 116.966609) (size 0.6) (drill 0.25) (layers "F.Cu" "B.Cu") (net 54))
  (segment (start 144.743673 117.92045) (end 144.375 117.551777) (width 0.125) (layer "B.Cu") (net 54))
  (segment (start 124.862499 116.966609) (end 124.624999 116.729109) (width 0.125) (layer "B.Cu") (net 54))
  (segment (start 144.743673 118.256327) (end 144.743673 117.92045) (width 0.125) (layer "B.Cu") (net 54))
  (segment (start 124.624999 116.551779) (end 125.125 116.051778) (width 0.125) (layer "B.Cu") (net 54))
  (segment (start 124.624999 116.729109) (end 124.624999 116.551779) (width 0.125) (layer "B.Cu") (net 54))
  (segment (start 144.375 117.551777) (end 144.375 113.551778) (width 0.125) (layer "B.Cu") (net 54))
  (segment (start 125.125 113.051778) (end 127.051778 111.125) (width 0.125) (layer "B.Cu") (net 54))
  (segment (start 141.948222 111.125) (end 144.375 113.551778) (width 0.125) (layer "B.Cu") (net 54))
  (segment (start 125.125 116.051778) (end 125.125 113.051778) (width 0.125) (layer "B.Cu") (net 54))
  (segment (start 127.051778 111.125) (end 141.948222 111.125) (width 0.125) (layer "B.Cu") (net 54))
  (segment (start 140.69822 120.674999) (end 140.77322 120.749999) (width 0.125) (layer "F.Cu") (net 55))
  (segment (start 127.249999 118.550004) (end 127.249999 117.349853) (width 0.125) (layer "F.Cu") (net 55))
  (segment (start 127.375 117.199902) (end 127.1375 116.962402) (width 0.125) (layer "F.Cu") (net 55))
  (segment (start 141.92045 116.756327) (end 140.69822 117.978557) (width 0.125) (layer "F.Cu") (net 55))
  (segment (start 140.77322 120.749999) (end 140.77322 121.5) (width 0.125) (layer "F.Cu") (net 55))
  (segment (start 140.69822 117.978557) (end 140.69822 120.674999) (width 0.125) (layer "F.Cu") (net 55))
  (segment (start 127.249999 117.349853) (end 127.375 117.224852) (width 0.125) (layer "F.Cu") (net 55))
  (segment (start 127.375 117.224852) (end 127.375 117.199902) (width 0.125) (layer "F.Cu") (net 55))
  (segment (start 142.256327 116.756327) (end 141.92045 116.756327) (width 0.125) (layer "F.Cu") (net 55))
  (via (at 127.1375 116.962402) (size 0.6) (drill 0.25) (layers "F.Cu" "B.Cu") (net 55))
  (via (at 142.256327 116.756327) (size 0.6) (drill 0.25) (layers "F.Cu" "B.Cu") (net 55))
  (segment (start 135.995612 113.956683) (end 136 113.917742) (width 0.125) (layer "B.Cu") (net 55))
  (segment (start 133.53411 114.054562) (end 133.56182 114.026852) (width 0.125) (layer "B.Cu") (net 55))
  (segment (start 133.23996 113.186335) (end 133.25 113.275442) (width 0.125) (layer "B.Cu") (net 55))
  (segment (start 131.738664 112.885039) (end 131.823303 112.914656) (width 0.125) (layer "B.Cu") (net 55))
  (segment (start 132.054387 113.956683) (end 132.06733 113.993671) (width 0.125) (layer "B.Cu") (net 55))
  (segment (start 132.263941 114.088354) (end 132.300929 114.075411) (width 0.125) (layer "B.Cu") (net 55))
  (segment (start 134.410343 113.101696) (end 134.43996 113.186335) (width 0.125) (layer "B.Cu") (net 55))
  (segment (start 135.026696 112.914656) (end 135.111335 112.885039) (width 0.125) (layer "B.Cu") (net 55))
  (segment (start 130.810343 113.101696) (end 130.83996 113.186335) (width 0.125) (layer "B.Cu") (net 55))
  (segment (start 131.100929 113.875411) (end 131.13411 113.854562) (width 0.125) (layer "B.Cu") (net 55))
  (segment (start 134.488179 114.026852) (end 134.515889 114.054562) (width 0.125) (layer "B.Cu") (net 55))
  (segment (start 132.010343 113.101696) (end 132.03996 113.186335) (width 0.125) (layer "B.Cu") (net 55))
  (segment (start 132.711335 112.885039) (end 132.800442 112.875) (width 0.125) (layer "B.Cu") (net 55))
  (segment (start 131.025 113.892742) (end 131.063941 113.888354) (width 0.125) (layer "B.Cu") (net 55))
  (segment (start 133.099229 112.962363) (end 133.162636 113.02577) (width 0.125) (layer "B.Cu") (net 55))
  (segment (start 133.386058 114.088354) (end 133.425 114.092742) (width 0.125) (layer "B.Cu") (net 55))
  (segment (start 134.223303 112.914656) (end 134.299229 112.962363) (width 0.125) (layer "B.Cu") (net 55))
  (segment (start 142.525 116.151777) (end 142.256327 116.42045) (width 0.125) (layer "B.Cu") (net 55))
  (segment (start 131.35077 112.962363) (end 131.426696 112.914656) (width 0.125) (layer "B.Cu") (net 55))
  (segment (start 135.63996 113.186335) (end 135.65 113.275442) (width 0.125) (layer "B.Cu") (net 55))
  (segment (start 132.33411 114.054562) (end 132.36182 114.026852) (width 0.125) (layer "B.Cu") (net 55))
  (segment (start 134.362636 113.02577) (end 134.410343 113.101696) (width 0.125) (layer "B.Cu") (net 55))
  (segment (start 134.782669 113.993671) (end 134.795612 113.956683) (width 0.125) (layer "B.Cu") (net 55))
  (segment (start 133.25 113.917742) (end 133.254387 113.956683) (width 0.125) (layer "B.Cu") (net 55))
  (segment (start 134.515889 114.054562) (end 134.54907 114.075411) (width 0.125) (layer "B.Cu") (net 55))
  (segment (start 136.039656 113.101696) (end 136.087363 113.02577) (width 0.125) (layer "B.Cu") (net 55))
  (segment (start 134.8 113.275442) (end 134.810039 113.186335) (width 0.125) (layer "B.Cu") (net 55))
  (segment (start 133.595612 113.956683) (end 133.6 113.917742) (width 0.125) (layer "B.Cu") (net 55))
  (segment (start 133.25 113.275442) (end 133.25 113.917742) (width 0.125) (layer "B.Cu") (net 55))
  (segment (start 134.454387 113.956683) (end 134.46733 113.993671) (width 0.125) (layer "B.Cu") (net 55))
  (segment (start 133.162636 113.02577) (end 133.210343 113.101696) (width 0.125) (layer "B.Cu") (net 55))
  (segment (start 135.338664 112.885039) (end 135.423303 112.914656) (width 0.125) (layer "B.Cu") (net 55))
  (segment (start 130.86733 113.793671) (end 130.888179 113.826852) (width 0.125) (layer "B.Cu") (net 55))
  (segment (start 134.299229 112.962363) (end 134.362636 113.02577) (width 0.125) (layer "B.Cu") (net 55))
  (segment (start 134.000442 112.875) (end 134.049557 112.875) (width 0.125) (layer "B.Cu") (net 55))
  (segment (start 132.225 114.092742) (end 132.263941 114.088354) (width 0.125) (layer "B.Cu") (net 55))
  (segment (start 133.463941 114.088354) (end 133.500929 114.075411) (width 0.125) (layer "B.Cu") (net 55))
  (segment (start 135.111335 112.885039) (end 135.200442 112.875) (width 0.125) (layer "B.Cu") (net 55))
  (segment (start 134.76182 114.026852) (end 134.782669 113.993671) (width 0.125) (layer "B.Cu") (net 55))
  (segment (start 130.449557 112.875) (end 130.538664 112.885039) (width 0.125) (layer "B.Cu") (net 55))
  (segment (start 133.56182 114.026852) (end 133.582669 113.993671) (width 0.125) (layer "B.Cu") (net 55))
  (segment (start 133.826696 112.914656) (end 133.911335 112.885039) (width 0.125) (layer "B.Cu") (net 55))
  (segment (start 134.43996 113.186335) (end 134.45 113.275442) (width 0.125) (layer "B.Cu") (net 55))
  (segment (start 136.400442 112.875) (end 141.251778 112.875) (width 0.125) (layer "B.Cu") (net 55))
  (segment (start 135.562636 113.02577) (end 135.610343 113.101696) (width 0.125) (layer "B.Cu") (net 55))
  (segment (start 134.887363 113.02577) (end 134.95077 112.962363) (width 0.125) (layer "B.Cu") (net 55))
  (segment (start 133.315889 114.054562) (end 133.34907 114.075411) (width 0.125) (layer "B.Cu") (net 55))
  (segment (start 133.610039 113.186335) (end 133.639656 113.101696) (width 0.125) (layer "B.Cu") (net 55))
  (segment (start 131.426696 112.914656) (end 131.511335 112.885039) (width 0.125) (layer "B.Cu") (net 55))
  (segment (start 133.425 114.092742) (end 133.463941 114.088354) (width 0.125) (layer "B.Cu") (net 55))
  (segment (start 136.311335 112.885039) (end 136.400442 112.875) (width 0.125) (layer "B.Cu") (net 55))
  (segment (start 131.649557 112.875) (end 131.738664 112.885039) (width 0.125) (layer "B.Cu") (net 55))
  (segment (start 133.34907 114.075411) (end 133.386058 114.088354) (width 0.125) (layer "B.Cu") (net 55))
  (segment (start 135.66733 113.993671) (end 135.688179 114.026852) (width 0.125) (layer "B.Cu") (net 55))
  (segment (start 130.854387 113.756683) (end 130.86733 113.793671) (width 0.125) (layer "B.Cu") (net 55))
  (segment (start 135.900929 114.075411) (end 135.93411 114.054562) (width 0.125) (layer "B.Cu") (net 55))
  (segment (start 131.195612 113.756683) (end 131.2 113.717742) (width 0.125) (layer "B.Cu") (net 55))
  (segment (start 134.46733 113.993671) (end 134.488179 114.026852) (width 0.125) (layer "B.Cu") (net 55))
  (segment (start 131.511335 112.885039) (end 131.600442 112.875) (width 0.125) (layer "B.Cu") (net 55))
  (segment (start 136.15077 112.962363) (end 136.226696 112.914656) (width 0.125) (layer "B.Cu") (net 55))
  (segment (start 132.36182 114.026852) (end 132.382669 113.993671) (width 0.125) (layer "B.Cu") (net 55))
  (segment (start 135.982669 113.993671) (end 135.995612 113.956683) (width 0.125) (layer "B.Cu") (net 55))
  (segment (start 142.256327 116.42045) (end 142.256327 116.756327) (width 0.125) (layer "B.Cu") (net 55))
  (segment (start 132.300929 114.075411) (end 132.33411 114.054562) (width 0.125) (layer "B.Cu") (net 55))
  (segment (start 131.962636 113.02577) (end 132.010343 113.101696) (width 0.125) (layer "B.Cu") (net 55))
  (segment (start 131.16182 113.826852) (end 131.182669 113.793671) (width 0.125) (layer "B.Cu") (net 55))
  (segment (start 132.395612 113.956683) (end 132.4 113.917742) (width 0.125) (layer "B.Cu") (net 55))
  (segment (start 133.687363 113.02577) (end 133.75077 112.962363) (width 0.125) (layer "B.Cu") (net 55))
  (segment (start 132.849557 112.875) (end 132.938664 112.885039) (width 0.125) (layer "B.Cu") (net 55))
  (segment (start 136.226696 112.914656) (end 136.311335 112.885039) (width 0.125) (layer "B.Cu") (net 55))
  (segment (start 127.375 116.724902) (end 127.375 113.448222) (width 0.125) (layer "B.Cu") (net 55))
  (segment (start 130.915889 113.854562) (end 130.94907 113.875411) (width 0.125) (layer "B.Cu") (net 55))
  (segment (start 132.487363 113.02577) (end 132.55077 112.962363) (width 0.125) (layer "B.Cu") (net 55))
  (segment (start 132.55077 112.962363) (end 132.626696 112.914656) (width 0.125) (layer "B.Cu") (net 55))
  (segment (start 133.582669 113.993671) (end 133.595612 113.956683) (width 0.125) (layer "B.Cu") (net 55))
  (segment (start 132.05 113.275442) (end 132.05 113.917742) (width 0.125) (layer "B.Cu") (net 55))
  (segment (start 135.65 113.917742) (end 135.654387 113.956683) (width 0.125) (layer "B.Cu") (net 55))
  (segment (start 135.610343 113.101696) (end 135.63996 113.186335) (width 0.125) (layer "B.Cu") (net 55))
  (segment (start 135.423303 112.914656) (end 135.499229 112.962363) (width 0.125) (layer "B.Cu") (net 55))
  (segment (start 135.74907 114.075411) (end 135.786058 114.088354) (width 0.125) (layer "B.Cu") (net 55))
  (segment (start 134.586058 114.088354) (end 134.625 114.092742) (width 0.125) (layer "B.Cu") (net 55))
  (segment (start 135.654387 113.956683) (end 135.66733 113.993671) (width 0.125) (layer "B.Cu") (net 55))
  (segment (start 130.623303 112.914656) (end 130.699229 112.962363) (width 0.125) (layer "B.Cu") (net 55))
  (segment (start 134.8 113.917742) (end 134.8 113.275442) (width 0.125) (layer "B.Cu") (net 55))
  (segment (start 132.4 113.917742) (end 132.4 113.275442) (width 0.125) (layer "B.Cu") (net 55))
  (segment (start 135.96182 114.026852) (end 135.982669 113.993671) (width 0.125) (layer "B.Cu") (net 55))
  (segment (start 135.863941 114.088354) (end 135.900929 114.075411) (width 0.125) (layer "B.Cu") (net 55))
  (segment (start 134.663941 114.088354) (end 134.700929 114.075411) (width 0.125) (layer "B.Cu") (net 55))
  (segment (start 132.938664 112.885039) (end 133.023303 112.914656) (width 0.125) (layer "B.Cu") (net 55))
  (segment (start 135.499229 112.962363) (end 135.562636 113.02577) (width 0.125) (layer "B.Cu") (net 55))
  (segment (start 132.626696 112.914656) (end 132.711335 112.885039) (width 0.125) (layer "B.Cu") (net 55))
  (segment (start 127.948222 112.875) (end 130.449557 112.875) (width 0.125) (layer "B.Cu") (net 55))
  (segment (start 131.063941 113.888354) (end 131.100929 113.875411) (width 0.125) (layer "B.Cu") (net 55))
  (segment (start 141.251778 112.875) (end 142.525 114.148222) (width 0.125) (layer "B.Cu") (net 55))
  (segment (start 134.839656 113.101696) (end 134.887363 113.02577) (width 0.125) (layer "B.Cu") (net 55))
  (segment (start 133.210343 113.101696) (end 133.23996 113.186335) (width 0.125) (layer "B.Cu") (net 55))
  (segment (start 135.715889 114.054562) (end 135.74907 114.075411) (width 0.125) (layer "B.Cu") (net 55))
  (segment (start 134.795612 113.956683) (end 134.8 113.917742) (width 0.125) (layer "B.Cu") (net 55))
  (segment (start 131.182669 113.793671) (end 131.195612 113.756683) (width 0.125) (layer "B.Cu") (net 55))
  (segment (start 142.525 114.148222) (end 142.525 116.151777) (width 0.125) (layer "B.Cu") (net 55))
  (segment (start 131.210039 113.186335) (end 131.239656 113.101696) (width 0.125) (layer "B.Cu") (net 55))
  (segment (start 132.382669 113.993671) (end 132.395612 113.956683) (width 0.125) (layer "B.Cu") (net 55))
  (segment (start 133.023303 112.914656) (end 133.099229 112.962363) (width 0.125) (layer "B.Cu") (net 55))
  (segment (start 135.200442 112.875) (end 135.249557 112.875) (width 0.125) (layer "B.Cu") (net 55))
  (segment (start 132.186058 114.088354) (end 132.225 114.092742) (width 0.125) (layer "B.Cu") (net 55))
  (segment (start 132.03996 113.186335) (end 132.05 113.275442) (width 0.125) (layer "B.Cu") (net 55))
  (segment (start 130.85 113.717742) (end 130.854387 113.756683) (width 0.125) (layer "B.Cu") (net 55))
  (segment (start 133.6 113.917742) (end 133.6 113.275442) (width 0.125) (layer "B.Cu") (net 55))
  (segment (start 135.93411 114.054562) (end 135.96182 114.026852) (width 0.125) (layer "B.Cu") (net 55))
  (segment (start 130.986058 113.888354) (end 131.025 113.892742) (width 0.125) (layer "B.Cu") (net 55))
  (segment (start 135.688179 114.026852) (end 135.715889 114.054562) (width 0.125) (layer "B.Cu") (net 55))
  (segment (start 131.239656 113.101696) (end 131.287363 113.02577) (width 0.125) (layer "B.Cu") (net 55))
  (segment (start 135.786058 114.088354) (end 135.825 114.092742) (width 0.125) (layer "B.Cu") (net 55))
  (segment (start 130.699229 112.962363) (end 130.762636 113.02577) (width 0.125) (layer "B.Cu") (net 55))
  (segment (start 132.14907 114.075411) (end 132.186058 114.088354) (width 0.125) (layer "B.Cu") (net 55))
  (segment (start 135.249557 112.875) (end 135.338664 112.885039) (width 0.125) (layer "B.Cu") (net 55))
  (segment (start 133.6 113.275442) (end 133.610039 113.186335) (width 0.125) (layer "B.Cu") (net 55))
  (segment (start 130.538664 112.885039) (end 130.623303 112.914656) (width 0.125) (layer "B.Cu") (net 55))
  (segment (start 134.138664 112.885039) (end 134.223303 112.914656) (width 0.125) (layer "B.Cu") (net 55))
  (segment (start 136 113.275442) (end 136.010039 113.186335) (width 0.125) (layer "B.Cu") (net 55))
  (segment (start 135.825 114.092742) (end 135.863941 114.088354) (width 0.125) (layer "B.Cu") (net 55))
  (segment (start 132.800442 112.875) (end 132.849557 112.875) (width 0.125) (layer "B.Cu") (net 55))
  (segment (start 133.254387 113.956683) (end 133.26733 113.993671) (width 0.125) (layer "B.Cu") (net 55))
  (segment (start 132.05 113.917742) (end 132.054387 113.956683) (width 0.125) (layer "B.Cu") (net 55))
  (segment (start 132.115889 114.054562) (end 132.14907 114.075411) (width 0.125) (layer "B.Cu") (net 55))
  (segment (start 133.911335 112.885039) (end 134.000442 112.875) (width 0.125) (layer "B.Cu") (net 55))
  (segment (start 132.410039 113.186335) (end 132.439656 113.101696) (width 0.125) (layer "B.Cu") (net 55))
  (segment (start 130.888179 113.826852) (end 130.915889 113.854562) (width 0.125) (layer "B.Cu") (net 55))
  (segment (start 134.45 113.917742) (end 134.454387 113.956683) (width 0.125) (layer "B.Cu") (net 55))
  (segment (start 131.823303 112.914656) (end 131.899229 112.962363) (width 0.125) (layer "B.Cu") (net 55))
  (segment (start 134.625 114.092742) (end 134.663941 114.088354) (width 0.125) (layer "B.Cu") (net 55))
  (segment (start 136 113.917742) (end 136 113.275442) (width 0.125) (layer "B.Cu") (net 55))
  (segment (start 131.2 113.275442) (end 131.210039 113.186335) (width 0.125) (layer "B.Cu") (net 55))
  (segment (start 133.26733 113.993671) (end 133.288179 114.026852) (width 0.125) (layer "B.Cu") (net 55))
  (segment (start 127.375 113.448222) (end 127.948222 112.875) (width 0.125) (layer "B.Cu") (net 55))
  (segment (start 130.83996 113.186335) (end 130.85 113.275442) (width 0.125) (layer "B.Cu") (net 55))
  (segment (start 136.087363 113.02577) (end 136.15077 112.962363) (width 0.125) (layer "B.Cu") (net 55))
  (segment (start 127.1375 116.962402) (end 127.375 116.724902) (width 0.125) (layer "B.Cu") (net 55))
  (segment (start 131.899229 112.962363) (end 131.962636 113.02577) (width 0.125) (layer "B.Cu") (net 55))
  (segment (start 134.810039 113.186335) (end 134.839656 113.101696) (width 0.125) (layer "B.Cu") (net 55))
  (segment (start 133.639656 113.101696) (end 133.687363 113.02577) (width 0.125) (layer "B.Cu") (net 55))
  (segment (start 134.700929 114.075411) (end 134.73411 114.054562) (width 0.125) (layer "B.Cu") (net 55))
  (segment (start 132.439656 113.101696) (end 132.487363 113.02577) (width 0.125) (layer "B.Cu") (net 55))
  (segment (start 136.010039 113.186335) (end 136.039656 113.101696) (width 0.125) (layer "B.Cu") (net 55))
  (segment (start 134.54907 114.075411) (end 134.586058 114.088354) (width 0.125) (layer "B.Cu") (net 55))
  (segment (start 133.288179 114.026852) (end 133.315889 114.054562) (width 0.125) (layer "B.Cu") (net 55))
  (segment (start 132.06733 113.993671) (end 132.088179 114.026852) (width 0.125) (layer "B.Cu") (net 55))
  (segment (start 131.600442 112.875) (end 131.649557 112.875) (width 0.125) (layer "B.Cu") (net 55))
  (segment (start 132.4 113.275442) (end 132.410039 113.186335) (width 0.125) (layer "B.Cu") (net 55))
  (segment (start 134.95077 112.962363) (end 135.026696 112.914656) (width 0.125) (layer "B.Cu") (net 55))
  (segment (start 130.85 113.275442) (end 130.85 113.717742) (width 0.125) (layer "B.Cu") (net 55))
  (segment (start 130.762636 113.02577) (end 130.810343 113.101696) (width 0.125) (layer "B.Cu") (net 55))
  (segment (start 131.13411 113.854562) (end 131.16182 113.826852) (width 0.125) (layer "B.Cu") (net 55))
  (segment (start 131.287363 113.02577) (end 131.35077 112.962363) (width 0.125) (layer "B.Cu") (net 55))
  (segment (start 134.73411 114.054562) (end 134.76182 114.026852) (width 0.125) (layer "B.Cu") (net 55))
  (segment (start 133.75077 112.962363) (end 133.826696 112.914656) (width 0.125) (layer "B.Cu") (net 55))
  (segment (start 134.45 113.275442) (end 134.45 113.917742) (width 0.125) (layer "B.Cu") (net 55))
  (segment (start 131.2 113.717742) (end 131.2 113.275442) (width 0.125) (layer "B.Cu") (net 55))
  (segment (start 130.94907 113.875411) (end 130.986058 113.888354) (width 0.125) (layer "B.Cu") (net 55))
  (segment (start 133.500929 114.075411) (end 133.53411 114.054562) (width 0.125) (layer "B.Cu") (net 55))
  (segment (start 134.049557 112.875) (end 134.138664 112.885039) (width 0.125) (layer "B.Cu") (net 55))
  (segment (start 135.65 113.275442) (end 135.65 113.917742) (width 0.125) (layer "B.Cu") (net 55))
  (segment (start 132.088179 114.026852) (end 132.115889 114.054562) (width 0.125) (layer "B.Cu") (net 55))
  (segment (start 127.750001 118.550004) (end 127.750001 117.349853) (width 0.125) (layer "F.Cu") (net 56))
  (segment (start 127.625 117.224852) (end 127.625 117.199902) (width 0.125) (layer "F.Cu") (net 56))
  (segment (start 141.743673 116.57955) (end 140.44822 117.875003) (width 0.125) (layer "F.Cu") (net 56))
  (segment (start 127.625 117.199902) (end 127.8625 116.962402) (width 0.125) (layer "F.Cu") (net 56))
  (segment (start 127.750001 117.349853) (end 127.625 117.224852) (width 0.125) (layer "F.Cu") (net 56))
  (segment (start 141.743673 116.243673) (end 141.743673 116.57955) (width 0.125) (layer "F.Cu") (net 56))
  (segment (start 140.44822 117.875003) (end 140.44822 120.674999) (width 0.125) (layer "F.Cu") (net 56))
  (segment (start 140.37322 120.749999) (end 140.37322 121.5) (width 0.125) (layer "F.Cu") (net 56))
  (segment (start 140.44822 120.674999) (end 140.37322 120.749999) (width 0.125) (layer "F.Cu") (net 56))
  (via (at 141.743673 116.243673) (size 0.6) (drill 0.25) (layers "F.Cu" "B.Cu") (net 56))
  (via (at 127.8625 116.962402) (size 0.6) (drill 0.25) (layers "F.Cu" "B.Cu") (net 56))
  (segment (start 136.23996 114.031406) (end 136.25 113.942299) (width 0.125) (layer "B.Cu") (net 56))
  (segment (start 132.499229 114.255378) (end 132.562636 114.191971) (width 0.125) (layer "B.Cu") (net 56))
  (segment (start 133.400442 114.342742) (end 133.449557 114.342742) (width 0.125) (layer "B.Cu") (net 56))
  (segment (start 131.410343 113.916045) (end 131.43996 113.831406) (width 0.125) (layer "B.Cu") (net 56))
  (segment (start 136.386058 113.129387) (end 136.425 113.125) (width 0.125) (layer "B.Cu") (net 56))
  (segment (start 136.25 113.3) (end 136.254387 113.261058) (width 0.125) (layer "B.Cu") (net 56))
  (segment (start 132.249557 114.342742) (end 132.338664 114.332702) (width 0.125) (layer "B.Cu") (net 56))
  (segment (start 131.223303 114.103085) (end 131.299229 114.055378) (width 0.125) (layer "B.Cu") (net 56))
  (segment (start 132.026696 114.303085) (end 132.111335 114.332702) (width 0.125) (layer "B.Cu") (net 56))
  (segment (start 132.825 113.125) (end 132.863941 113.129387) (width 0.125) (layer "B.Cu") (net 56))
  (segment (start 134.899229 114.255378) (end 134.962636 114.191971) (width 0.125) (layer "B.Cu") (net 56))
  (segment (start 132.900929 113.14233) (end 132.93411 113.163179) (width 0.125) (layer "B.Cu") (net 56))
  (segment (start 134.13411 113.163179) (end 134.16182 113.190889) (width 0.125) (layer "B.Cu") (net 56))
  (segment (start 133 113.3) (end 133 113.942299) (width 0.125) (layer "B.Cu") (net 56))
  (segment (start 131.049557 114.142742) (end 131.138664 114.132702) (width 0.125) (layer "B.Cu") (net 56))
  (segment (start 134.35077 114.255378) (end 134.426696 114.303085) (width 0.125) (layer "B.Cu") (net 56))
  (segment (start 131.362636 113.991971) (end 131.410343 113.916045) (width 0.125) (layer "B.Cu") (net 56))
  (segment (start 132.654387 113.261058) (end 132.66733 113.22407) (width 0.125) (layer "B.Cu") (net 56))
  (segment (start 135.36182 113.190889) (end 135.382669 113.22407) (width 0.125) (layer "B.Cu") (net 56))
  (segment (start 135.938664 114.332702) (end 136.023303 114.303085) (width 0.125) (layer "B.Cu") (net 56))
  (segment (start 133.854387 113.261058) (end 133.86733 113.22407) (width 0.125) (layer "B.Cu") (net 56))
  (segment (start 131.299229 114.055378) (end 131.362636 113.991971) (width 0.125) (layer "B.Cu") (net 56))
  (segment (start 142.275 114.251778) (end 142.275 116.048223) (width 0.125) (layer "B.Cu") (net 56))
  (segment (start 132.423303 114.303085) (end 132.499229 114.255378) (width 0.125) (layer "B.Cu") (net 56))
  (segment (start 135.487363 114.191971) (end 135.55077 114.255378) (width 0.125) (layer "B.Cu") (net 56))
  (segment (start 135.06733 113.22407) (end 135.088179 113.190889) (width 0.125) (layer "B.Cu") (net 56))
  (segment (start 134.2 113.942299) (end 134.210039 114.031406) (width 0.125) (layer "B.Cu") (net 56))
  (segment (start 132.93411 113.163179) (end 132.96182 113.190889) (width 0.125) (layer "B.Cu") (net 56))
  (segment (start 133 113.942299) (end 133.010039 114.031406) (width 0.125) (layer "B.Cu") (net 56))
  (segment (start 131.138664 114.132702) (end 131.223303 114.103085) (width 0.125) (layer "B.Cu") (net 56))
  (segment (start 132.610343 114.116045) (end 132.63996 114.031406) (width 0.125) (layer "B.Cu") (net 56))
  (segment (start 136.26733 113.22407) (end 136.288179 113.190889) (width 0.125) (layer "B.Cu") (net 56))
  (segment (start 131.700929 113.14233) (end 131.73411 113.163179) (width 0.125) (layer "B.Cu") (net 56))
  (segment (start 136.425 113.125) (end 141.148222 113.125) (width 0.125) (layer "B.Cu") (net 56))
  (segment (start 133.986058 113.129387) (end 134.025 113.125) (width 0.125) (layer "B.Cu") (net 56))
  (segment (start 132.96182 113.190889) (end 132.982669 113.22407) (width 0.125) (layer "B.Cu") (net 56))
  (segment (start 133.915889 113.163179) (end 133.94907 113.14233) (width 0.125) (layer "B.Cu") (net 56))
  (segment (start 131.46733 113.22407) (end 131.488179 113.190889) (width 0.125) (layer "B.Cu") (net 56))
  (segment (start 130.639656 113.916045) (end 130.687363 113.991971) (width 0.125) (layer "B.Cu") (net 56))
  (segment (start 136.162636 114.191971) (end 136.210343 114.116045) (width 0.125) (layer "B.Cu") (net 56))
  (segment (start 132.65 113.3) (end 132.654387 113.261058) (width 0.125) (layer "B.Cu") (net 56))
  (segment (start 135.263941 113.129387) (end 135.300929 113.14233) (width 0.125) (layer "B.Cu") (net 56))
  (segment (start 135.439656 114.116045) (end 135.487363 114.191971) (width 0.125) (layer "B.Cu") (net 56))
  (segment (start 131.586058 113.129387) (end 131.625 113.125) (width 0.125) (layer "B.Cu") (net 56))
  (segment (start 130.56182 113.190889) (end 130.582669 113.22407) (width 0.125) (layer "B.Cu") (net 56))
  (segment (start 135.626696 114.303085) (end 135.711335 114.332702) (width 0.125) (layer "B.Cu") (net 56))
  (segment (start 132.982669 113.22407) (end 132.995612 113.261058) (width 0.125) (layer "B.Cu") (net 56))
  (segment (start 135.088179 113.190889) (end 135.115889 113.163179) (width 0.125) (layer "B.Cu") (net 56))
  (segment (start 133.15077 114.255378) (end 133.226696 114.303085) (width 0.125) (layer "B.Cu") (net 56))
  (segment (start 130.6 113.742299) (end 130.610039 113.831406) (width 0.125) (layer "B.Cu") (net 56))
  (segment (start 134.287363 114.191971) (end 134.35077 114.255378) (width 0.125) (layer "B.Cu") (net 56))
  (segment (start 131.887363 114.191971) (end 131.95077 114.255378) (width 0.125) (layer "B.Cu") (net 56))
  (segment (start 134.426696 114.303085) (end 134.511335 114.332702) (width 0.125) (layer "B.Cu") (net 56))
  (segment (start 133.86733 113.22407) (end 133.888179 113.190889) (width 0.125) (layer "B.Cu") (net 56))
  (segment (start 127.625 116.724902) (end 127.625 113.551778) (width 0.125) (layer "B.Cu") (net 56))
  (segment (start 130.582669 113.22407) (end 130.595612 113.261058) (width 0.125) (layer "B.Cu") (net 56))
  (segment (start 133.449557 114.342742) (end 133.538664 114.332702) (width 0.125) (layer "B.Cu") (net 56))
  (segment (start 142.07955 116.243673) (end 141.743673 116.243673) (width 0.125) (layer "B.Cu") (net 56))
  (segment (start 132.63996 114.031406) (end 132.65 113.942299) (width 0.125) (layer "B.Cu") (net 56))
  (segment (start 134.239656 114.116045) (end 134.287363 114.191971) (width 0.125) (layer "B.Cu") (net 56))
  (segment (start 131.43996 113.831406) (end 131.45 113.742299) (width 0.125) (layer "B.Cu") (net 56))
  (segment (start 136.315889 113.163179) (end 136.34907 113.14233) (width 0.125) (layer "B.Cu") (net 56))
  (segment (start 131.8 113.3) (end 131.8 113.942299) (width 0.125) (layer "B.Cu") (net 56))
  (segment (start 134.063941 113.129387) (end 134.100929 113.14233) (width 0.125) (layer "B.Cu") (net 56))
  (segment (start 136.25 113.942299) (end 136.25 113.3) (width 0.125) (layer "B.Cu") (net 56))
  (segment (start 132.786058 113.129387) (end 132.825 113.125) (width 0.125) (layer "B.Cu") (net 56))
  (segment (start 134.2 113.3) (end 134.2 113.942299) (width 0.125) (layer "B.Cu") (net 56))
  (segment (start 135.03996 114.031406) (end 135.05 113.942299) (width 0.125) (layer "B.Cu") (net 56))
  (segment (start 135.395612 113.261058) (end 135.4 113.3) (width 0.125) (layer "B.Cu") (net 56))
  (segment (start 133.810343 114.116045) (end 133.83996 114.031406) (width 0.125) (layer "B.Cu") (net 56))
  (segment (start 133.85 113.942299) (end 133.85 113.3) (width 0.125) (layer "B.Cu") (net 56))
  (segment (start 135.300929 113.14233) (end 135.33411 113.163179) (width 0.125) (layer "B.Cu") (net 56))
  (segment (start 134.182669 113.22407) (end 134.195612 113.261058) (width 0.125) (layer "B.Cu") (net 56))
  (segment (start 130.687363 113.991971) (end 130.75077 114.055378) (width 0.125) (layer "B.Cu") (net 56))
  (segment (start 136.099229 114.255378) (end 136.162636 114.191971) (width 0.125) (layer "B.Cu") (net 56))
  (segment (start 135.55077 114.255378) (end 135.626696 114.303085) (width 0.125) (layer "B.Cu") (net 56))
  (segment (start 134.649557 114.342742) (end 134.738664 114.332702) (width 0.125) (layer "B.Cu") (net 56))
  (segment (start 132.65 113.942299) (end 132.65 113.3) (width 0.125) (layer "B.Cu") (net 56))
  (segment (start 135.054387 113.261058) (end 135.06733 113.22407) (width 0.125) (layer "B.Cu") (net 56))
  (segment (start 135.05 113.942299) (end 135.05 113.3) (width 0.125) (layer "B.Cu") (net 56))
  (segment (start 132.111335 114.332702) (end 132.200442 114.342742) (width 0.125) (layer "B.Cu") (net 56))
  (segment (start 131.95077 114.255378) (end 132.026696 114.303085) (width 0.125) (layer "B.Cu") (net 56))
  (segment (start 135.410039 114.031406) (end 135.439656 114.116045) (width 0.125) (layer "B.Cu") (net 56))
  (segment (start 131.76182 113.190889) (end 131.782669 113.22407) (width 0.125) (layer "B.Cu") (net 56))
  (segment (start 133.087363 114.191971) (end 133.15077 114.255378) (width 0.125) (layer "B.Cu") (net 56))
  (segment (start 135.4 113.942299) (end 135.410039 114.031406) (width 0.125) (layer "B.Cu") (net 56))
  (segment (start 135.010343 114.116045) (end 135.03996 114.031406) (width 0.125) (layer "B.Cu") (net 56))
  (segment (start 135.4 113.3) (end 135.4 113.942299) (width 0.125) (layer "B.Cu") (net 56))
  (segment (start 135.800442 114.342742) (end 135.849557 114.342742) (width 0.125) (layer "B.Cu") (net 56))
  (segment (start 134.511335 114.332702) (end 134.600442 114.342742) (width 0.125) (layer "B.Cu") (net 56))
  (segment (start 131.454387 113.261058) (end 131.46733 113.22407) (width 0.125) (layer "B.Cu") (net 56))
  (segment (start 131.45 113.742299) (end 131.45 113.3) (width 0.125) (layer "B.Cu") (net 56))
  (segment (start 131.000442 114.142742) (end 131.049557 114.142742) (width 0.125) (layer "B.Cu") (net 56))
  (segment (start 131.625 113.125) (end 131.663941 113.129387) (width 0.125) (layer "B.Cu") (net 56))
  (segment (start 136.34907 113.14233) (end 136.386058 113.129387) (width 0.125) (layer "B.Cu") (net 56))
  (segment (start 130.53411 113.163179) (end 130.56182 113.190889) (width 0.125) (layer "B.Cu") (net 56))
  (segment (start 134.100929 113.14233) (end 134.13411 113.163179) (width 0.125) (layer "B.Cu") (net 56))
  (segment (start 131.8 113.942299) (end 131.810039 114.031406) (width 0.125) (layer "B.Cu") (net 56))
  (segment (start 130.911335 114.132702) (end 131.000442 114.142742) (width 0.125) (layer "B.Cu") (net 56))
  (segment (start 134.738664 114.332702) (end 134.823303 114.303085) (width 0.125) (layer "B.Cu") (net 56))
  (segment (start 131.663941 113.129387) (end 131.700929 113.14233) (width 0.125) (layer "B.Cu") (net 56))
  (segment (start 131.488179 113.190889) (end 131.515889 113.163179) (width 0.125) (layer "B.Cu") (net 56))
  (segment (start 130.6 113.3) (end 130.6 113.742299) (width 0.125) (layer "B.Cu") (net 56))
  (segment (start 133.762636 114.191971) (end 133.810343 114.116045) (width 0.125) (layer "B.Cu") (net 56))
  (segment (start 132.863941 113.129387) (end 132.900929 113.14233) (width 0.125) (layer "B.Cu") (net 56))
  (segment (start 132.995612 113.261058) (end 133 113.3) (width 0.125) (layer "B.Cu") (net 56))
  (segment (start 135.711335 114.332702) (end 135.800442 114.342742) (width 0.125) (layer "B.Cu") (net 56))
  (segment (start 135.14907 113.14233) (end 135.186058 113.129387) (width 0.125) (layer "B.Cu") (net 56))
  (segment (start 133.85 113.3) (end 133.854387 113.261058) (width 0.125) (layer "B.Cu") (net 56))
  (segment (start 133.699229 114.255378) (end 133.762636 114.191971) (width 0.125) (layer "B.Cu") (net 56))
  (segment (start 134.025 113.125) (end 134.063941 113.129387) (width 0.125) (layer "B.Cu") (net 56))
  (segment (start 132.688179 113.190889) (end 132.715889 113.163179) (width 0.125) (layer "B.Cu") (net 56))
  (segment (start 132.66733 113.22407) (end 132.688179 113.190889) (width 0.125) (layer "B.Cu") (net 56))
  (segment (start 133.311335 114.332702) (end 133.400442 114.342742) (width 0.125) (layer "B.Cu") (net 56))
  (segment (start 132.715889 113.163179) (end 132.74907 113.14233) (width 0.125) (layer "B.Cu") (net 56))
  (segment (start 131.795612 113.261058) (end 131.8 113.3) (width 0.125) (layer "B.Cu") (net 56))
  (segment (start 130.425 113.125) (end 130.463941 113.129387) (width 0.125) (layer "B.Cu") (net 56))
  (segment (start 134.210039 114.031406) (end 134.239656 114.116045) (width 0.125) (layer "B.Cu") (net 56))
  (segment (start 134.16182 113.190889) (end 134.182669 113.22407) (width 0.125) (layer "B.Cu") (net 56))
  (segment (start 141.148222 113.125) (end 142.275 114.251778) (width 0.125) (layer "B.Cu") (net 56))
  (segment (start 131.515889 113.163179) (end 131.54907 113.14233) (width 0.125) (layer "B.Cu") (net 56))
  (segment (start 133.83996 114.031406) (end 133.85 113.942299) (width 0.125) (layer "B.Cu") (net 56))
  (segment (start 134.195612 113.261058) (end 134.2 113.3) (width 0.125) (layer "B.Cu") (net 56))
  (segment (start 130.500929 113.14233) (end 130.53411 113.163179) (width 0.125) (layer "B.Cu") (net 56))
  (segment (start 135.849557 114.342742) (end 135.938664 114.332702) (width 0.125) (layer "B.Cu") (net 56))
  (segment (start 133.623303 114.303085) (end 133.699229 114.255378) (width 0.125) (layer "B.Cu") (net 56))
  (segment (start 136.254387 113.261058) (end 136.26733 113.22407) (width 0.125) (layer "B.Cu") (net 56))
  (segment (start 135.05 113.3) (end 135.054387 113.261058) (width 0.125) (layer "B.Cu") (net 56))
  (segment (start 130.463941 113.129387) (end 130.500929 113.14233) (width 0.125) (layer "B.Cu") (net 56))
  (segment (start 135.33411 113.163179) (end 135.36182 113.190889) (width 0.125) (layer "B.Cu") (net 56))
  (segment (start 132.338664 114.332702) (end 132.423303 114.303085) (width 0.125) (layer "B.Cu") (net 56))
  (segment (start 135.225 113.125) (end 135.263941 113.129387) (width 0.125) (layer "B.Cu") (net 56))
  (segment (start 133.010039 114.031406) (end 133.039656 114.116045) (width 0.125) (layer "B.Cu") (net 56))
  (segment (start 134.600442 114.342742) (end 134.649557 114.342742) (width 0.125) (layer "B.Cu") (net 56))
  (segment (start 127.625 113.551778) (end 128.051778 113.125) (width 0.125) (layer "B.Cu") (net 56))
  (segment (start 131.839656 114.116045) (end 131.887363 114.191971) (width 0.125) (layer "B.Cu") (net 56))
  (segment (start 131.45 113.3) (end 131.454387 113.261058) (width 0.125) (layer "B.Cu") (net 56))
  (segment (start 133.039656 114.116045) (end 133.087363 114.191971) (width 0.125) (layer "B.Cu") (net 56))
  (segment (start 128.051778 113.125) (end 130.425 113.125) (width 0.125) (layer "B.Cu") (net 56))
  (segment (start 133.538664 114.332702) (end 133.623303 114.303085) (width 0.125) (layer "B.Cu") (net 56))
  (segment (start 142.275 116.048223) (end 142.07955 116.243673) (width 0.125) (layer "B.Cu") (net 56))
  (segment (start 133.888179 113.190889) (end 133.915889 113.163179) (width 0.125) (layer "B.Cu") (net 56))
  (segment (start 135.115889 113.163179) (end 135.14907 113.14233) (width 0.125) (layer "B.Cu") (net 56))
  (segment (start 132.74907 113.14233) (end 132.786058 113.129387) (width 0.125) (layer "B.Cu") (net 56))
  (segment (start 127.8625 116.962402) (end 127.625 116.724902) (width 0.125) (layer "B.Cu") (net 56))
  (segment (start 130.826696 114.103085) (end 130.911335 114.132702) (width 0.125) (layer "B.Cu") (net 56))
  (segment (start 131.782669 113.22407) (end 131.795612 113.261058) (width 0.125) (layer "B.Cu") (net 56))
  (segment (start 130.610039 113.831406) (end 130.639656 113.916045) (width 0.125) (layer "B.Cu") (net 56))
  (segment (start 132.562636 114.191971) (end 132.610343 114.116045) (width 0.125) (layer "B.Cu") (net 56))
  (segment (start 132.200442 114.342742) (end 132.249557 114.342742) (width 0.125) (layer "B.Cu") (net 56))
  (segment (start 136.023303 114.303085) (end 136.099229 114.255378) (width 0.125) (layer "B.Cu") (net 56))
  (segment (start 131.810039 114.031406) (end 131.839656 114.116045) (width 0.125) (layer "B.Cu") (net 56))
  (segment (start 135.186058 113.129387) (end 135.225 113.125) (width 0.125) (layer "B.Cu") (net 56))
  (segment (start 130.75077 114.055378) (end 130.826696 114.103085) (width 0.125) (layer "B.Cu") (net 56))
  (segment (start 136.210343 114.116045) (end 136.23996 114.031406) (width 0.125) (layer "B.Cu") (net 56))
  (segment (start 130.595612 113.261058) (end 130.6 113.3) (width 0.125) (layer "B.Cu") (net 56))
  (segment (start 136.288179 113.190889) (end 136.315889 113.163179) (width 0.125) (layer "B.Cu") (net 56))
  (segment (start 134.823303 114.303085) (end 134.899229 114.255378) (width 0.125) (layer "B.Cu") (net 56))
  (segment (start 135.382669 113.22407) (end 135.395612 113.261058) (width 0.125) (layer "B.Cu") (net 56))
  (segment (start 133.226696 114.303085) (end 133.311335 114.332702) (width 0.125) (layer "B.Cu") (net 56))
  (segment (start 134.962636 114.191971) (end 135.010343 114.116045) (width 0.125) (layer "B.Cu") (net 56))
  (segment (start 133.94907 113.14233) (end 133.986058 113.129387) (width 0.125) (layer "B.Cu") (net 56))
  (segment (start 131.54907 113.14233) (end 131.586058 113.129387) (width 0.125) (layer "B.Cu") (net 56))
  (segment (start 131.73411 113.163179) (end 131.76182 113.190889) (width 0.125) (layer "B.Cu") (net 56))
  (segment (start 141.17322 120.749999) (end 141.24822 120.674999) (width 0.125) (layer "F.Cu") (net 57))
  (segment (start 141.248221 118.575002) (end 143.243673 116.57955) (width 0.125) (layer "F.Cu") (net 57))
  (segment (start 143.243673 116.57955) (end 143.243673 116.243673) (width 0.125) (layer "F.Cu") (net 57))
  (segment (start 141.17322 121.5) (end 141.17322 120.749999) (width 0.125) (layer "F.Cu") (net 57))
  (segment (start 141.24822 120.674999) (end 141.248221 118.575002) (width 0.125) (layer "F.Cu") (net 57))
  (segment (start 126.125 117.204109) (end 126.3625 116.966609) (width 0.125) (layer "F.Cu") (net 57))
  (segment (start 126.125 117.224852) (end 126.125 117.204109) (width 0.125) (layer "F.Cu") (net 57))
  (segment (start 126.250001 117.349853) (end 126.125 117.224852) (width 0.125) (layer "F.Cu") (net 57))
  (segment (start 126.250001 118.550004) (end 126.250001 117.349853) (width 0.125) (layer "F.Cu") (net 57))
  (via (at 143.243673 116.243673) (size 0.6) (drill 0.25) (layers "F.Cu" "B.Cu") (net 57))
  (via (at 126.3625 116.966609) (size 0.6) (drill 0.25) (layers "F.Cu" "B.Cu") (net 57))
  (segment (start 130.014091 111.668826) (end 130.020048 111.678306) (width 0.125) (layer "B.Cu") (net 57))
  (segment (start 129.776253 111.688874) (end 129.779951 111.678306) (width 0.125) (layer "B.Cu") (net 57))
  (segment (start 128.713331 112.493573) (end 128.747007 112.439978) (width 0.125) (layer "B.Cu") (net 57))
  (segment (start 126.680721 114.961072) (end 126.723305 114.893301) (width 0.125) (layer "B.Cu") (net 57))
  (segment (start 126.137809 114.222421) (end 126.128243 114.195081) (width 0.125) (layer "B.Cu") (net 57))
  (segment (start 126.125 113.551778) (end 127.551778 112.125) (width 0.125) (layer "B.Cu") (net 57))
  (segment (start 126.401271 115.395649) (end 126.254351 115.395649) (width 0.125) (layer "B.Cu") (net 57))
  (segment (start 126.225567 115.392405) (end 126.198227 115.382839) (width 0.125) (layer "B.Cu") (net 57))
  (segment (start 126.15322 115.346947) (end 126.137809 115.322421) (width 0.125) (layer "B.Cu") (net 57))
  (segment (start 128.813873 111.651254) (end 128.825 111.65) (width 0.125) (layer "B.Cu") (net 57))
  (segment (start 128.803305 111.654952) (end 128.813873 111.651254) (width 0.125) (layer "B.Cu") (net 57))
  (segment (start 128.555233 112.592912) (end 128.614978 112.572007) (width 0.125) (layer "B.Cu") (net 57))
  (segment (start 130.775 112.175) (end 130.776253 112.163873) (width 0.125) (layer "B.Cu") (net 57))
  (segment (start 126.254351 115.095649) (end 126.401271 115.095649) (width 0.125) (layer "B.Cu") (net 57))
  (segment (start 126.198227 115.382839) (end 126.173701 115.367428) (width 0.125) (layer "B.Cu") (net 57))
  (segment (start 129.025 111.7) (end 129.025 112.317334) (width 0.125) (layer "B.Cu") (net 57))
  (segment (start 126.556354 115.060252) (end 126.624125 115.017668) (width 0.125) (layer "B.Cu") (net 57))
  (segment (start 126.624125 115.017668) (end 126.680721 114.961072) (width 0.125) (layer "B.Cu") (net 57))
  (segment (start 126.15322 114.246947) (end 126.137809 114.222421) (width 0.125) (layer "B.Cu") (net 57))
  (segment (start 143.506327 114.183105) (end 143.506327 115.981019) (width 0.125) (layer "B.Cu") (net 57))
  (segment (start 130.813873 112.126253) (end 130.825 112.125) (width 0.125) (layer "B.Cu") (net 57))
  (segment (start 128.032087 112.380233) (end 128.052992 112.439978) (width 0.125) (layer "B.Cu") (net 57))
  (segment (start 129.713331 112.493573) (end 129.747007 112.439978) (width 0.125) (layer "B.Cu") (net 57))
  (segment (start 126.128243 115.295081) (end 126.125 115.266298) (width 0.125) (layer "B.Cu") (net 57))
  (segment (start 126.137809 115.322421) (end 126.128243 115.295081) (width 0.125) (layer "B.Cu") (net 57))
  (segment (start 130.767912 112.380233) (end 130.775 112.317334) (width 0.125) (layer "B.Cu") (net 57))
  (segment (start 126.74974 114.817753) (end 126.758702 114.738218) (width 0.125) (layer "B.Cu") (net 57))
  (segment (start 130.825 112.125) (end 141.448222 112.125) (width 0.125) (layer "B.Cu") (net 57))
  (segment (start 127.986126 112.126253) (end 127.996694 112.129951) (width 0.125) (layer "B.Cu") (net 57))
  (segment (start 126.225567 116.198892) (end 126.254351 116.195649) (width 0.125) (layer "B.Cu") (net 57))
  (segment (start 128.131426 112.538331) (end 128.185021 112.572007) (width 0.125) (layer "B.Cu") (net 57))
  (segment (start 126.723305 114.893301) (end 126.74974 114.817753) (width 0.125) (layer "B.Cu") (net 57))
  (segment (start 128.307665 112.6) (end 128.492334 112.6) (width 0.125) (layer "B.Cu") (net 57))
  (segment (start 129.775 112.317334) (end 129.775 111.7) (width 0.125) (layer "B.Cu") (net 57))
  (segment (start 130.713331 112.493573) (end 130.747007 112.439978) (width 0.125) (layer "B.Cu") (net 57))
  (segment (start 129.032087 112.380233) (end 129.052992 112.439978) (width 0.125) (layer "B.Cu") (net 57))
  (segment (start 126.254351 116.195649) (end 126.401271 116.195649) (width 0.125) (layer "B.Cu") (net 57))
  (segment (start 129.775 111.7) (end 129.776253 111.688874) (width 0.125) (layer "B.Cu") (net 57))
  (segment (start 128.668573 112.538331) (end 128.713331 112.493573) (width 0.125) (layer "B.Cu") (net 57))
  (segment (start 126.74974 115.673544) (end 126.723305 115.597996) (width 0.125) (layer "B.Cu") (net 57))
  (segment (start 129.793825 111.660909) (end 129.803305 111.654952) (width 0.125) (layer "B.Cu") (net 57))
  (segment (start 130.555233 112.592912) (end 130.614978 112.572007) (width 0.125) (layer "B.Cu") (net 57))
  (segment (start 128.020048 112.153305) (end 128.023746 112.163873) (width 0.125) (layer "B.Cu") (net 57))
  (segment (start 126.401271 115.095649) (end 126.480806 115.086687) (width 0.125) (layer "B.Cu") (net 57))
  (segment (start 128.775 112.317334) (end 128.775 111.7) (width 0.125) (layer "B.Cu") (net 57))
  (segment (start 126.680721 115.530225) (end 126.624125 115.473629) (width 0.125) (layer "B.Cu") (net 57))
  (segment (start 126.125 115.225) (end 126.128243 115.196216) (width 0.125) (layer "B.Cu") (net 57))
  (segment (start 126.758702 115.753079) (end 126.74974 115.673544) (width 0.125) (layer "B.Cu") (net 57))
  (segment (start 129.244766 112.592912) (end 129.307665 112.6) (width 0.125) (layer "B.Cu") (net 57))
  (segment (start 130.006174 111.660909) (end 130.014091 111.668826) (width 0.125) (layer "B.Cu") (net 57))
  (segment (start 130.244766 112.592912) (end 130.307665 112.6) (width 0.125) (layer "B.Cu") (net 57))
  (segment (start 126.680721 114.430225) (end 126.624125 114.373629) (width 0.125) (layer "B.Cu") (net 57))
  (segment (start 130.803305 112.129951) (end 130.813873 112.126253) (width 0.125) (layer "B.Cu") (net 57))
  (segment (start 126.128243 114.195081) (end 126.125 114.166298) (width 0.125) (layer "B.Cu") (net 57))
  (segment (start 128.775 111.7) (end 128.776253 111.688874) (width 0.125) (layer "B.Cu") (net 57))
  (segment (start 130.307665 112.6) (end 130.492334 112.6) (width 0.125) (layer "B.Cu") (net 57))
  (segment (start 128.793825 111.660909) (end 128.803305 111.654952) (width 0.125) (layer "B.Cu") (net 57))
  (segment (start 130.020048 111.678306) (end 130.023746 111.688874) (width 0.125) (layer "B.Cu") (net 57))
  (segment (start 126.254351 115.395649) (end 126.225567 115.392405) (width 0.125) (layer "B.Cu") (net 57))
  (segment (start 130.614978 112.572007) (end 130.668573 112.538331) (width 0.125) (layer "B.Cu") (net 57))
  (segment (start 128.014091 112.143825) (end 128.020048 112.153305) (width 0.125) (layer "B.Cu") (net 57))
  (segment (start 127.975 112.125) (end 127.986126 112.126253) (width 0.125) (layer "B.Cu") (net 57))
  (segment (start 128.776253 111.688874) (end 128.779951 111.678306) (width 0.125) (layer "B.Cu") (net 57))
  (segment (start 128.986126 111.651254) (end 128.996694 111.654952) (width 0.125) (layer "B.Cu") (net 57))
  (segment (start 126.758702 114.738218) (end 126.758702 114.653079) (width 0.125) (layer "B.Cu") (net 57))
  (segment (start 130.785908 112.143825) (end 130.793825 112.135908) (width 0.125) (layer "B.Cu") (net 57))
  (segment (start 129.023746 111.688874) (end 129.025 111.7) (width 0.125) (layer "B.Cu") (net 57))
  (segment (start 129.014091 111.668826) (end 129.020048 111.678306) (width 0.125) (layer "B.Cu") (net 57))
  (segment (start 126.125 116.729109) (end 126.125 116.325) (width 0.125) (layer "B.Cu") (net 57))
  (segment (start 126.556354 114.331045) (end 126.480806 114.30461) (width 0.125) (layer "B.Cu") (net 57))
  (segment (start 129.025 112.317334) (end 129.032087 112.380233) (width 0.125) (layer "B.Cu") (net 57))
  (segment (start 126.74974 114.573544) (end 126.723305 114.497996) (width 0.125) (layer "B.Cu") (net 57))
  (segment (start 126.198227 115.108458) (end 126.225567 115.098892) (width 0.125) (layer "B.Cu") (net 57))
  (segment (start 130.025 112.317334) (end 130.032087 112.380233) (width 0.125) (layer "B.Cu") (net 57))
  (segment (start 128.785908 111.668826) (end 128.793825 111.660909) (width 0.125) (layer "B.Cu") (net 57))
  (segment (start 126.125 116.325) (end 126.128243 116.296216) (width 0.125) (layer "B.Cu") (net 57))
  (segment (start 127.551778 112.125) (end 127.975 112.125) (width 0.125) (layer "B.Cu") (net 57))
  (segment (start 129.185021 112.572007) (end 129.244766 112.592912) (width 0.125) (layer "B.Cu") (net 57))
  (segment (start 129.813873 111.651254) (end 129.825 111.65) (width 0.125) (layer "B.Cu") (net 57))
  (segment (start 126.198227 114.282839) (end 126.173701 114.267428) (width 0.125) (layer "B.Cu") (net 57))
  (segment (start 126.3625 116.966609) (end 126.125 116.729109) (width 0.125) (layer "B.Cu") (net 57))
  (segment (start 126.624125 115.473629) (end 126.556354 115.431045) (width 0.125) (layer "B.Cu") (net 57))
  (segment (start 126.128243 116.296216) (end 126.137809 116.268876) (width 0.125) (layer "B.Cu") (net 57))
  (segment (start 129.986126 111.651254) (end 129.996694 111.654952) (width 0.125) (layer "B.Cu") (net 57))
  (segment (start 129.785908 111.668826) (end 129.793825 111.660909) (width 0.125) (layer "B.Cu") (net 57))
  (segment (start 126.624125 116.117668) (end 126.680721 116.061072) (width 0.125) (layer "B.Cu") (net 57))
  (segment (start 130.747007 112.439978) (end 130.767912 112.380233) (width 0.125) (layer "B.Cu") (net 57))
  (segment (start 129.020048 111.678306) (end 129.023746 111.688874) (width 0.125) (layer "B.Cu") (net 57))
  (segment (start 126.128243 115.196216) (end 126.137809 115.168876) (width 0.125) (layer "B.Cu") (net 57))
  (segment (start 129.996694 111.654952) (end 130.006174 111.660909) (width 0.125) (layer "B.Cu") (net 57))
  (segment (start 130.025 111.7) (end 130.025 112.317334) (width 0.125) (layer "B.Cu") (net 57))
  (segment (start 143.506327 115.981019) (end 143.243673 116.243673) (width 0.125) (layer "B.Cu") (net 57))
  (segment (start 130.793825 112.135908) (end 130.803305 112.129951) (width 0.125) (layer "B.Cu") (net 57))
  (segment (start 129.052992 112.439978) (end 129.086668 112.493573) (width 0.125) (layer "B.Cu") (net 57))
  (segment (start 126.480806 115.40461) (end 126.401271 115.395649) (width 0.125) (layer "B.Cu") (net 57))
  (segment (start 129.779951 111.678306) (end 129.785908 111.668826) (width 0.125) (layer "B.Cu") (net 57))
  (segment (start 128.614978 112.572007) (end 128.668573 112.538331) (width 0.125) (layer "B.Cu") (net 57))
  (segment (start 126.680721 116.061072) (end 126.723305 115.993301) (width 0.125) (layer "B.Cu") (net 57))
  (segment (start 126.723305 115.597996) (end 126.680721 115.530225) (width 0.125) (layer "B.Cu") (net 57))
  (segment (start 126.173701 115.123869) (end 126.198227 115.108458) (width 0.125) (layer "B.Cu") (net 57))
  (segment (start 130.185021 112.572007) (end 130.244766 112.592912) (width 0.125) (layer "B.Cu") (net 57))
  (segment (start 130.492334 112.6) (end 130.555233 112.592912) (width 0.125) (layer "B.Cu") (net 57))
  (segment (start 129.803305 111.654952) (end 129.813873 111.651254) (width 0.125) (layer "B.Cu") (net 57))
  (segment (start 126.480806 114.30461) (end 126.401271 114.295649) (width 0.125) (layer "B.Cu") (net 57))
  (segment (start 126.480806 115.086687) (end 126.556354 115.060252) (width 0.125) (layer "B.Cu") (net 57))
  (segment (start 130.668573 112.538331) (end 130.713331 112.493573) (width 0.125) (layer "B.Cu") (net 57))
  (segment (start 129.668573 112.538331) (end 129.713331 112.493573) (width 0.125) (layer "B.Cu") (net 57))
  (segment (start 128.052992 112.439978) (end 128.086668 112.493573) (width 0.125) (layer "B.Cu") (net 57))
  (segment (start 126.198227 116.208458) (end 126.225567 116.198892) (width 0.125) (layer "B.Cu") (net 57))
  (segment (start 130.776253 112.163873) (end 130.779951 112.153305) (width 0.125) (layer "B.Cu") (net 57))
  (segment (start 126.74974 115.917753) (end 126.758702 115.838218) (width 0.125) (layer "B.Cu") (net 57))
  (segment (start 128.747007 112.439978) (end 128.767912 112.380233) (width 0.125) (layer "B.Cu") (net 57))
  (segment (start 129.086668 112.493573) (end 129.131426 112.538331) (width 0.125) (layer "B.Cu") (net 57))
  (segment (start 126.173701 116.223869) (end 126.198227 116.208458) (width 0.125) (layer "B.Cu") (net 57))
  (segment (start 129.492334 112.6) (end 129.555233 112.592912) (width 0.125) (layer "B.Cu") (net 57))
  (segment (start 128.025 112.175) (end 128.025 112.317334) (width 0.125) (layer "B.Cu") (net 57))
  (segment (start 130.775 112.317334) (end 130.775 112.175) (width 0.125) (layer "B.Cu") (net 57))
  (segment (start 126.125 114.166298) (end 126.125 113.551778) (width 0.125) (layer "B.Cu") (net 57))
  (segment (start 129.006174 111.660909) (end 129.014091 111.668826) (width 0.125) (layer "B.Cu") (net 57))
  (segment (start 130.023746 111.688874) (end 130.025 111.7) (width 0.125) (layer "B.Cu") (net 57))
  (segment (start 129.975 111.65) (end 129.986126 111.651254) (width 0.125) (layer "B.Cu") (net 57))
  (segment (start 126.173701 114.267428) (end 126.15322 114.246947) (width 0.125) (layer "B.Cu") (net 57))
  (segment (start 128.086668 112.493573) (end 128.131426 112.538331) (width 0.125) (layer "B.Cu") (net 57))
  (segment (start 128.975 111.65) (end 128.986126 111.651254) (width 0.125) (layer "B.Cu") (net 57))
  (segment (start 128.025 112.317334) (end 128.032087 112.380233) (width 0.125) (layer "B.Cu") (net 57))
  (segment (start 126.401271 114.295649) (end 126.254351 114.295649) (width 0.125) (layer "B.Cu") (net 57))
  (segment (start 126.254351 114.295649) (end 126.225567 114.292405) (width 0.125) (layer "B.Cu") (net 57))
  (segment (start 126.173701 115.367428) (end 126.15322 115.346947) (width 0.125) (layer "B.Cu") (net 57))
  (segment (start 126.556354 115.431045) (end 126.480806 115.40461) (width 0.125) (layer "B.Cu") (net 57))
  (segment (start 126.723305 115.993301) (end 126.74974 115.917753) (width 0.125) (layer "B.Cu") (net 57))
  (segment (start 130.052992 112.439978) (end 130.086668 112.493573) (width 0.125) (layer "B.Cu") (net 57))
  (segment (start 129.555233 112.592912) (end 129.614978 112.572007) (width 0.125) (layer "B.Cu") (net 57))
  (segment (start 126.758702 114.653079) (end 126.74974 114.573544) (width 0.125) (layer "B.Cu") (net 57))
  (segment (start 126.15322 116.24435) (end 126.173701 116.223869) (width 0.125) (layer "B.Cu") (net 57))
  (segment (start 129.747007 112.439978) (end 129.767912 112.380233) (width 0.125) (layer "B.Cu") (net 57))
  (segment (start 126.137809 115.168876) (end 126.15322 115.14435) (width 0.125) (layer "B.Cu") (net 57))
  (segment (start 126.556354 116.160252) (end 126.624125 116.117668) (width 0.125) (layer "B.Cu") (net 57))
  (segment (start 126.137809 116.268876) (end 126.15322 116.24435) (width 0.125) (layer "B.Cu") (net 57))
  (segment (start 126.758702 115.838218) (end 126.758702 115.753079) (width 0.125) (layer "B.Cu") (net 57))
  (segment (start 128.996694 111.654952) (end 129.006174 111.660909) (width 0.125) (layer "B.Cu") (net 57))
  (segment (start 130.086668 112.493573) (end 130.131426 112.538331) (width 0.125) (layer "B.Cu") (net 57))
  (segment (start 128.244766 112.592912) (end 128.307665 112.6) (width 0.125) (layer "B.Cu") (net 57))
  (segment (start 128.825 111.65) (end 128.975 111.65) (width 0.125) (layer "B.Cu") (net 57))
  (segment (start 126.15322 115.14435) (end 126.173701 115.123869) (width 0.125) (layer "B.Cu") (net 57))
  (segment (start 126.480806 116.186687) (end 126.556354 116.160252) (width 0.125) (layer "B.Cu") (net 57))
  (segment (start 126.624125 114.373629) (end 126.556354 114.331045) (width 0.125) (layer "B.Cu") (net 57))
  (segment (start 128.023746 112.163873) (end 128.025 112.175) (width 0.125) (layer "B.Cu") (net 57))
  (segment (start 128.492334 112.6) (end 128.555233 112.592912) (width 0.125) (layer "B.Cu") (net 57))
  (segment (start 129.767912 112.380233) (end 129.775 112.317334) (width 0.125) (layer "B.Cu") (net 57))
  (segment (start 130.779951 112.153305) (end 130.785908 112.143825) (width 0.125) (layer "B.Cu") (net 57))
  (segment (start 126.225567 114.292405) (end 126.198227 114.282839) (width 0.125) (layer "B.Cu") (net 57))
  (segment (start 128.006174 112.135908) (end 128.014091 112.143825) (width 0.125) (layer "B.Cu") (net 57))
  (segment (start 129.614978 112.572007) (end 129.668573 112.538331) (width 0.125) (layer "B.Cu") (net 57))
  (segment (start 128.779951 111.678306) (end 128.785908 111.668826) (width 0.125) (layer "B.Cu") (net 57))
  (segment (start 129.131426 112.538331) (end 129.185021 112.572007) (width 0.125) (layer "B.Cu") (net 57))
  (segment (start 126.401271 116.195649) (end 126.480806 116.186687) (width 0.125) (layer "B.Cu") (net 57))
  (segment (start 129.825 111.65) (end 129.975 111.65) (width 0.125) (layer "B.Cu") (net 57))
  (segment (start 126.723305 114.497996) (end 126.680721 114.430225) (width 0.125) (layer "B.Cu") (net 57))
  (segment (start 128.767912 112.380233) (end 128.775 112.317334) (width 0.125) (layer "B.Cu") (net 57))
  (segment (start 126.225567 115.098892) (end 126.254351 115.095649) (width 0.125) (layer "B.Cu") (net 57))
  (segment (start 127.996694 112.129951) (end 128.006174 112.135908) (width 0.125) (layer "B.Cu") (net 57))
  (segment (start 129.307665 112.6) (end 129.492334 112.6) (width 0.125) (layer "B.Cu") (net 57))
  (segment (start 130.032087 112.380233) (end 130.052992 112.439978) (width 0.125) (layer "B.Cu") (net 57))
  (segment (start 141.448222 112.125) (end 143.506327 114.183105) (width 0.125) (layer "B.Cu") (net 57))
  (segment (start 128.185021 112.572007) (end 128.244766 112.592912) (width 0.125) (layer "B.Cu") (net 57))
  (segment (start 130.131426 112.538331) (end 130.185021 112.572007) (width 0.125) (layer "B.Cu") (net 57))
  (segment (start 126.125 115.266298) (end 126.125 115.225) (width 0.125) (layer "B.Cu") (net 57))
  (segment (start 143.948222 117.375) (end 144.551777 117.375) (width 0.125) (layer "F.Cu") (net 58))
  (segment (start 141.97322 120.749999) (end 142.04822 120.674999) (width 0.125) (layer "F.Cu") (net 58))
  (segment (start 144.551777 117.375) (end 144.92045 117.743673) (width 0.125) (layer "F.Cu") (net 58))
  (segment (start 142.04822 120.674999) (end 142.04822 119.275002) (width 0.125) (layer "F.Cu") (net 58))
  (segment (start 144.92045 117.743673) (end 145.256327 117.743673) (width 0.125) (layer "F.Cu") (net 58))
  (segment (start 142.04822 119.275002) (end 143.948222 117.375) (width 0.125) (layer "F.Cu") (net 58))
  (segment (start 141.97322 121.5) (end 141.97322 120.749999) (width 0.125) (layer "F.Cu") (net 58))
  (segment (start 124.25 117.349853) (end 124.375 117.224853) (width 0.125) (layer "F.Cu") (net 58))
  (segment (start 124.374999 117.204109) (end 124.137499 116.966609) (width 0.125) (layer "F.Cu") (net 58))
  (segment (start 124.25 118.550004) (end 124.25 117.349853) (width 0.125) (layer "F.Cu") (net 58))
  (segment (start 124.375 117.224853) (end 124.374999 117.204109) (width 0.125) (layer "F.Cu") (net 58))
  (via (at 145.256327 117.743673) (size 0.6) (drill 0.25) (layers "F.Cu" "B.Cu") (net 58))
  (via (at 124.137499 116.966609) (size 0.6) (drill 0.25) (layers "F.Cu" "B.Cu") (net 58))
  (segment (start 144.625 117.448223) (end 144.625 113.448222) (width 0.125) (layer "B.Cu") (net 58))
  (segment (start 124.875 115.948222) (end 124.875 112.948222) (width 0.125) (layer "B.Cu") (net 58))
  (segment (start 124.374999 116.729109) (end 124.374999 116.448223) (width 0.125) (layer "B.Cu") (net 58))
  (segment (start 144.92045 117.743673) (end 144.625 117.448223) (width 0.125) (layer "B.Cu") (net 58))
  (segment (start 124.875 112.948222) (end 126.948222 110.875) (width 0.125) (layer "B.Cu") (net 58))
  (segment (start 142.051778 110.875) (end 144.625 113.448222) (width 0.125) (layer "B.Cu") (net 58))
  (segment (start 124.137499 116.966609) (end 124.374999 116.729109) (width 0.125) (layer "B.Cu") (net 58))
  (segment (start 126.948222 110.875) (end 142.051778 110.875) (width 0.125) (layer "B.Cu") (net 58))
  (segment (start 145.256327 117.743673) (end 144.92045 117.743673) (width 0.125) (layer "B.Cu") (net 58))
  (segment (start 124.374999 116.448223) (end 124.875 115.948222) (width 0.125) (layer "B.Cu") (net 58))
  (segment (start 129.69498 127.09498) (end 127.23959 127.09498) (width 0.15) (layer "F.Cu") (net 59))
  (segment (start 129.877007 126.912953) (end 129.69498 127.09498) (width 0.15) (layer "F.Cu") (net 59))
  (segment (start 125.54461 125.4) (end 119.4 125.4) (width 0.15) (layer "F.Cu") (net 59))
  (segment (start 119.4 125.4) (end 119.1 125.1) (width 0.15) (layer "F.Cu") (net 59))
  (segment (start 133.238164 126.912953) (end 129.877007 126.912953) (width 0.15) (layer "F.Cu") (net 59))
  (segment (start 118.04461 122.1) (end 113.8 122.1) (width 0.15) (layer "F.Cu") (net 59))
  (segment (start 112.75 121.05) (end 112.75 118.55) (width 0.15) (layer "F.Cu") (net 59))
  (segment (start 119.1 125.1) (end 119.1 123.15539) (width 0.15) (layer "F.Cu") (net 59))
  (segment (start 119.1 123.15539) (end 118.04461 122.1) (width 0.15) (layer "F.Cu") (net 59))
  (segment (start 127.23959 127.09498) (end 125.54461 125.4) (width 0.15) (layer "F.Cu") (net 59))
  (segment (start 113.8 122.1) (end 112.75 121.05) (width 0.15) (layer "F.Cu") (net 59))
  (segment (start 118.82499 125.213912) (end 118.82499 123.269302) (width 0.15) (layer "F.Cu") (net 60))
  (segment (start 113.686088 122.37501) (end 112.25 120.938922) (width 0.15) (layer "F.Cu") (net 60))
  (segment (start 131.347046 127.747046) (end 131.347046 127.347046) (width 0.15) (layer "F.Cu") (net 60))
  (segment (start 117.930698 122.37501) (end 113.686088 122.37501) (width 0.15) (layer "F.Cu") (net 60))
  (segment (start 112.25 120.938922) (end 112.25 118.55) (width 0.15) (layer "F.Cu") (net 60))
  (segment (start 125.430698 125.67501) (end 119.286088 125.67501) (width 0.15) (layer "F.Cu") (net 60))
  (segment (start 118.82499 123.269302) (end 117.930698 122.37501) (width 0.15) (layer "F.Cu") (net 60))
  (segment (start 132.588163 127.912954) (end 131.512954 127.912954) (width 0.15) (layer "F.Cu") (net 60))
  (segment (start 131.512954 127.912954) (end 131.347046 127.747046) (width 0.15) (layer "F.Cu") (net 60))
  (segment (start 132.788164 127.712953) (end 132.588163 127.912954) (width 0.15) (layer "F.Cu") (net 60))
  (segment (start 129.93001 127.36999) (end 127.125678 127.36999) (width 0.15) (layer "F.Cu") (net 60))
  (segment (start 127.125678 127.36999) (end 125.430698 125.67501) (width 0.15) (layer "F.Cu") (net 60))
  (segment (start 130.1 127.2) (end 129.93001 127.36999) (width 0.15) (layer "F.Cu") (net 60))
  (segment (start 119.286088 125.67501) (end 118.82499 125.213912) (width 0.15) (layer "F.Cu") (net 60))
  (segment (start 131.347046 127.347046) (end 131.2 127.2) (width 0.15) (layer "F.Cu") (net 60))
  (segment (start 131.2 127.2) (end 130.1 127.2) (width 0.15) (layer "F.Cu") (net 60))
  (segment (start 133.238164 127.712953) (end 132.788164 127.712953) (width 0.15) (layer "F.Cu") (net 60))
  (segment (start 129.445 127.645) (end 127.011766 127.645) (width 0.15) (layer "F.Cu") (net 61))
  (segment (start 130.5 127.8) (end 130.267953 127.645) (width 0.15) (layer "F.Cu") (net 61))
  (segment (start 132.4 127.312953) (end 132.3 127.412953) (width 0.15) (layer "F.Cu") (net 61))
  (segment (start 130.267953 127.645) (end 129.445 127.645) (width 0.15) (layer "F.Cu") (net 61))
  (segment (start 118.54998 125.327824) (end 118.54998 123.383214) (width 0.15) (layer "F.Cu") (net 61))
  (segment (start 133.238164 127.312953) (end 132.4 127.312953) (width 0.15) (layer "F.Cu") (net 61))
  (segment (start 117.816786 122.65002) (end 113.572176 122.65002) (width 0.15) (layer "F.Cu") (net 61))
  (segment (start 118.54998 123.383214) (end 117.816786 122.65002) (width 0.15) (layer "F.Cu") (net 61))
  (segment (start 113.572176 122.65002) (end 111.75 120.827844) (width 0.15) (layer "F.Cu") (net 61))
  (segment (start 111.75 120.827844) (end 111.75 118.55) (width 0.15) (layer "F.Cu") (net 61))
  (segment (start 127.011766 127.645) (end 125.316786 125.95002) (width 0.15) (layer "F.Cu") (net 61))
  (segment (start 125.316786 125.95002) (end 119.172176 125.95002) (width 0.15) (layer "F.Cu") (net 61))
  (segment (start 119.172176 125.95002) (end 118.54998 125.327824) (width 0.15) (layer "F.Cu") (net 61))
  (via (at 132.3 127.412953) (size 0.6) (drill 0.25) (layers "F.Cu" "B.Cu") (net 61))
  (via (at 130.5 127.8) (size 0.6) (drill 0.25) (layers "F.Cu" "B.Cu") (net 61))
  (segment (start 131.912953 127.8) (end 132.3 127.412953) (width 0.15) (layer "B.Cu") (net 61))
  (segment (start 130.5 127.8) (end 131.912953 127.8) (width 0.15) (layer "B.Cu") (net 61))
  (segment (start 117.702874 122.92503) (end 113.458264 122.92503) (width 0.15) (layer "F.Cu") (net 62))
  (segment (start 129.880008 127.92001) (end 126.897854 127.92001) (width 0.15) (layer "F.Cu") (net 62))
  (segment (start 130.259999 128.300001) (end 129.880008 127.92001) (width 0.15) (layer "F.Cu") (net 62))
  (segment (start 119.058264 126.22503) (end 118.27497 125.441736) (width 0.15) (layer "F.Cu") (net 62))
  (segment (start 126.897854 127.92001) (end 125.202874 126.22503) (width 0.15) (layer "F.Cu") (net 62))
  (segment (start 118.27497 123.497126) (end 117.702874 122.92503) (width 0.15) (layer "F.Cu") (net 62))
  (segment (start 132.590038 128.300001) (end 130.259999 128.300001) (width 0.15) (layer "F.Cu") (net 62))
  (segment (start 113.458264 122.92503) (end 110.75 120.216766) (width 0.15) (layer "F.Cu") (net 62))
  (segment (start 133.238164 128.112953) (end 132.777086 128.112953) (width 0.15) (layer "F.Cu") (net 62))
  (segment (start 132.777086 128.112953) (end 132.590038 128.300001) (width 0.15) (layer "F.Cu") (net 62))
  (segment (start 118.27497 125.441736) (end 118.27497 123.497126) (width 0.15) (layer "F.Cu") (net 62))
  (segment (start 125.202874 126.22503) (end 119.058264 126.22503) (width 0.15) (layer "F.Cu") (net 62))
  (segment (start 110.75 120.216766) (end 110.75 118.55) (width 0.15) (layer "F.Cu") (net 62))
  (segment (start 63.5 137.43) (end 62.31 136.24) (width 0.25) (layer "B.Cu") (net 63))
  (segment (start 62.31 134.97) (end 63.58 133.7) (width 0.25) (layer "B.Cu") (net 63))
  (segment (start 63.5 138.415) (end 63.5 137.43) (width 0.25) (layer "B.Cu") (net 63))
  (segment (start 62.31 136.24) (end 62.31 134.97) (width 0.25) (layer "B.Cu") (net 63))
  (segment (start 101.25 119.750001) (end 101.36 119.860001) (width 0.155) (layer "F.Cu") (net 64))
  (segment (start 101.25 118.55) (end 101.25 119.750001) (width 0.155) (layer "F.Cu") (net 64))
  (segment (start 101.36 120.228578) (end 100.687689 120.900889) (width 0.155) (layer "F.Cu") (net 64))
  (segment (start 100.687689 120.900889) (end 100.373025 120.900889) (width 0.155) (layer "F.Cu") (net 64))
  (segment (start 101.36 119.860001) (end 101.36 120.228578) (width 0.155) (layer "F.Cu") (net 64))
  (via (at 100.373025 120.900889) (size 0.6) (drill 0.25) (layers "F.Cu" "B.Cu") (net 64))
  (segment (start 98.757661 126.814575) (end 98.757661 126.865424) (width 0.155) (layer "B.Cu") (net 64))
  (segment (start 98.913752 126.490447) (end 98.848108 126.556091) (width 0.155) (layer "B.Cu") (net 64))
  (segment (start 98.992358 126.038944) (end 99.079984 126.069605) (width 0.155) (layer "B.Cu") (net 64))
  (segment (start 100.902098 124.914906) (end 100.927433 124.940241) (width 0.155) (layer "B.Cu") (net 64))
  (segment (start 99.7 128.48) (end 99.735603 128.484011) (width 0.155) (layer "B.Cu") (net 64))
  (segment (start 100.958328 127.475603) (end 100.946495 127.509421) (width 0.155) (layer "B.Cu") (net 64))
  (segment (start 98.992358 126.441055) (end 98.913752 126.490447) (width 0.155) (layer "B.Cu") (net 64))
  (segment (start 99.86 123.84) (end 99.855988 123.875603) (width 0.155) (layer "B.Cu") (net 64))
  (segment (start 100.802339 125.2) (end 99.172236 125.2) (width 0.155) (layer "B.Cu") (net 64))
  (segment (start 99.079984 124.869605) (end 99.172236 124.88) (width 0.155) (layer "B.Cu") (net 64))
  (segment (start 99.172236 127.6) (end 99.079984 127.610394) (width 0.155) (layer "B.Cu") (net 64))
  (segment (start 100.871761 127.584155) (end 100.837943 127.595988) (width 0.155) (layer "B.Cu") (net 64))
  (segment (start 100.373025 121.215553) (end 99.86 121.728578) (width 0.155) (layer "B.Cu") (net 64))
  (segment (start 99.079984 126.410394) (end 98.992358 126.441055) (width 0.155) (layer "B.Cu") (net 64))
  (segment (start 98.757661 124.465424) (end 98.768055 124.557676) (width 0.155) (layer "B.Cu") (net 64))
  (segment (start 100.802339 127.28) (end 100.837943 127.284011) (width 0.155) (layer "B.Cu") (net 64))
  (segment (start 100.902098 126.365093) (end 100.871761 126.384155) (width 0.155) (layer "B.Cu") (net 64))
  (segment (start 98.768055 126.722323) (end 98.757661 126.814575) (width 0.155) (layer "B.Cu") (net 64))
  (segment (start 100.927433 125.139758) (end 100.902098 125.165093) (width 0.155) (layer "B.Cu") (net 64))
  (segment (start 98.913752 124.789552) (end 98.992358 124.838944) (width 0.155) (layer "B.Cu") (net 64))
  (segment (start 100.802339 124.88) (end 100.837943 124.884011) (width 0.155) (layer "B.Cu") (net 64))
  (segment (start 100.837943 126.395988) (end 100.802339 126.4) (width 0.155) (layer "B.Cu") (net 64))
  (segment (start 100.962339 126.24) (end 100.958328 126.275603) (width 0.155) (layer "B.Cu") (net 64))
  (segment (start 100.958328 126.275603) (end 100.946495 126.309421) (width 0.155) (layer "B.Cu") (net 64))
  (segment (start 98.848108 124.156091) (end 98.798716 124.234697) (width 0.155) (layer "B.Cu") (net 64))
  (segment (start 98.992358 127.238944) (end 99.079984 127.269605) (width 0.155) (layer "B.Cu") (net 64))
  (segment (start 100.902098 125.165093) (end 100.871761 125.184155) (width 0.155) (layer "B.Cu") (net 64))
  (segment (start 100.802339 127.6) (end 99.172236 127.6) (width 0.155) (layer "B.Cu") (net 64))
  (segment (start 98.757661 128.065424) (end 98.768055 128.157676) (width 0.155) (layer "B.Cu") (net 64))
  (segment (start 98.913752 127.189552) (end 98.992358 127.238944) (width 0.155) (layer "B.Cu") (net 64))
  (segment (start 99.799758 123.965093) (end 99.769421 123.984155) (width 0.155) (layer "B.Cu") (net 64))
  (segment (start 100.927433 127.340241) (end 100.946495 127.370578) (width 0.155) (layer "B.Cu") (net 64))
  (segment (start 98.848108 128.323908) (end 98.913752 128.389552) (width 0.155) (layer "B.Cu") (net 64))
  (segment (start 98.913752 124.090447) (end 98.848108 124.156091) (width 0.155) (layer "B.Cu") (net 64))
  (segment (start 99.7 124) (end 99.172236 124) (width 0.155) (layer "B.Cu") (net 64))
  (segment (start 99.844155 128.570578) (end 99.855988 128.604396) (width 0.155) (layer "B.Cu") (net 64))
  (segment (start 98.798716 126.634697) (end 98.768055 126.722323) (width 0.155) (layer "B.Cu") (net 64))
  (segment (start 98.798716 127.834697) (end 98.768055 127.922323) (width 0.155) (layer "B.Cu") (net 64))
  (segment (start 99.86 121.728578) (end 99.86 123.84) (width 0.155) (layer "B.Cu") (net 64))
  (segment (start 98.798716 124.234697) (end 98.768055 124.322323) (width 0.155) (layer "B.Cu") (net 64))
  (segment (start 99.172236 124) (end 99.079984 124.010394) (width 0.155) (layer "B.Cu") (net 64))
  (segment (start 99.172236 125.2) (end 99.079984 125.210394) (width 0.155) (layer "B.Cu") (net 64))
  (segment (start 98.992358 128.438944) (end 99.079984 128.469605) (width 0.155) (layer "B.Cu") (net 64))
  (segment (start 100.871761 126.095844) (end 100.902098 126.114906) (width 0.155) (layer "B.Cu") (net 64))
  (segment (start 99.172236 128.48) (end 99.7 128.48) (width 0.155) (layer "B.Cu") (net 64))
  (segment (start 99.172236 126.08) (end 100.802339 126.08) (width 0.155) (layer "B.Cu") (net 64))
  (segment (start 100.902098 127.565093) (end 100.871761 127.584155) (width 0.155) (layer "B.Cu") (net 64))
  (segment (start 98.757661 124.414575) (end 98.757661 124.465424) (width 0.155) (layer "B.Cu") (net 64))
  (segment (start 99.079984 128.469605) (end 99.172236 128.48) (width 0.155) (layer "B.Cu") (net 64))
  (segment (start 100.837943 127.284011) (end 100.871761 127.295844) (width 0.155) (layer "B.Cu") (net 64))
  (segment (start 100.946495 127.370578) (end 100.958328 127.404396) (width 0.155) (layer "B.Cu") (net 64))
  (segment (start 98.848108 127.123908) (end 98.913752 127.189552) (width 0.155) (layer "B.Cu") (net 64))
  (segment (start 99.799758 128.514906) (end 99.825093 128.540241) (width 0.155) (layer "B.Cu") (net 64))
  (segment (start 99.769421 128.495844) (end 99.799758 128.514906) (width 0.155) (layer "B.Cu") (net 64))
  (segment (start 98.913752 127.690447) (end 98.848108 127.756091) (width 0.155) (layer "B.Cu") (net 64))
  (segment (start 98.992358 125.241055) (end 98.913752 125.290447) (width 0.155) (layer "B.Cu") (net 64))
  (segment (start 98.768055 125.522323) (end 98.757661 125.614575) (width 0.155) (layer "B.Cu") (net 64))
  (segment (start 98.848108 125.356091) (end 98.798716 125.434697) (width 0.155) (layer "B.Cu") (net 64))
  (segment (start 98.848108 125.923908) (end 98.913752 125.989552) (width 0.155) (layer "B.Cu") (net 64))
  (segment (start 100.871761 124.895844) (end 100.902098 124.914906) (width 0.155) (layer "B.Cu") (net 64))
  (segment (start 100.946495 124.970578) (end 100.958328 125.004396) (width 0.155) (layer "B.Cu") (net 64))
  (segment (start 100.927433 127.539758) (end 100.902098 127.565093) (width 0.155) (layer "B.Cu") (net 64))
  (segment (start 100.802339 126.08) (end 100.837943 126.084011) (width 0.155) (layer "B.Cu") (net 64))
  (segment (start 98.757661 125.614575) (end 98.757661 125.665424) (width 0.155) (layer "B.Cu") (net 64))
  (segment (start 100.902098 127.314906) (end 100.927433 127.340241) (width 0.155) (layer "B.Cu") (net 64))
  (segment (start 98.913752 125.989552) (end 98.992358 126.038944) (width 0.155) (layer "B.Cu") (net 64))
  (segment (start 98.848108 126.556091) (end 98.798716 126.634697) (width 0.155) (layer "B.Cu") (net 64))
  (segment (start 100.962339 127.44) (end 100.958328 127.475603) (width 0.155) (layer "B.Cu") (net 64))
  (segment (start 100.902098 126.114906) (end 100.927433 126.140241) (width 0.155) (layer "B.Cu") (net 64))
  (segment (start 100.958328 126.204396) (end 100.962339 126.24) (width 0.155) (layer "B.Cu") (net 64))
  (segment (start 100.927433 126.140241) (end 100.946495 126.170578) (width 0.155) (layer "B.Cu") (net 64))
  (segment (start 100.958328 125.004396) (end 100.962339 125.04) (width 0.155) (layer "B.Cu") (net 64))
  (segment (start 100.927433 124.940241) (end 100.946495 124.970578) (width 0.155) (layer "B.Cu") (net 64))
  (segment (start 99.86 137.255) (end 99.5 137.615) (width 0.155) (layer "B.Cu") (net 64))
  (segment (start 98.848108 124.723908) (end 98.913752 124.789552) (width 0.155) (layer "B.Cu") (net 64))
  (segment (start 99.079984 127.610394) (end 98.992358 127.641055) (width 0.155) (layer "B.Cu") (net 64))
  (segment (start 100.958328 127.404396) (end 100.962339 127.44) (width 0.155) (layer "B.Cu") (net 64))
  (segment (start 99.855988 123.875603) (end 99.844155 123.909421) (width 0.155) (layer "B.Cu") (net 64))
  (segment (start 99.079984 127.269605) (end 99.172236 127.28) (width 0.155) (layer "B.Cu") (net 64))
  (segment (start 99.735603 123.995988) (end 99.7 124) (width 0.155) (layer "B.Cu") (net 64))
  (segment (start 100.871761 127.295844) (end 100.902098 127.314906) (width 0.155) (layer "B.Cu") (net 64))
  (segment (start 98.757661 126.865424) (end 98.768055 126.957676) (width 0.155) (layer "B.Cu") (net 64))
  (segment (start 98.913752 128.389552) (end 98.992358 128.438944) (width 0.155) (layer "B.Cu") (net 64))
  (segment (start 99.172236 127.28) (end 100.802339 127.28) (width 0.155) (layer "B.Cu") (net 64))
  (segment (start 100.837943 126.084011) (end 100.871761 126.095844) (width 0.155) (layer "B.Cu") (net 64))
  (segment (start 100.958328 125.075603) (end 100.946495 125.109421) (width 0.155) (layer "B.Cu") (net 64))
  (segment (start 98.768055 125.757676) (end 98.798716 125.845302) (width 0.155) (layer "B.Cu") (net 64))
  (segment (start 98.848108 127.756091) (end 98.798716 127.834697) (width 0.155) (layer "B.Cu") (net 64))
  (segment (start 98.798716 124.645302) (end 98.848108 124.723908) (width 0.155) (layer "B.Cu") (net 64))
  (segment (start 100.927433 126.339758) (end 100.902098 126.365093) (width 0.155) (layer "B.Cu") (net 64))
  (segment (start 98.798716 128.245302) (end 98.848108 128.323908) (width 0.155) (layer "B.Cu") (net 64))
  (segment (start 98.798716 125.845302) (end 98.848108 125.923908) (width 0.155) (layer "B.Cu") (net 64))
  (segment (start 99.86 128.64) (end 99.86 137.255) (width 0.155) (layer "B.Cu") (net 64))
  (segment (start 99.855988 128.604396) (end 99.86 128.64) (width 0.155) (layer "B.Cu") (net 64))
  (segment (start 99.825093 123.939758) (end 99.799758 123.965093) (width 0.155) (layer "B.Cu") (net 64))
  (segment (start 100.373025 120.900889) (end 100.373025 121.215553) (width 0.155) (layer "B.Cu") (net 64))
  (segment (start 99.844155 123.909421) (end 99.825093 123.939758) (width 0.155) (layer "B.Cu") (net 64))
  (segment (start 99.172236 124.88) (end 100.802339 124.88) (width 0.155) (layer "B.Cu") (net 64))
  (segment (start 99.825093 128.540241) (end 99.844155 128.570578) (width 0.155) (layer "B.Cu") (net 64))
  (segment (start 100.871761 126.384155) (end 100.837943 126.395988) (width 0.155) (layer "B.Cu") (net 64))
  (segment (start 98.992358 127.641055) (end 98.913752 127.690447) (width 0.155) (layer "B.Cu") (net 64))
  (segment (start 98.798716 125.434697) (end 98.768055 125.522323) (width 0.155) (layer "B.Cu") (net 64))
  (segment (start 98.768055 128.157676) (end 98.798716 128.245302) (width 0.155) (layer "B.Cu") (net 64))
  (segment (start 100.946495 126.309421) (end 100.927433 126.339758) (width 0.155) (layer "B.Cu") (net 64))
  (segment (start 98.768055 126.957676) (end 98.798716 127.045302) (width 0.155) (layer "B.Cu") (net 64))
  (segment (start 99.735603 128.484011) (end 99.769421 128.495844) (width 0.155) (layer "B.Cu") (net 64))
  (segment (start 98.992358 124.838944) (end 99.079984 124.869605) (width 0.155) (layer "B.Cu") (net 64))
  (segment (start 100.837943 124.884011) (end 100.871761 124.895844) (width 0.155) (layer "B.Cu") (net 64))
  (segment (start 100.946495 126.170578) (end 100.958328 126.204396) (width 0.155) (layer "B.Cu") (net 64))
  (segment (start 98.757661 128.014575) (end 98.757661 128.065424) (width 0.155) (layer "B.Cu") (net 64))
  (segment (start 99.079984 125.210394) (end 98.992358 125.241055) (width 0.155) (layer "B.Cu") (net 64))
  (segment (start 98.798716 127.045302) (end 98.848108 127.123908) (width 0.155) (layer "B.Cu") (net 64))
  (segment (start 98.757661 125.665424) (end 98.768055 125.757676) (width 0.155) (layer "B.Cu") (net 64))
  (segment (start 100.946495 127.509421) (end 100.927433 127.539758) (width 0.155) (layer "B.Cu") (net 64))
  (segment (start 98.913752 125.290447) (end 98.848108 125.356091) (width 0.155) (layer "B.Cu") (net 64))
  (segment (start 100.837943 125.195988) (end 100.802339 125.2) (width 0.155) (layer "B.Cu") (net 64))
  (segment (start 99.079984 124.010394) (end 98.992358 124.041055) (width 0.155) (layer "B.Cu") (net 64))
  (segment (start 98.768055 127.922323) (end 98.757661 128.014575) (width 0.155) (layer "B.Cu") (net 64))
  (segment (start 99.172236 126.4) (end 99.079984 126.410394) (width 0.155) (layer "B.Cu") (net 64))
  (segment (start 100.837943 127.595988) (end 100.802339 127.6) (width 0.155) (layer "B.Cu") (net 64))
  (segment (start 99.769421 123.984155) (end 99.735603 123.995988) (width 0.155) (layer "B.Cu") (net 64))
  (segment (start 100.871761 125.184155) (end 100.837943 125.195988) (width 0.155) (layer "B.Cu") (net 64))
  (segment (start 100.946495 125.109421) (end 100.927433 125.139758) (width 0.155) (layer "B.Cu") (net 64))
  (segment (start 100.802339 126.4) (end 99.172236 126.4) (width 0.155) (layer "B.Cu") (net 64))
  (segment (start 98.992358 124.041055) (end 98.913752 124.090447) (width 0.155) (layer "B.Cu") (net 64))
  (segment (start 98.768055 124.322323) (end 98.757661 124.414575) (width 0.155) (layer "B.Cu") (net 64))
  (segment (start 99.079984 126.069605) (end 99.172236 126.08) (width 0.155) (layer "B.Cu") (net 64))
  (segment (start 100.962339 125.04) (end 100.958328 125.075603) (width 0.155) (layer "B.Cu") (net 64))
  (segment (start 98.768055 124.557676) (end 98.798716 124.645302) (width 0.155) (layer "B.Cu") (net 64))
  (segment (start 101.75 118.55) (end 101.75 119.750001) (width 0.155) (layer "F.Cu") (net 65))
  (segment (start 101.64 120.344558) (end 100.885679 121.098879) (width 0.155) (layer "F.Cu") (net 65))
  (segment (start 101.64 119.860001) (end 101.64 120.344558) (width 0.155) (layer "F.Cu") (net 65))
  (segment (start 100.885679 121.098879) (end 100.885679 121.413543) (width 0.155) (layer "F.Cu") (net 65))
  (segment (start 101.75 119.750001) (end 101.64 119.860001) (width 0.155) (layer "F.Cu") (net 65))
  (via (at 100.885679 121.413543) (size 0.6) (drill 0.25) (layers "F.Cu" "B.Cu") (net 65))
  (segment (start 99.097902 128.165093) (end 99.128239 128.184155) (width 0.155) (layer "B.Cu") (net 65))
  (segment (start 100.827764 125.48) (end 99.197661 125.48) (width 0.155) (layer "B.Cu") (net 65))
  (segment (start 101.007642 127.838944) (end 100.920016 127.869605) (width 0.155) (layer "B.Cu") (net 65))
  (segment (start 101.007642 125.841055) (end 101.086248 125.890447) (width 0.155) (layer "B.Cu") (net 65))
  (segment (start 100.571015 121.413543) (end 100.14 121.844558) (width 0.155) (layer "B.Cu") (net 65))
  (segment (start 101.086248 127.090447) (end 101.151892 127.156091) (width 0.155) (layer "B.Cu") (net 65))
  (segment (start 101.242339 126.265424) (end 101.231945 126.357676) (width 0.155) (layer "B.Cu") (net 65))
  (segment (start 100.827764 127.88) (end 99.197661 127.88) (width 0.155) (layer "B.Cu") (net 65))
  (segment (start 100.129605 128.522323) (end 100.14 128.614575) (width 0.155) (layer "B.Cu") (net 65))
  (segment (start 99.197661 128.2) (end 99.725424 128.2) (width 0.155) (layer "B.Cu") (net 65))
  (segment (start 100.827764 126.68) (end 99.197661 126.68) (width 0.155) (layer "B.Cu") (net 65))
  (segment (start 99.037661 128.04) (end 99.041672 128.075603) (width 0.155) (layer "B.Cu") (net 65))
  (segment (start 99.162057 126.995988) (end 99.197661 127) (width 0.155) (layer "B.Cu") (net 65))
  (segment (start 99.905302 124.238944) (end 99.817676 124.269605) (width 0.155) (layer "B.Cu") (net 65))
  (segment (start 99.072567 126.740241) (end 99.053505 126.770578) (width 0.155) (layer "B.Cu") (net 65))
  (segment (start 99.053505 125.709421) (end 99.072567 125.739758) (width 0.155) (layer "B.Cu") (net 65))
  (segment (start 99.072567 127.940241) (end 99.053505 127.970578) (width 0.155) (layer "B.Cu") (net 65))
  (segment (start 101.201284 124.834697) (end 101.231945 124.922323) (width 0.155) (layer "B.Cu") (net 65))
  (segment (start 99.072567 125.739758) (end 99.097902 125.765093) (width 0.155) (layer "B.Cu") (net 65))
  (segment (start 99.128239 125.495844) (end 99.097902 125.514906) (width 0.155) (layer "B.Cu") (net 65))
  (segment (start 99.097902 126.714906) (end 99.072567 126.740241) (width 0.155) (layer "B.Cu") (net 65))
  (segment (start 101.201284 127.234697) (end 101.231945 127.322323) (width 0.155) (layer "B.Cu") (net 65))
  (segment (start 100.14 121.844558) (end 100.14 123.865424) (width 0.155) (layer "B.Cu") (net 65))
  (segment (start 100.885679 121.413543) (end 100.571015 121.413543) (width 0.155) (layer "B.Cu") (net 65))
  (segment (start 99.053505 126.770578) (end 99.041672 126.804396) (width 0.155) (layer "B.Cu") (net 65))
  (segment (start 99.128239 127.895844) (end 99.097902 127.914906) (width 0.155) (layer "B.Cu") (net 65))
  (segment (start 101.201284 126.445302) (end 101.151892 126.523908) (width 0.155) (layer "B.Cu") (net 65))
  (segment (start 99.072567 125.540241) (end 99.053505 125.570578) (width 0.155) (layer "B.Cu") (net 65))
  (segment (start 99.053505 126.909421) (end 99.072567 126.939758) (width 0.155) (layer "B.Cu") (net 65))
  (segment (start 99.725424 128.2) (end 99.817676 128.210394) (width 0.155) (layer "B.Cu") (net 65))
  (segment (start 99.037661 125.64) (end 99.041672 125.675603) (width 0.155) (layer "B.Cu") (net 65))
  (segment (start 100.920016 125.810394) (end 101.007642 125.841055) (width 0.155) (layer "B.Cu") (net 65))
  (segment (start 99.162057 128.195988) (end 99.197661 128.2) (width 0.155) (layer "B.Cu") (net 65))
  (segment (start 101.242339 127.414575) (end 101.242339 127.465424) (width 0.155) (layer "B.Cu") (net 65))
  (segment (start 101.086248 125.890447) (end 101.151892 125.956091) (width 0.155) (layer "B.Cu") (net 65))
  (segment (start 99.041672 126.804396) (end 99.037661 126.84) (width 0.155) (layer "B.Cu") (net 65))
  (segment (start 99.053505 125.570578) (end 99.041672 125.604396) (width 0.155) (layer "B.Cu") (net 65))
  (segment (start 99.097902 127.914906) (end 99.072567 127.940241) (width 0.155) (layer "B.Cu") (net 65))
  (segment (start 99.983908 124.189552) (end 99.905302 124.238944) (width 0.155) (layer "B.Cu") (net 65))
  (segment (start 99.817676 124.269605) (end 99.725424 124.28) (width 0.155) (layer "B.Cu") (net 65))
  (segment (start 101.242339 127.465424) (end 101.231945 127.557676) (width 0.155) (layer "B.Cu") (net 65))
  (segment (start 101.086248 125.389552) (end 101.007642 125.438944) (width 0.155) (layer "B.Cu") (net 65))
  (segment (start 99.041672 125.604396) (end 99.037661 125.64) (width 0.155) (layer "B.Cu") (net 65))
  (segment (start 101.201284 125.245302) (end 101.151892 125.323908) (width 0.155) (layer "B.Cu") (net 65))
  (segment (start 99.097902 124.565093) (end 99.128239 124.584155) (width 0.155) (layer "B.Cu") (net 65))
  (segment (start 101.242339 126.214575) (end 101.242339 126.265424) (width 0.155) (layer "B.Cu") (net 65))
  (segment (start 101.007642 127.041055) (end 101.086248 127.090447) (width 0.155) (layer "B.Cu") (net 65))
  (segment (start 99.905302 128.241055) (end 99.983908 128.290447) (width 0.155) (layer "B.Cu") (net 65))
  (segment (start 101.007642 126.638944) (end 100.920016 126.669605) (width 0.155) (layer "B.Cu") (net 65))
  (segment (start 100.827764 127) (end 100.920016 127.010394) (width 0.155) (layer "B.Cu") (net 65))
  (segment (start 101.231945 127.322323) (end 101.242339 127.414575) (width 0.155) (layer "B.Cu") (net 65))
  (segment (start 99.041672 126.875603) (end 99.053505 126.909421) (width 0.155) (layer "B.Cu") (net 65))
  (segment (start 100.920016 126.669605) (end 100.827764 126.68) (width 0.155) (layer "B.Cu") (net 65))
  (segment (start 101.151892 126.523908) (end 101.086248 126.589552) (width 0.155) (layer "B.Cu") (net 65))
  (segment (start 100.827764 125.8) (end 100.920016 125.810394) (width 0.155) (layer "B.Cu") (net 65))
  (segment (start 99.197661 125.48) (end 99.162057 125.484011) (width 0.155) (layer "B.Cu") (net 65))
  (segment (start 99.128239 124.584155) (end 99.162057 124.595988) (width 0.155) (layer "B.Cu") (net 65))
  (segment (start 99.817676 128.210394) (end 99.905302 128.241055) (width 0.155) (layer "B.Cu") (net 65))
  (segment (start 100.129605 123.957676) (end 100.098944 124.045302) (width 0.155) (layer "B.Cu") (net 65))
  (segment (start 99.053505 124.370578) (end 99.041672 124.404396) (width 0.155) (layer "B.Cu") (net 65))
  (segment (start 99.128239 126.984155) (end 99.162057 126.995988) (width 0.155) (layer "B.Cu") (net 65))
  (segment (start 101.242339 125.065424) (end 101.231945 125.157676) (width 0.155) (layer "B.Cu") (net 65))
  (segment (start 99.041672 128.075603) (end 99.053505 128.109421) (width 0.155) (layer "B.Cu") (net 65))
  (segment (start 101.007642 125.438944) (end 100.920016 125.469605) (width 0.155) (layer "B.Cu") (net 65))
  (segment (start 100.14 137.255) (end 100.5 137.615) (width 0.155) (layer "B.Cu") (net 65))
  (segment (start 99.162057 125.795988) (end 99.197661 125.8) (width 0.155) (layer "B.Cu") (net 65))
  (segment (start 101.086248 127.789552) (end 101.007642 127.838944) (width 0.155) (layer "B.Cu") (net 65))
  (segment (start 99.197661 125.8) (end 100.827764 125.8) (width 0.155) (layer "B.Cu") (net 65))
  (segment (start 99.128239 128.184155) (end 99.162057 128.195988) (width 0.155) (layer "B.Cu") (net 65))
  (segment (start 101.086248 124.690447) (end 101.151892 124.756091) (width 0.155) (layer "B.Cu") (net 65))
  (segment (start 99.041672 124.404396) (end 99.037661 124.44) (width 0.155) (layer "B.Cu") (net 65))
  (segment (start 99.041672 125.675603) (end 99.053505 125.709421) (width 0.155) (layer "B.Cu") (net 65))
  (segment (start 99.053505 128.109421) (end 99.072567 128.139758) (width 0.155) (layer "B.Cu") (net 65))
  (segment (start 101.231945 126.357676) (end 101.201284 126.445302) (width 0.155) (layer "B.Cu") (net 65))
  (segment (start 99.072567 126.939758) (end 99.097902 126.965093) (width 0.155) (layer "B.Cu") (net 65))
  (segment (start 99.197661 124.6) (end 100.827764 124.6) (width 0.155) (layer "B.Cu") (net 65))
  (segment (start 99.097902 124.314906) (end 99.072567 124.340241) (width 0.155) (layer "B.Cu") (net 65))
  (segment (start 99.097902 125.514906) (end 99.072567 125.540241) (width 0.155) (layer "B.Cu") (net 65))
  (segment (start 99.037661 124.44) (end 99.041672 124.475603) (width 0.155) (layer "B.Cu") (net 65))
  (segment (start 100.14 123.865424) (end 100.129605 123.957676) (width 0.155) (layer "B.Cu") (net 65))
  (segment (start 99.072567 124.539758) (end 99.097902 124.565093) (width 0.155) (layer "B.Cu") (net 65))
  (segment (start 101.242339 125.014575) (end 101.242339 125.065424) (width 0.155) (layer "B.Cu") (net 65))
  (segment (start 99.041672 128.004396) (end 99.037661 128.04) (width 0.155) (layer "B.Cu") (net 65))
  (segment (start 99.053505 124.509421) (end 99.072567 124.539758) (width 0.155) (layer "B.Cu") (net 65))
  (segment (start 99.072567 124.340241) (end 99.053505 124.370578) (width 0.155) (layer "B.Cu") (net 65))
  (segment (start 100.049552 124.123908) (end 99.983908 124.189552) (width 0.155) (layer "B.Cu") (net 65))
  (segment (start 99.197661 127) (end 100.827764 127) (width 0.155) (layer "B.Cu") (net 65))
  (segment (start 101.007642 124.641055) (end 101.086248 124.690447) (width 0.155) (layer "B.Cu") (net 65))
  (segment (start 99.128239 125.784155) (end 99.162057 125.795988) (width 0.155) (layer "B.Cu") (net 65))
  (segment (start 101.231945 126.122323) (end 101.242339 126.214575) (width 0.155) (layer "B.Cu") (net 65))
  (segment (start 99.983908 128.290447) (end 100.049552 128.356091) (width 0.155) (layer "B.Cu") (net 65))
  (segment (start 101.151892 125.956091) (end 101.201284 126.034697) (width 0.155) (layer "B.Cu") (net 65))
  (segment (start 101.231945 124.922323) (end 101.242339 125.014575) (width 0.155) (layer "B.Cu") (net 65))
  (segment (start 100.920016 127.010394) (end 101.007642 127.041055) (width 0.155) (layer "B.Cu") (net 65))
  (segment (start 100.920016 125.469605) (end 100.827764 125.48) (width 0.155) (layer "B.Cu") (net 65))
  (segment (start 101.151892 125.323908) (end 101.086248 125.389552) (width 0.155) (layer "B.Cu") (net 65))
  (segment (start 100.049552 128.356091) (end 100.098944 128.434697) (width 0.155) (layer "B.Cu") (net 65))
  (segment (start 101.151892 124.756091) (end 101.201284 124.834697) (width 0.155) (layer "B.Cu") (net 65))
  (segment (start 100.098944 124.045302) (end 100.049552 124.123908) (width 0.155) (layer "B.Cu") (net 65))
  (segment (start 99.162057 125.484011) (end 99.128239 125.495844) (width 0.155) (layer "B.Cu") (net 65))
  (segment (start 101.151892 127.723908) (end 101.086248 127.789552) (width 0.155) (layer "B.Cu") (net 65))
  (segment (start 99.128239 124.295844) (end 99.097902 124.314906) (width 0.155) (layer "B.Cu") (net 65))
  (segment (start 100.920016 124.610394) (end 101.007642 124.641055) (width 0.155) (layer "B.Cu") (net 65))
  (segment (start 99.072567 128.139758) (end 99.097902 128.165093) (width 0.155) (layer "B.Cu") (net 65))
  (segment (start 101.201284 126.034697) (end 101.231945 126.122323) (width 0.155) (layer "B.Cu") (net 65))
  (segment (start 99.097902 126.965093) (end 99.128239 126.984155) (width 0.155) (layer "B.Cu") (net 65))
  (segment (start 101.231945 125.157676) (end 101.201284 125.245302) (width 0.155) (layer "B.Cu") (net 65))
  (segment (start 101.086248 126.589552) (end 101.007642 126.638944) (width 0.155) (layer "B.Cu") (net 65))
  (segment (start 99.162057 126.684011) (end 99.128239 126.695844) (width 0.155) (layer "B.Cu") (net 65))
  (segment (start 100.827764 124.6) (end 100.920016 124.610394) (width 0.155) (layer "B.Cu") (net 65))
  (segment (start 99.037661 126.84) (end 99.041672 126.875603) (width 0.155) (layer "B.Cu") (net 65))
  (segment (start 99.197661 124.28) (end 99.162057 124.284011) (width 0.155) (layer "B.Cu") (net 65))
  (segment (start 100.14 128.614575) (end 100.14 137.255) (width 0.155) (layer "B.Cu") (net 65))
  (segment (start 101.201284 127.645302) (end 101.151892 127.723908) (width 0.155) (layer "B.Cu") (net 65))
  (segment (start 101.151892 127.156091) (end 101.201284 127.234697) (width 0.155) (layer "B.Cu") (net 65))
  (segment (start 100.920016 127.869605) (end 100.827764 127.88) (width 0.155) (layer "B.Cu") (net 65))
  (segment (start 99.725424 124.28) (end 99.197661 124.28) (width 0.155) (layer "B.Cu") (net 65))
  (segment (start 99.162057 124.595988) (end 99.197661 124.6) (width 0.155) (layer "B.Cu") (net 65))
  (segment (start 99.162057 127.884011) (end 99.128239 127.895844) (width 0.155) (layer "B.Cu") (net 65))
  (segment (start 99.128239 126.695844) (end 99.097902 126.714906) (width 0.155) (layer "B.Cu") (net 65))
  (segment (start 99.041672 124.475603) (end 99.053505 124.509421) (width 0.155) (layer "B.Cu") (net 65))
  (segment (start 99.197661 127.88) (end 99.162057 127.884011) (width 0.155) (layer "B.Cu") (net 65))
  (segment (start 101.231945 127.557676) (end 101.201284 127.645302) (width 0.155) (layer "B.Cu") (net 65))
  (segment (start 100.098944 128.434697) (end 100.129605 128.522323) (width 0.155) (layer "B.Cu") (net 65))
  (segment (start 99.162057 124.284011) (end 99.128239 124.295844) (width 0.155) (layer "B.Cu") (net 65))
  (segment (start 99.197661 126.68) (end 99.162057 126.684011) (width 0.155) (layer "B.Cu") (net 65))
  (segment (start 99.053505 127.970578) (end 99.041672 128.004396) (width 0.155) (layer "B.Cu") (net 65))
  (segment (start 99.097902 125.765093) (end 99.128239 125.784155) (width 0.155) (layer "B.Cu") (net 65))
  (segment (start 100.5 143.04) (end 100.5 143.7) (width 0.3) (layer "F.Cu") (net 66))
  (segment (start 100.5 143.7) (end 100.3 143.9) (width 0.3) (layer "F.Cu") (net 66))
  (segment (start 100.25 144.74) (end 100.25 143.95) (width 0.3) (layer "F.Cu") (net 66))
  (segment (start 100.25 143.95) (end 100.3 143.9) (width 0.3) (layer "F.Cu") (net 66))
  (segment (start 103 143.04) (end 103 143.8) (width 0.3) (layer "F.Cu") (net 66))
  (segment (start 103 143.8) (end 102.9 143.9) (width 0.3) (layer "F.Cu") (net 66))
  (segment (start 102.75 144.74) (end 102.75 144.05) (width 0.3) (layer "F.Cu") (net 66))
  (segment (start 102.75 144.05) (end 102.9 143.9) (width 0.3) (layer "F.Cu") (net 66))
  (via (at 100.3 143.9) (size 0.6) (drill 0.25) (layers "F.Cu" "B.Cu") (net 66))
  (via (at 102.9 143.9) (size 0.6) (drill 0.25) (layers "F.Cu" "B.Cu") (net 66))
  (via (at 94.1 115.6) (size 0.6) (drill 0.25) (layers "F.Cu" "B.Cu") (net 66))
  (via (at 94.7 115.6) (size 0.6) (drill 0.25) (layers "F.Cu" "B.Cu") (net 66))
  (via (at 103.4 147.7) (size 0.6) (drill 0.25) (layers "F.Cu" "B.Cu") (net 66))
  (via (at 102.6 148.5) (size 0.6) (drill 0.25) (layers "F.Cu" "B.Cu") (net 66))
  (via (at 94.7 114.4) (size 0.6) (drill 0.25) (layers "F.Cu" "B.Cu") (net 66))
  (via (at 94.7 115) (size 0.6) (drill 0.25) (layers "F.Cu" "B.Cu") (net 66))
  (via (at 99.4 147.8) (size 0.6) (drill 0.25) (layers "F.Cu" "B.Cu") (net 66))
  (via (at 94.1 115) (size 0.6) (drill 0.25) (layers "F.Cu" "B.Cu") (net 66))
  (via (at 102.6 147.7) (size 0.6) (drill 0.25) (layers "F.Cu" "B.Cu") (net 66))
  (via (at 94.7 113.8) (size 0.6) (drill 0.25) (layers "F.Cu" "B.Cu") (net 66))
  (via (at 94.1 113.8) (size 0.6) (drill 0.25) (layers "F.Cu" "B.Cu") (net 66))
  (via (at 99.4 147) (size 0.6) (drill 0.25) (layers "F.Cu" "B.Cu") (net 66))
  (via (at 94.1 114.4) (size 0.6) (drill 0.25) (layers "F.Cu" "B.Cu") (net 66))
  (segment (start 104.36 113.195) (end 104.36 114.0275) (width 0.155) (layer "F.Cu") (net 67))
  (segment (start 104.36 114.0275) (end 104.1375 114.25) (width 0.155) (layer "F.Cu") (net 67))
  (segment (start 104.25 113.085) (end 104.36 113.195) (width 0.155) (layer "F.Cu") (net 67))
  (via (at 104.1375 114.25) (size 0.6) (drill 0.25) (layers "F.Cu" "B.Cu") (net 67))
  (segment (start 104.082621 133.465093) (end 104.107956 133.439758) (width 0.155) (layer "B.Cu") (net 67))
  (segment (start 104.142863 133.34) (end 104.138851 133.304396) (width 0.155) (layer "B.Cu") (net 67))
  (segment (start 102.86 116.69201) (end 104.36 115.19201) (width 0.155) (layer "B.Cu") (net 67))
  (segment (start 103 137.615) (end 103.36 137.255) (width 0.155) (layer "B.Cu") (net 67))
  (segment (start 102.387532 132.622323) (end 102.418193 132.534697) (width 0.155) (layer "B.Cu") (net 67))
  (segment (start 104.052284 133.195844) (end 104.018466 133.184011) (width 0.155) (layer "B.Cu") (net 67))
  (segment (start 104.36 114.4725) (end 104.1375 114.25) (width 0.155) (layer "B.Cu") (net 67))
  (segment (start 104.018466 132.295988) (end 104.052284 132.284155) (width 0.155) (layer "B.Cu") (net 67))
  (segment (start 103.982863 133.5) (end 104.018466 133.495988) (width 0.155) (layer "B.Cu") (net 67))
  (segment (start 104.107956 133.240241) (end 104.082621 133.214906) (width 0.155) (layer "B.Cu") (net 67))
  (segment (start 104.127018 134.609421) (end 104.138851 134.575603) (width 0.155) (layer "B.Cu") (net 67))
  (segment (start 102.791713 134.38) (end 102.699461 134.369605) (width 0.155) (layer "B.Cu") (net 67))
  (segment (start 102.387532 133.822323) (end 102.418193 133.734697) (width 0.155) (layer "B.Cu") (net 67))
  (segment (start 102.533229 132.390447) (end 102.611835 132.341055) (width 0.155) (layer "B.Cu") (net 67))
  (segment (start 104.138851 133.304396) (end 104.127018 133.270578) (width 0.155) (layer "B.Cu") (net 67))
  (segment (start 104.138851 134.575603) (end 104.142863 134.54) (width 0.155) (layer "B.Cu") (net 67))
  (segment (start 102.611835 133.138944) (end 102.533229 133.089552) (width 0.155) (layer "B.Cu") (net 67))
  (segment (start 103.36 121.15799) (end 102.86 120.65799) (width 0.155) (layer "B.Cu") (net 67))
  (segment (start 102.387532 134.057676) (end 102.377137 133.965424) (width 0.155) (layer "B.Cu") (net 67))
  (segment (start 104.082621 134.414906) (end 104.052284 134.395844) (width 0.155) (layer "B.Cu") (net 67))
  (segment (start 103.982863 134.7) (end 104.018466 134.695988) (width 0.155) (layer "B.Cu") (net 67))
  (segment (start 104.107956 132.239758) (end 104.127018 132.209421) (width 0.155) (layer "B.Cu") (net 67))
  (segment (start 103.516091 134.790447) (end 103.594697 134.741055) (width 0.155) (layer "B.Cu") (net 67))
  (segment (start 103.594697 131.938944) (end 103.516091 131.889552) (width 0.155) (layer "B.Cu") (net 67))
  (segment (start 102.791713 133.5) (end 103.982863 133.5) (width 0.155) (layer "B.Cu") (net 67))
  (segment (start 103.450447 134.856091) (end 103.516091 134.790447) (width 0.155) (layer "B.Cu") (net 67))
  (segment (start 104.082621 132.265093) (end 104.107956 132.239758) (width 0.155) (layer "B.Cu") (net 67))
  (segment (start 104.052284 134.395844) (end 104.018466 134.384011) (width 0.155) (layer "B.Cu") (net 67))
  (segment (start 104.107956 134.440241) (end 104.082621 134.414906) (width 0.155) (layer "B.Cu") (net 67))
  (segment (start 103.36 131.565424) (end 103.36 121.15799) (width 0.155) (layer "B.Cu") (net 67))
  (segment (start 104.052284 132.284155) (end 104.082621 132.265093) (width 0.155) (layer "B.Cu") (net 67))
  (segment (start 104.107956 132.040241) (end 104.082621 132.014906) (width 0.155) (layer "B.Cu") (net 67))
  (segment (start 104.36 115.19201) (end 104.36 114.4725) (width 0.155) (layer "B.Cu") (net 67))
  (segment (start 102.791713 133.18) (end 102.699461 133.169605) (width 0.155) (layer "B.Cu") (net 67))
  (segment (start 104.138851 132.175603) (end 104.142863 132.14) (width 0.155) (layer "B.Cu") (net 67))
  (segment (start 104.082621 133.214906) (end 104.052284 133.195844) (width 0.155) (layer "B.Cu") (net 67))
  (segment (start 102.377137 133.914575) (end 102.387532 133.822323) (width 0.155) (layer "B.Cu") (net 67))
  (segment (start 102.377137 132.765424) (end 102.377137 132.714575) (width 0.155) (layer "B.Cu") (net 67))
  (segment (start 102.387532 132.857676) (end 102.377137 132.765424) (width 0.155) (layer "B.Cu") (net 67))
  (segment (start 102.418193 132.945302) (end 102.387532 132.857676) (width 0.155) (layer "B.Cu") (net 67))
  (segment (start 102.611835 134.338944) (end 102.533229 134.289552) (width 0.155) (layer "B.Cu") (net 67))
  (segment (start 104.142863 132.14) (end 104.138851 132.104396) (width 0.155) (layer "B.Cu") (net 67))
  (segment (start 103.594697 134.741055) (end 103.682323 134.710394) (width 0.155) (layer "B.Cu") (net 67))
  (segment (start 104.138851 134.504396) (end 104.127018 134.470578) (width 0.155) (layer "B.Cu") (net 67))
  (segment (start 104.138851 132.104396) (end 104.127018 132.070578) (width 0.155) (layer "B.Cu") (net 67))
  (segment (start 102.86 120.65799) (end 102.86 116.69201) (width 0.155) (layer "B.Cu") (net 67))
  (segment (start 103.982863 131.98) (end 103.774575 131.98) (width 0.155) (layer "B.Cu") (net 67))
  (segment (start 102.418193 132.534697) (end 102.467585 132.456091) (width 0.155) (layer "B.Cu") (net 67))
  (segment (start 102.377137 132.714575) (end 102.387532 132.622323) (width 0.155) (layer "B.Cu") (net 67))
  (segment (start 102.791713 132.3) (end 103.982863 132.3) (width 0.155) (layer "B.Cu") (net 67))
  (segment (start 103.36 135.114575) (end 103.370394 135.022323) (width 0.155) (layer "B.Cu") (net 67))
  (segment (start 102.467585 133.656091) (end 102.533229 133.590447) (width 0.155) (layer "B.Cu") (net 67))
  (segment (start 104.082621 134.665093) (end 104.107956 134.639758) (width 0.155) (layer "B.Cu") (net 67))
  (segment (start 104.142863 134.54) (end 104.138851 134.504396) (width 0.155) (layer "B.Cu") (net 67))
  (segment (start 102.533229 133.089552) (end 102.467585 133.023908) (width 0.155) (layer "B.Cu") (net 67))
  (segment (start 104.018466 134.695988) (end 104.052284 134.684155) (width 0.155) (layer "B.Cu") (net 67))
  (segment (start 104.127018 132.209421) (end 104.138851 132.175603) (width 0.155) (layer "B.Cu") (net 67))
  (segment (start 102.533229 134.289552) (end 102.467585 134.223908) (width 0.155) (layer "B.Cu") (net 67))
  (segment (start 104.082621 132.014906) (end 104.052284 131.995844) (width 0.155) (layer "B.Cu") (net 67))
  (segment (start 103.370394 135.022323) (end 103.401055 134.934697) (width 0.155) (layer "B.Cu") (net 67))
  (segment (start 103.36 137.255) (end 103.36 135.114575) (width 0.155) (layer "B.Cu") (net 67))
  (segment (start 104.018466 134.384011) (end 103.982863 134.38) (width 0.155) (layer "B.Cu") (net 67))
  (segment (start 104.107956 133.439758) (end 104.127018 133.409421) (width 0.155) (layer "B.Cu") (net 67))
  (segment (start 102.418193 133.734697) (end 102.467585 133.656091) (width 0.155) (layer "B.Cu") (net 67))
  (segment (start 103.370394 131.657676) (end 103.36 131.565424) (width 0.155) (layer "B.Cu") (net 67))
  (segment (start 102.611835 132.341055) (end 102.699461 132.310394) (width 0.155) (layer "B.Cu") (net 67))
  (segment (start 104.018466 133.495988) (end 104.052284 133.484155) (width 0.155) (layer "B.Cu") (net 67))
  (segment (start 103.982863 133.18) (end 102.791713 133.18) (width 0.155) (layer "B.Cu") (net 67))
  (segment (start 103.516091 131.889552) (end 103.450447 131.823908) (width 0.155) (layer "B.Cu") (net 67))
  (segment (start 104.127018 132.070578) (end 104.107956 132.040241) (width 0.155) (layer "B.Cu") (net 67))
  (segment (start 104.052284 133.484155) (end 104.082621 133.465093) (width 0.155) (layer "B.Cu") (net 67))
  (segment (start 104.018466 131.984011) (end 103.982863 131.98) (width 0.155) (layer "B.Cu") (net 67))
  (segment (start 103.682323 131.969605) (end 103.594697 131.938944) (width 0.155) (layer "B.Cu") (net 67))
  (segment (start 102.418193 134.145302) (end 102.387532 134.057676) (width 0.155) (layer "B.Cu") (net 67))
  (segment (start 104.138851 133.375603) (end 104.142863 133.34) (width 0.155) (layer "B.Cu") (net 67))
  (segment (start 104.127018 133.270578) (end 104.107956 133.240241) (width 0.155) (layer "B.Cu") (net 67))
  (segment (start 102.699461 133.169605) (end 102.611835 133.138944) (width 0.155) (layer "B.Cu") (net 67))
  (segment (start 103.774575 131.98) (end 103.682323 131.969605) (width 0.155) (layer "B.Cu") (net 67))
  (segment (start 103.982863 132.3) (end 104.018466 132.295988) (width 0.155) (layer "B.Cu") (net 67))
  (segment (start 102.533229 133.590447) (end 102.611835 133.541055) (width 0.155) (layer "B.Cu") (net 67))
  (segment (start 104.107956 134.639758) (end 104.127018 134.609421) (width 0.155) (layer "B.Cu") (net 67))
  (segment (start 103.682323 134.710394) (end 103.774575 134.7) (width 0.155) (layer "B.Cu") (net 67))
  (segment (start 104.052284 134.684155) (end 104.082621 134.665093) (width 0.155) (layer "B.Cu") (net 67))
  (segment (start 102.467585 132.456091) (end 102.533229 132.390447) (width 0.155) (layer "B.Cu") (net 67))
  (segment (start 102.699461 134.369605) (end 102.611835 134.338944) (width 0.155) (layer "B.Cu") (net 67))
  (segment (start 103.982863 134.38) (end 102.791713 134.38) (width 0.155) (layer "B.Cu") (net 67))
  (segment (start 102.611835 133.541055) (end 102.699461 133.510394) (width 0.155) (layer "B.Cu") (net 67))
  (segment (start 104.127018 133.409421) (end 104.138851 133.375603) (width 0.155) (layer "B.Cu") (net 67))
  (segment (start 102.699461 133.510394) (end 102.791713 133.5) (width 0.155) (layer "B.Cu") (net 67))
  (segment (start 103.450447 131.823908) (end 103.401055 131.745302) (width 0.155) (layer "B.Cu") (net 67))
  (segment (start 102.699461 132.310394) (end 102.791713 132.3) (width 0.155) (layer "B.Cu") (net 67))
  (segment (start 102.467585 133.023908) (end 102.418193 132.945302) (width 0.155) (layer "B.Cu") (net 67))
  (segment (start 102.377137 133.965424) (end 102.377137 133.914575) (width 0.155) (layer "B.Cu") (net 67))
  (segment (start 103.401055 131.745302) (end 103.370394 131.657676) (width 0.155) (layer "B.Cu") (net 67))
  (segment (start 104.052284 131.995844) (end 104.018466 131.984011) (width 0.155) (layer "B.Cu") (net 67))
  (segment (start 102.467585 134.223908) (end 102.418193 134.145302) (width 0.155) (layer "B.Cu") (net 67))
  (segment (start 104.018466 133.184011) (end 103.982863 133.18) (width 0.155) (layer "B.Cu") (net 67))
  (segment (start 103.774575 134.7) (end 103.982863 134.7) (width 0.155) (layer "B.Cu") (net 67))
  (segment (start 103.401055 134.934697) (end 103.450447 134.856091) (width 0.155) (layer "B.Cu") (net 67))
  (segment (start 104.127018 134.470578) (end 104.107956 134.440241) (width 0.155) (layer "B.Cu") (net 67))
  (segment (start 104.75 113.085) (end 104.64 113.195) (width 0.155) (layer "F.Cu") (net 68))
  (segment (start 104.64 113.195) (end 104.64 114.0275) (width 0.155) (layer "F.Cu") (net 68))
  (segment (start 104.64 114.0275) (end 104.8625 114.25) (width 0.155) (layer "F.Cu") (net 68))
  (via (at 104.8625 114.25) (size 0.6) (drill 0.25) (layers "F.Cu" "B.Cu") (net 68))
  (segment (start 103.644011 131.575603) (end 103.64 131.54) (width 0.155) (layer "B.Cu") (net 68))
  (segment (start 104.008287 132.9) (end 102.817137 132.9) (width 0.155) (layer "B.Cu") (net 68))
  (segment (start 102.657137 132.74) (end 102.661149 132.704396) (width 0.155) (layer "B.Cu") (net 68))
  (segment (start 104.422863 134.514575) (end 104.412468 134.422323) (width 0.155) (layer "B.Cu") (net 68))
  (segment (start 103.700241 131.665093) (end 103.674906 131.639758) (width 0.155) (layer "B.Cu") (net 68))
  (segment (start 104.381807 134.745302) (end 104.412468 134.657676) (width 0.155) (layer "B.Cu") (net 68))
  (segment (start 104.412468 134.657676) (end 104.422863 134.565424) (width 0.155) (layer "B.Cu") (net 68))
  (segment (start 102.672982 133.870578) (end 102.692044 133.840241) (width 0.155) (layer "B.Cu") (net 68))
  (segment (start 103.700241 135.014906) (end 103.730578 134.995844) (width 0.155) (layer "B.Cu") (net 68))
  (segment (start 104.64 114.4725) (end 104.8625 114.25) (width 0.155) (layer "B.Cu") (net 68))
  (segment (start 102.747716 134.084155) (end 102.717379 134.065093) (width 0.155) (layer "B.Cu") (net 68))
  (segment (start 104.422863 132.165424) (end 104.422863 132.114575) (width 0.155) (layer "B.Cu") (net 68))
  (segment (start 104.332415 134.256091) (end 104.266771 134.190447) (width 0.155) (layer "B.Cu") (net 68))
  (segment (start 104.266771 134.190447) (end 104.188165 134.141055) (width 0.155) (layer "B.Cu") (net 68))
  (segment (start 104.188165 134.141055) (end 104.100539 134.110394) (width 0.155) (layer "B.Cu") (net 68))
  (segment (start 102.717379 132.865093) (end 102.692044 132.839758) (width 0.155) (layer "B.Cu") (net 68))
  (segment (start 104.188165 131.741055) (end 104.100539 131.710394) (width 0.155) (layer "B.Cu") (net 68))
  (segment (start 104.188165 134.938944) (end 104.266771 134.889552) (width 0.155) (layer "B.Cu") (net 68))
  (segment (start 102.817137 133.78) (end 104.008287 133.78) (width 0.155) (layer "B.Cu") (net 68))
  (segment (start 104.100539 134.969605) (end 104.188165 134.938944) (width 0.155) (layer "B.Cu") (net 68))
  (segment (start 104.412468 134.422323) (end 104.381807 134.334697) (width 0.155) (layer "B.Cu") (net 68))
  (segment (start 104.008287 134.98) (end 104.100539 134.969605) (width 0.155) (layer "B.Cu") (net 68))
  (segment (start 102.817137 134.1) (end 102.781534 134.095988) (width 0.155) (layer "B.Cu") (net 68))
  (segment (start 104.100539 131.710394) (end 104.008287 131.7) (width 0.155) (layer "B.Cu") (net 68))
  (segment (start 102.817137 132.58) (end 104.008287 132.58) (width 0.155) (layer "B.Cu") (net 68))
  (segment (start 102.672982 134.009421) (end 102.661149 133.975603) (width 0.155) (layer "B.Cu") (net 68))
  (segment (start 104.266771 131.790447) (end 104.188165 131.741055) (width 0.155) (layer "B.Cu") (net 68))
  (segment (start 104.266771 132.990447) (end 104.188165 132.941055) (width 0.155) (layer "B.Cu") (net 68))
  (segment (start 102.661149 133.904396) (end 102.672982 133.870578) (width 0.155) (layer "B.Cu") (net 68))
  (segment (start 102.692044 134.039758) (end 102.672982 134.009421) (width 0.155) (layer "B.Cu") (net 68))
  (segment (start 104.008287 131.7) (end 103.8 131.7) (width 0.155) (layer "B.Cu") (net 68))
  (segment (start 103.674906 135.040241) (end 103.700241 135.014906) (width 0.155) (layer "B.Cu") (net 68))
  (segment (start 104.381807 133.545302) (end 104.412468 133.457676) (width 0.155) (layer "B.Cu") (net 68))
  (segment (start 104 137.615) (end 103.64 137.255) (width 0.155) (layer "B.Cu") (net 68))
  (segment (start 104.332415 131.856091) (end 104.266771 131.790447) (width 0.155) (layer "B.Cu") (net 68))
  (segment (start 102.717379 134.065093) (end 102.692044 134.039758) (width 0.155) (layer "B.Cu") (net 68))
  (segment (start 103.8 131.7) (end 103.764396 131.695988) (width 0.155) (layer "B.Cu") (net 68))
  (segment (start 102.747716 132.884155) (end 102.717379 132.865093) (width 0.155) (layer "B.Cu") (net 68))
  (segment (start 104.422863 134.565424) (end 104.422863 134.514575) (width 0.155) (layer "B.Cu") (net 68))
  (segment (start 104.422863 133.365424) (end 104.422863 133.314575) (width 0.155) (layer "B.Cu") (net 68))
  (segment (start 103.14 116.80799) (end 104.64 115.30799) (width 0.155) (layer "B.Cu") (net 68))
  (segment (start 104.422863 133.314575) (end 104.412468 133.222323) (width 0.155) (layer "B.Cu") (net 68))
  (segment (start 103.64 131.54) (end 103.64 121.04201) (width 0.155) (layer "B.Cu") (net 68))
  (segment (start 102.781534 132.584011) (end 102.817137 132.58) (width 0.155) (layer "B.Cu") (net 68))
  (segment (start 102.692044 133.840241) (end 102.717379 133.814906) (width 0.155) (layer "B.Cu") (net 68))
  (segment (start 102.717379 133.814906) (end 102.747716 133.795844) (width 0.155) (layer "B.Cu") (net 68))
  (segment (start 102.817137 132.9) (end 102.781534 132.895988) (width 0.155) (layer "B.Cu") (net 68))
  (segment (start 102.781534 134.095988) (end 102.747716 134.084155) (width 0.155) (layer "B.Cu") (net 68))
  (segment (start 104.188165 132.941055) (end 104.100539 132.910394) (width 0.155) (layer "B.Cu") (net 68))
  (segment (start 104.381807 131.934697) (end 104.332415 131.856091) (width 0.155) (layer "B.Cu") (net 68))
  (segment (start 104.100539 134.110394) (end 104.008287 134.1) (width 0.155) (layer "B.Cu") (net 68))
  (segment (start 104.381807 132.345302) (end 104.412468 132.257676) (width 0.155) (layer "B.Cu") (net 68))
  (segment (start 104.100539 132.569605) (end 104.188165 132.538944) (width 0.155) (layer "B.Cu") (net 68))
  (segment (start 104.266771 133.689552) (end 104.332415 133.623908) (width 0.155) (layer "B.Cu") (net 68))
  (segment (start 102.692044 132.839758) (end 102.672982 132.809421) (width 0.155) (layer "B.Cu") (net 68))
  (segment (start 104.332415 133.623908) (end 104.381807 133.545302) (width 0.155) (layer "B.Cu") (net 68))
  (segment (start 103.644011 135.104396) (end 103.655844 135.070578) (width 0.155) (layer "B.Cu") (net 68))
  (segment (start 104.381807 134.334697) (end 104.332415 134.256091) (width 0.155) (layer "B.Cu") (net 68))
  (segment (start 104.008287 133.78) (end 104.100539 133.769605) (width 0.155) (layer "B.Cu") (net 68))
  (segment (start 104.64 115.30799) (end 104.64 114.4725) (width 0.155) (layer "B.Cu") (net 68))
  (segment (start 102.661149 133.975603) (end 102.657137 133.94) (width 0.155) (layer "B.Cu") (net 68))
  (segment (start 103.8 134.98) (end 104.008287 134.98) (width 0.155) (layer "B.Cu") (net 68))
  (segment (start 102.747716 132.595844) (end 102.781534 132.584011) (width 0.155) (layer "B.Cu") (net 68))
  (segment (start 102.781534 133.784011) (end 102.817137 133.78) (width 0.155) (layer "B.Cu") (net 68))
  (segment (start 104.100539 132.910394) (end 104.008287 132.9) (width 0.155) (layer "B.Cu") (net 68))
  (segment (start 103.64 135.14) (end 103.644011 135.104396) (width 0.155) (layer "B.Cu") (net 68))
  (segment (start 104.100539 133.769605) (end 104.188165 133.738944) (width 0.155) (layer "B.Cu") (net 68))
  (segment (start 103.64 121.04201) (end 103.14 120.54201) (width 0.155) (layer "B.Cu") (net 68))
  (segment (start 102.692044 132.640241) (end 102.717379 132.614906) (width 0.155) (layer "B.Cu") (net 68))
  (segment (start 103.764396 131.695988) (end 103.730578 131.684155) (width 0.155) (layer "B.Cu") (net 68))
  (segment (start 104.332415 133.056091) (end 104.266771 132.990447) (width 0.155) (layer "B.Cu") (net 68))
  (segment (start 104.188165 132.538944) (end 104.266771 132.489552) (width 0.155) (layer "B.Cu") (net 68))
  (segment (start 104.422863 132.114575) (end 104.412468 132.022323) (width 0.155) (layer "B.Cu") (net 68))
  (segment (start 103.655844 131.609421) (end 103.644011 131.575603) (width 0.155) (layer "B.Cu") (net 68))
  (segment (start 102.717379 132.614906) (end 102.747716 132.595844) (width 0.155) (layer "B.Cu") (net 68))
  (segment (start 103.764396 134.984011) (end 103.8 134.98) (width 0.155) (layer "B.Cu") (net 68))
  (segment (start 104.008287 134.1) (end 102.817137 134.1) (width 0.155) (layer "B.Cu") (net 68))
  (segment (start 104.332415 134.823908) (end 104.381807 134.745302) (width 0.155) (layer "B.Cu") (net 68))
  (segment (start 104.412468 133.222323) (end 104.381807 133.134697) (width 0.155) (layer "B.Cu") (net 68))
  (segment (start 104.266771 134.889552) (end 104.332415 134.823908) (width 0.155) (layer "B.Cu") (net 68))
  (segment (start 103.674906 131.639758) (end 103.655844 131.609421) (width 0.155) (layer "B.Cu") (net 68))
  (segment (start 103.655844 135.070578) (end 103.674906 135.040241) (width 0.155) (layer "B.Cu") (net 68))
  (segment (start 102.657137 133.94) (end 102.661149 133.904396) (width 0.155) (layer "B.Cu") (net 68))
  (segment (start 102.747716 133.795844) (end 102.781534 133.784011) (width 0.155) (layer "B.Cu") (net 68))
  (segment (start 103.64 137.255) (end 103.64 135.14) (width 0.155) (layer "B.Cu") (net 68))
  (segment (start 103.730578 131.684155) (end 103.700241 131.665093) (width 0.155) (layer "B.Cu") (net 68))
  (segment (start 102.672982 132.670578) (end 102.692044 132.640241) (width 0.155) (layer "B.Cu") (net 68))
  (segment (start 104.266771 132.489552) (end 104.332415 132.423908) (width 0.155) (layer "B.Cu") (net 68))
  (segment (start 103.730578 134.995844) (end 103.764396 134.984011) (width 0.155) (layer "B.Cu") (net 68))
  (segment (start 102.672982 132.809421) (end 102.661149 132.775603) (width 0.155) (layer "B.Cu") (net 68))
  (segment (start 104.381807 133.134697) (end 104.332415 133.056091) (width 0.155) (layer "B.Cu") (net 68))
  (segment (start 102.661149 132.775603) (end 102.657137 132.74) (width 0.155) (layer "B.Cu") (net 68))
  (segment (start 104.412468 132.257676) (end 104.422863 132.165424) (width 0.155) (layer "B.Cu") (net 68))
  (segment (start 104.188165 133.738944) (end 104.266771 133.689552) (width 0.155) (layer "B.Cu") (net 68))
  (segment (start 104.412468 133.457676) (end 104.422863 133.365424) (width 0.155) (layer "B.Cu") (net 68))
  (segment (start 102.661149 132.704396) (end 102.672982 132.670578) (width 0.155) (layer "B.Cu") (net 68))
  (segment (start 102.781534 132.895988) (end 102.747716 132.884155) (width 0.155) (layer "B.Cu") (net 68))
  (segment (start 104.008287 132.58) (end 104.100539 132.569605) (width 0.155) (layer "B.Cu") (net 68))
  (segment (start 103.14 120.54201) (end 103.14 116.80799) (width 0.155) (layer "B.Cu") (net 68))
  (segment (start 104.412468 132.022323) (end 104.381807 131.934697) (width 0.155) (layer "B.Cu") (net 68))
  (segment (start 104.332415 132.423908) (end 104.381807 132.345302) (width 0.155) (layer "B.Cu") (net 68))
  (segment (start 102.86 113.195) (end 102.86 114.0275) (width 0.155) (layer "F.Cu") (net 69))
  (segment (start 102.75 113.085) (end 102.86 113.195) (width 0.155) (layer "F.Cu") (net 69))
  (segment (start 102.86 114.0275) (end 102.6375 114.25) (width 0.155) (layer "F.Cu") (net 69))
  (via (at 102.6375 114.25) (size 0.6) (drill 0.25) (layers "F.Cu" "B.Cu") (net 69))
  (segment (start 97.5 137.615) (end 97.86 137.255) (width 0.155) (layer "B.Cu") (net 69))
  (segment (start 101.36 118.24201) (end 101.36 116.64201) (width 0.155) (layer "B.Cu") (net 69))
  (segment (start 98.54201 118.66) (end 100.94201 118.66) (width 0.155) (layer "B.Cu") (net 69))
  (segment (start 97.86 137.255) (end 97.86 119.34201) (width 0.155) (layer "B.Cu") (net 69))
  (segment (start 101.36 116.64201) (end 102.86 115.14201) (width 0.155) (layer "B.Cu") (net 69))
  (segment (start 102.86 115.14201) (end 102.86 114.4725) (width 0.155) (layer "B.Cu") (net 69))
  (segment (start 100.94201 118.66) (end 101.36 118.24201) (width 0.155) (layer "B.Cu") (net 69))
  (segment (start 97.86 119.34201) (end 98.54201 118.66) (width 0.155) (layer "B.Cu") (net 69))
  (segment (start 102.86 114.4725) (end 102.6375 114.25) (width 0.155) (layer "B.Cu") (net 69))
  (segment (start 103.25 113.085) (end 103.14 113.195) (width 0.155) (layer "F.Cu") (net 70))
  (segment (start 103.14 113.195) (end 103.14 114.0275) (width 0.155) (layer "F.Cu") (net 70))
  (segment (start 103.14 114.0275) (end 103.3625 114.25) (width 0.155) (layer "F.Cu") (net 70))
  (via (at 103.3625 114.25) (size 0.6) (drill 0.25) (layers "F.Cu" "B.Cu") (net 70))
  (segment (start 103.14 114.4725) (end 103.3625 114.25) (width 0.155) (layer "B.Cu") (net 70))
  (segment (start 101.64 116.75799) (end 103.14 115.25799) (width 0.155) (layer "B.Cu") (net 70))
  (segment (start 101.64 118.35799) (end 101.64 116.75799) (width 0.155) (layer "B.Cu") (net 70))
  (segment (start 98.5 137.615) (end 98.14 137.255) (width 0.155) (layer "B.Cu") (net 70))
  (segment (start 98.65799 118.94) (end 101.05799 118.94) (width 0.155) (layer "B.Cu") (net 70))
  (segment (start 98.14 119.45799) (end 98.65799 118.94) (width 0.155) (layer "B.Cu") (net 70))
  (segment (start 103.14 115.25799) (end 103.14 114.4725) (width 0.155) (layer "B.Cu") (net 70))
  (segment (start 101.05799 118.94) (end 101.64 118.35799) (width 0.155) (layer "B.Cu") (net 70))
  (segment (start 98.14 137.255) (end 98.14 119.45799) (width 0.155) (layer "B.Cu") (net 70))
  (segment (start 104.849324 120.690807) (end 104.972499 120.690807) (width 0.155) (layer "F.Cu") (net 71))
  (segment (start 104.64 120.481483) (end 104.849324 120.690807) (width 0.155) (layer "F.Cu") (net 71))
  (segment (start 104.75 118.55) (end 104.75 119.750001) (width 0.155) (layer "F.Cu") (net 71))
  (segment (start 104.75 119.750001) (end 104.64 119.860001) (width 0.155) (layer "F.Cu") (net 71))
  (segment (start 104.972499 120.690807) (end 105.195 120.468306) (width 0.155) (layer "F.Cu") (net 71))
  (segment (start 104.64 119.860001) (end 104.64 120.481483) (width 0.155) (layer "F.Cu") (net 71))
  (via (at 105.195 120.468306) (size 0.6) (drill 0.25) (layers "F.Cu" "B.Cu") (net 71))
  (segment (start 104.844155 127.370578) (end 104.855988 127.404396) (width 0.155) (layer "B.Cu") (net 71))
  (segment (start 104.769421 127.584155) (end 104.735603 127.595988) (width 0.155) (layer "B.Cu") (net 71))
  (segment (start 104.340084 126.410394) (end 104.252458 126.441055) (width 0.155) (layer "B.Cu") (net 71))
  (segment (start 104.028155 124.557676) (end 104.058816 124.645302) (width 0.155) (layer "B.Cu") (net 71))
  (segment (start 104.769421 124.895844) (end 104.799758 124.914906) (width 0.155) (layer "B.Cu") (net 71))
  (segment (start 104.252458 124.838944) (end 104.340084 124.869605) (width 0.155) (layer "B.Cu") (net 71))
  (segment (start 104.028155 123.122323) (end 104.017761 123.214575) (width 0.155) (layer "B.Cu") (net 71))
  (segment (start 104.017761 126.814575) (end 104.017761 126.865424) (width 0.155) (layer "B.Cu") (net 71))
  (segment (start 104.735603 125.195988) (end 104.7 125.2) (width 0.155) (layer "B.Cu") (net 71))
  (segment (start 104.340084 123.669605) (end 104.432336 123.68) (width 0.155) (layer "B.Cu") (net 71))
  (segment (start 104.432336 127.28) (end 104.7 127.28) (width 0.155) (layer "B.Cu") (net 71))
  (segment (start 104.108208 122.956091) (end 104.058816 123.034697) (width 0.155) (layer "B.Cu") (net 71))
  (segment (start 104.7 123.68) (end 104.735603 123.684011) (width 0.155) (layer "B.Cu") (net 71))
  (segment (start 104.855988 127.404396) (end 104.86 127.44) (width 0.155) (layer "B.Cu") (net 71))
  (segment (start 104.844155 122.709421) (end 104.825093 122.739758) (width 0.155) (layer "B.Cu") (net 71))
  (segment (start 104.799758 125.165093) (end 104.769421 125.184155) (width 0.155) (layer "B.Cu") (net 71))
  (segment (start 104.173852 125.989552) (end 104.252458 126.038944) (width 0.155) (layer "B.Cu") (net 71))
  (segment (start 104.252458 125.241055) (end 104.173852 125.290447) (width 0.155) (layer "B.Cu") (net 71))
  (segment (start 104.844155 127.509421) (end 104.825093 127.539758) (width 0.155) (layer "B.Cu") (net 71))
  (segment (start 104.252458 124.041055) (end 104.173852 124.090447) (width 0.155) (layer "B.Cu") (net 71))
  (segment (start 104.7 127.28) (end 104.735603 127.284011) (width 0.155) (layer "B.Cu") (net 71))
  (segment (start 104.7 126.4) (end 104.432336 126.4) (width 0.155) (layer "B.Cu") (net 71))
  (segment (start 104.432336 127.6) (end 104.340084 127.610394) (width 0.155) (layer "B.Cu") (net 71))
  (segment (start 104.769421 122.784155) (end 104.735603 122.795988) (width 0.155) (layer "B.Cu") (net 71))
  (segment (start 104.028155 125.522323) (end 104.017761 125.614575) (width 0.155) (layer "B.Cu") (net 71))
  (segment (start 104.855988 128.604396) (end 104.86 128.64) (width 0.155) (layer "B.Cu") (net 71))
  (segment (start 104.769421 123.695844) (end 104.799758 123.714906) (width 0.155) (layer "B.Cu") (net 71))
  (segment (start 104.017761 128.065424) (end 104.028155 128.157676) (width 0.155) (layer "B.Cu") (net 71))
  (segment (start 104.252458 122.841055) (end 104.173852 122.890447) (width 0.155) (layer "B.Cu") (net 71))
  (segment (start 104.028155 126.957676) (end 104.058816 127.045302) (width 0.155) (layer "B.Cu") (net 71))
  (segment (start 104.340084 128.469605) (end 104.432336 128.48) (width 0.155) (layer "B.Cu") (net 71))
  (segment (start 104.108208 125.356091) (end 104.058816 125.434697) (width 0.155) (layer "B.Cu") (net 71))
  (segment (start 104.7 126.08) (end 104.735603 126.084011) (width 0.155) (layer "B.Cu") (net 71))
  (segment (start 104.108208 123.523908) (end 104.173852 123.589552) (width 0.155) (layer "B.Cu") (net 71))
  (segment (start 104.799758 124.914906) (end 104.825093 124.940241) (width 0.155) (layer "B.Cu") (net 71))
  (segment (start 104.26 121.14201) (end 104.26 121.65799) (width 0.155) (layer "B.Cu") (net 71))
  (segment (start 104.735603 123.995988) (end 104.7 124) (width 0.155) (layer "B.Cu") (net 71))
  (segment (start 104.799758 122.765093) (end 104.769421 122.784155) (width 0.155) (layer "B.Cu") (net 71))
  (segment (start 104.855988 126.204396) (end 104.86 126.24) (width 0.155) (layer "B.Cu") (net 71))
  (segment (start 104.058816 123.034697) (end 104.028155 123.122323) (width 0.155) (layer "B.Cu") (net 71))
  (segment (start 104.735603 127.595988) (end 104.7 127.6) (width 0.155) (layer "B.Cu") (net 71))
  (segment (start 104.173852 122.890447) (end 104.108208 122.956091) (width 0.155) (layer "B.Cu") (net 71))
  (segment (start 104.173852 124.090447) (end 104.108208 124.156091) (width 0.155) (layer "B.Cu") (net 71))
  (segment (start 104.340084 127.269605) (end 104.432336 127.28) (width 0.155) (layer "B.Cu") (net 71))
  (segment (start 104.058816 128.245302) (end 104.108208 128.323908) (width 0.155) (layer "B.Cu") (net 71))
  (segment (start 104.7 124) (end 104.432336 124) (width 0.155) (layer "B.Cu") (net 71))
  (segment (start 104.735603 126.084011) (end 104.769421 126.095844) (width 0.155) (layer "B.Cu") (net 71))
  (segment (start 104.173852 127.189552) (end 104.252458 127.238944) (width 0.155) (layer "B.Cu") (net 71))
  (segment (start 104.855988 123.804396) (end 104.86 123.84) (width 0.155) (layer "B.Cu") (net 71))
  (segment (start 104.058816 125.434697) (end 104.028155 125.522323) (width 0.155) (layer "B.Cu") (net 71))
  (segment (start 104.86 126.24) (end 104.855988 126.275603) (width 0.155) (layer "B.Cu") (net 71))
  (segment (start 104.017761 126.865424) (end 104.028155 126.957676) (width 0.155) (layer "B.Cu") (net 71))
  (segment (start 104.799758 123.714906) (end 104.825093 123.740241) (width 0.155) (layer "B.Cu") (net 71))
  (segment (start 104.86 122.64) (end 104.855988 122.675603) (width 0.155) (layer "B.Cu") (net 71))
  (segment (start 104.108208 128.323908) (end 104.173852 128.389552) (width 0.155) (layer "B.Cu") (net 71))
  (segment (start 104.028155 128.157676) (end 104.058816 128.245302) (width 0.155) (layer "B.Cu") (net 71))
  (segment (start 104.855988 125.004396) (end 104.86 125.04) (width 0.155) (layer "B.Cu") (net 71))
  (segment (start 104.799758 126.365093) (end 104.769421 126.384155) (width 0.155) (layer "B.Cu") (net 71))
  (segment (start 104.86 136.05799) (end 105.36 136.55799) (width 0.155) (layer "B.Cu") (net 71))
  (segment (start 104.058816 124.234697) (end 104.028155 124.322323) (width 0.155) (layer "B.Cu") (net 71))
  (segment (start 104.017761 123.265424) (end 104.028155 123.357676) (width 0.155) (layer "B.Cu") (net 71))
  (segment (start 104.825093 122.739758) (end 104.799758 122.765093) (width 0.155) (layer "B.Cu") (net 71))
  (segment (start 104.017761 125.665424) (end 104.028155 125.757676) (width 0.155) (layer "B.Cu") (net 71))
  (segment (start 104.844155 123.770578) (end 104.855988 123.804396) (width 0.155) (layer "B.Cu") (net 71))
  (segment (start 104.173852 125.290447) (end 104.108208 125.356091) (width 0.155) (layer "B.Cu") (net 71))
  (segment (start 105.195 120.468306) (end 104.972499 120.690807) (width 0.155) (layer "B.Cu") (net 71))
  (segment (start 104.173852 124.789552) (end 104.252458 124.838944) (width 0.155) (layer "B.Cu") (net 71))
  (segment (start 104.108208 124.723908) (end 104.173852 124.789552) (width 0.155) (layer "B.Cu") (net 71))
  (segment (start 104.769421 126.095844) (end 104.799758 126.114906) (width 0.155) (layer "B.Cu") (net 71))
  (segment (start 104.252458 126.441055) (end 104.173852 126.490447) (width 0.155) (layer "B.Cu") (net 71))
  (segment (start 104.017761 128.014575) (end 104.017761 128.065424) (width 0.155) (layer "B.Cu") (net 71))
  (segment (start 104.735603 124.884011) (end 104.769421 124.895844) (width 0.155) (layer "B.Cu") (net 71))
  (segment (start 104.7 124.88) (end 104.735603 124.884011) (width 0.155) (layer "B.Cu") (net 71))
  (segment (start 104.340084 122.810394) (end 104.252458 122.841055) (width 0.155) (layer "B.Cu") (net 71))
  (segment (start 104.799758 126.114906) (end 104.825093 126.140241) (width 0.155) (layer "B.Cu") (net 71))
  (segment (start 104.173852 126.490447) (end 104.108208 126.556091) (width 0.155) (layer "B.Cu") (net 71))
  (segment (start 104.844155 126.170578) (end 104.855988 126.204396) (width 0.155) (layer "B.Cu") (net 71))
  (segment (start 104.825093 128.540241) (end 104.844155 128.570578) (width 0.155) (layer "B.Cu") (net 71))
  (segment (start 104.340084 124.010394) (end 104.252458 124.041055) (width 0.155) (layer "B.Cu") (net 71))
  (segment (start 104.340084 126.069605) (end 104.432336 126.08) (width 0.155) (layer "B.Cu") (net 71))
  (segment (start 104.058816 126.634697) (end 104.028155 126.722323) (width 0.155) (layer "B.Cu") (net 71))
  (segment (start 104.108208 124.156091) (end 104.058816 124.234697) (width 0.155) (layer "B.Cu") (net 71))
  (segment (start 104.028155 127.922323) (end 104.017761 128.014575) (width 0.155) (layer "B.Cu") (net 71))
  (segment (start 104.432336 126.08) (end 104.7 126.08) (width 0.155) (layer "B.Cu") (net 71))
  (segment (start 104.735603 122.795988) (end 104.7 122.8) (width 0.155) (layer "B.Cu") (net 71))
  (segment (start 104.844155 126.309421) (end 104.825093 126.339758) (width 0.155) (layer "B.Cu") (net 71))
  (segment (start 104.86 125.04) (end 104.855988 125.075603) (width 0.155) (layer "B.Cu") (net 71))
  (segment (start 104.108208 127.756091) (end 104.058816 127.834697) (width 0.155) (layer "B.Cu") (net 71))
  (segment (start 104.972499 120.690807) (end 104.711203 120.690807) (width 0.155) (layer "B.Cu") (net 71))
  (segment (start 104.825093 126.339758) (end 104.799758 126.365093) (width 0.155) (layer "B.Cu") (net 71))
  (segment (start 104.7 127.6) (end 104.432336 127.6) (width 0.155) (layer "B.Cu") (net 71))
  (segment (start 104.855988 123.875603) (end 104.844155 123.909421) (width 0.155) (layer "B.Cu") (net 71))
  (segment (start 104.252458 126.038944) (end 104.340084 126.069605) (width 0.155) (layer "B.Cu") (net 71))
  (segment (start 104.825093 127.539758) (end 104.799758 127.565093) (width 0.155) (layer "B.Cu") (net 71))
  (segment (start 104.108208 126.556091) (end 104.058816 126.634697) (width 0.155) (layer "B.Cu") (net 71))
  (segment (start 104.173852 123.589552) (end 104.252458 123.638944) (width 0.155) (layer "B.Cu") (net 71))
  (segment (start 104.058816 127.834697) (end 104.028155 127.922323) (width 0.155) (layer "B.Cu") (net 71))
  (segment (start 104.432336 126.4) (end 104.340084 126.410394) (width 0.155) (layer "B.Cu") (net 71))
  (segment (start 104.432336 125.2) (end 104.340084 125.210394) (width 0.155) (layer "B.Cu") (net 71))
  (segment (start 104.855988 125.075603) (end 104.844155 125.109421) (width 0.155) (layer "B.Cu") (net 71))
  (segment (start 104.735603 127.284011) (end 104.769421 127.295844) (width 0.155) (layer "B.Cu") (net 71))
  (segment (start 104.252458 127.238944) (end 104.340084 127.269605) (width 0.155) (layer "B.Cu") (net 71))
  (segment (start 104.799758 127.565093) (end 104.769421 127.584155) (width 0.155) (layer "B.Cu") (net 71))
  (segment (start 104.86 122.25799) (end 104.86 122.64) (width 0.155) (layer "B.Cu") (net 71))
  (segment (start 105.36 136.55799) (end 105.36 137.255) (width 0.155) (layer "B.Cu") (net 71))
  (segment (start 104.711203 120.690807) (end 104.26 121.14201) (width 0.155) (layer "B.Cu") (net 71))
  (segment (start 104.028155 125.757676) (end 104.058816 125.845302) (width 0.155) (layer "B.Cu") (net 71))
  (segment (start 104.252458 123.638944) (end 104.340084 123.669605) (width 0.155) (layer "B.Cu") (net 71))
  (segment (start 104.769421 128.495844) (end 104.799758 128.514906) (width 0.155) (layer "B.Cu") (net 71))
  (segment (start 104.7 128.48) (end 104.735603 128.484011) (width 0.155) (layer "B.Cu") (net 71))
  (segment (start 104.058816 127.045302) (end 104.108208 127.123908) (width 0.155) (layer "B.Cu") (net 71))
  (segment (start 104.432336 123.68) (end 104.7 123.68) (width 0.155) (layer "B.Cu") (net 71))
  (segment (start 104.173852 127.690447) (end 104.108208 127.756091) (width 0.155) (layer "B.Cu") (net 71))
  (segment (start 104.799758 123.965093) (end 104.769421 123.984155) (width 0.155) (layer "B.Cu") (net 71))
  (segment (start 104.844155 125.109421) (end 104.825093 125.139758) (width 0.155) (layer "B.Cu") (net 71))
  (segment (start 104.017761 123.214575) (end 104.017761 123.265424) (width 0.155) (layer "B.Cu") (net 71))
  (segment (start 104.825093 123.740241) (end 104.844155 123.770578) (width 0.155) (layer "B.Cu") (net 71))
  (segment (start 104.86 123.84) (end 104.855988 123.875603) (width 0.155) (layer "B.Cu") (net 71))
  (segment (start 104.108208 127.123908) (end 104.173852 127.189552) (width 0.155) (layer "B.Cu") (net 71))
  (segment (start 104.432336 124.88) (end 104.7 124.88) (width 0.155) (layer "B.Cu") (net 71))
  (segment (start 104.825093 126.140241) (end 104.844155 126.170578) (width 0.155) (layer "B.Cu") (net 71))
  (segment (start 104.017761 124.465424) (end 104.028155 124.557676) (width 0.155) (layer "B.Cu") (net 71))
  (segment (start 104.173852 128.389552) (end 104.252458 128.438944) (width 0.155) (layer "B.Cu") (net 71))
  (segment (start 105.36 137.255) (end 105 137.615) (width 0.155) (layer "B.Cu") (net 71))
  (segment (start 104.769421 123.984155) (end 104.735603 123.995988) (width 0.155) (layer "B.Cu") (net 71))
  (segment (start 104.86 127.44) (end 104.855988 127.475603) (width 0.155) (layer "B.Cu") (net 71))
  (segment (start 104.799758 128.514906) (end 104.825093 128.540241) (width 0.155) (layer "B.Cu") (net 71))
  (segment (start 104.252458 127.641055) (end 104.173852 127.690447) (width 0.155) (layer "B.Cu") (net 71))
  (segment (start 104.7 125.2) (end 104.432336 125.2) (width 0.155) (layer "B.Cu") (net 71))
  (segment (start 104.058816 124.645302) (end 104.108208 124.723908) (width 0.155) (layer "B.Cu") (net 71))
  (segment (start 104.855988 127.475603) (end 104.844155 127.509421) (width 0.155) (layer "B.Cu") (net 71))
  (segment (start 104.769421 125.184155) (end 104.735603 125.195988) (width 0.155) (layer "B.Cu") (net 71))
  (segment (start 104.855988 122.675603) (end 104.844155 122.709421) (width 0.155) (layer "B.Cu") (net 71))
  (segment (start 104.432336 124) (end 104.340084 124.010394) (width 0.155) (layer "B.Cu") (net 71))
  (segment (start 104.108208 125.923908) (end 104.173852 125.989552) (width 0.155) (layer "B.Cu") (net 71))
  (segment (start 104.017761 125.614575) (end 104.017761 125.665424) (width 0.155) (layer "B.Cu") (net 71))
  (segment (start 104.86 128.64) (end 104.86 136.05799) (width 0.155) (layer "B.Cu") (net 71))
  (segment (start 104.028155 124.322323) (end 104.017761 124.414575) (width 0.155) (layer "B.Cu") (net 71))
  (segment (start 104.769421 126.384155) (end 104.735603 126.395988) (width 0.155) (layer "B.Cu") (net 71))
  (segment (start 104.028155 126.722323) (end 104.017761 126.814575) (width 0.155) (layer "B.Cu") (net 71))
  (segment (start 104.432336 122.8) (end 104.340084 122.810394) (width 0.155) (layer "B.Cu") (net 71))
  (segment (start 104.340084 127.610394) (end 104.252458 127.641055) (width 0.155) (layer "B.Cu") (net 71))
  (segment (start 104.735603 128.484011) (end 104.769421 128.495844) (width 0.155) (layer "B.Cu") (net 71))
  (segment (start 104.252458 128.438944) (end 104.340084 128.469605) (width 0.155) (layer "B.Cu") (net 71))
  (segment (start 104.825093 125.139758) (end 104.799758 125.165093) (width 0.155) (layer "B.Cu") (net 71))
  (segment (start 104.825093 127.340241) (end 104.844155 127.370578) (width 0.155) (layer "B.Cu") (net 71))
  (segment (start 104.058816 125.845302) (end 104.108208 125.923908) (width 0.155) (layer "B.Cu") (net 71))
  (segment (start 104.058816 123.445302) (end 104.108208 123.523908) (width 0.155) (layer "B.Cu") (net 71))
  (segment (start 104.855988 126.275603) (end 104.844155 126.309421) (width 0.155) (layer "B.Cu") (net 71))
  (segment (start 104.844155 123.909421) (end 104.825093 123.939758) (width 0.155) (layer "B.Cu") (net 71))
  (segment (start 104.017761 124.414575) (end 104.017761 124.465424) (width 0.155) (layer "B.Cu") (net 71))
  (segment (start 104.799758 127.314906) (end 104.825093 127.340241) (width 0.155) (layer "B.Cu") (net 71))
  (segment (start 104.735603 123.684011) (end 104.769421 123.695844) (width 0.155) (layer "B.Cu") (net 71))
  (segment (start 104.735603 126.395988) (end 104.7 126.4) (width 0.155) (layer "B.Cu") (net 71))
  (segment (start 104.825093 124.940241) (end 104.844155 124.970578) (width 0.155) (layer "B.Cu") (net 71))
  (segment (start 104.432336 128.48) (end 104.7 128.48) (width 0.155) (layer "B.Cu") (net 71))
  (segment (start 104.844155 128.570578) (end 104.855988 128.604396) (width 0.155) (layer "B.Cu") (net 71))
  (segment (start 104.825093 123.939758) (end 104.799758 123.965093) (width 0.155) (layer "B.Cu") (net 71))
  (segment (start 104.769421 127.295844) (end 104.799758 127.314906) (width 0.155) (layer "B.Cu") (net 71))
  (segment (start 104.028155 123.357676) (end 104.058816 123.445302) (width 0.155) (layer "B.Cu") (net 71))
  (segment (start 104.340084 124.869605) (end 104.432336 124.88) (width 0.155) (layer "B.Cu") (net 71))
  (segment (start 104.26 121.65799) (end 104.86 122.25799) (width 0.155) (layer "B.Cu") (net 71))
  (segment (start 104.844155 124.970578) (end 104.855988 125.004396) (width 0.155) (layer "B.Cu") (net 71))
  (segment (start 104.340084 125.210394) (end 104.252458 125.241055) (width 0.155) (layer "B.Cu") (net 71))
  (segment (start 104.7 122.8) (end 104.432336 122.8) (width 0.155) (layer "B.Cu") (net 71))
  (segment (start 104.25 118.55) (end 104.25 119.750001) (width 0.155) (layer "F.Cu") (net 72))
  (segment (start 104.733344 120.970807) (end 104.972499 120.970807) (width 0.155) (layer "F.Cu") (net 72))
  (segment (start 104.36 120.597463) (end 104.733344 120.970807) (width 0.155) (layer "F.Cu") (net 72))
  (segment (start 104.36 119.860001) (end 104.36 120.597463) (width 0.155) (layer "F.Cu") (net 72))
  (segment (start 104.972499 120.970807) (end 105.195 121.193308) (width 0.155) (layer "F.Cu") (net 72))
  (segment (start 104.25 119.750001) (end 104.36 119.860001) (width 0.155) (layer "F.Cu") (net 72))
  (via (at 105.195 121.193308) (size 0.6) (drill 0.25) (layers "F.Cu" "B.Cu") (net 72))
  (segment (start 104.457761 128.2) (end 104.725424 128.2) (width 0.155) (layer "B.Cu") (net 72))
  (segment (start 104.313605 123.170578) (end 104.301772 123.204396) (width 0.155) (layer "B.Cu") (net 72))
  (segment (start 104.457761 127.88) (end 104.422157 127.884011) (width 0.155) (layer "B.Cu") (net 72))
  (segment (start 104.313605 124.509421) (end 104.332667 124.539758) (width 0.155) (layer "B.Cu") (net 72))
  (segment (start 104.817676 125.469605) (end 104.725424 125.48) (width 0.155) (layer "B.Cu") (net 72))
  (segment (start 104.313605 126.909421) (end 104.332667 126.939758) (width 0.155) (layer "B.Cu") (net 72))
  (segment (start 104.817676 123.069605) (end 104.725424 123.08) (width 0.155) (layer "B.Cu") (net 72))
  (segment (start 104.297761 124.44) (end 104.301772 124.475603) (width 0.155) (layer "B.Cu") (net 72))
  (segment (start 104.817676 124.610394) (end 104.905302 124.641055) (width 0.155) (layer "B.Cu") (net 72))
  (segment (start 105.14 125.014575) (end 105.14 125.065424) (width 0.155) (layer "B.Cu") (net 72))
  (segment (start 104.301772 125.675603) (end 104.313605 125.709421) (width 0.155) (layer "B.Cu") (net 72))
  (segment (start 105.098944 123.634697) (end 105.129605 123.722323) (width 0.155) (layer "B.Cu") (net 72))
  (segment (start 104.301772 126.804396) (end 104.297761 126.84) (width 0.155) (layer "B.Cu") (net 72))
  (segment (start 104.457761 126.68) (end 104.422157 126.684011) (width 0.155) (layer "B.Cu") (net 72))
  (segment (start 104.422157 125.484011) (end 104.388339 125.495844) (width 0.155) (layer "B.Cu") (net 72))
  (segment (start 104.388339 125.784155) (end 104.422157 125.795988) (width 0.155) (layer "B.Cu") (net 72))
  (segment (start 104.725424 125.48) (end 104.457761 125.48) (width 0.155) (layer "B.Cu") (net 72))
  (segment (start 104.725424 124.6) (end 104.817676 124.610394) (width 0.155) (layer "B.Cu") (net 72))
  (segment (start 105.14 135.94201) (end 105.64 136.44201) (width 0.155) (layer "B.Cu") (net 72))
  (segment (start 104.301772 128.075603) (end 104.313605 128.109421) (width 0.155) (layer "B.Cu") (net 72))
  (segment (start 104.725424 125.8) (end 104.817676 125.810394) (width 0.155) (layer "B.Cu") (net 72))
  (segment (start 105.14 125.065424) (end 105.129605 125.157676) (width 0.155) (layer "B.Cu") (net 72))
  (segment (start 104.358002 127.914906) (end 104.332667 127.940241) (width 0.155) (layer "B.Cu") (net 72))
  (segment (start 104.332667 127.940241) (end 104.313605 127.970578) (width 0.155) (layer "B.Cu") (net 72))
  (segment (start 104.905302 125.841055) (end 104.983908 125.890447) (width 0.155) (layer "B.Cu") (net 72))
  (segment (start 105.129605 124.922323) (end 105.14 125.014575) (width 0.155) (layer "B.Cu") (net 72))
  (segment (start 105.049552 124.123908) (end 104.983908 124.189552) (width 0.155) (layer "B.Cu") (net 72))
  (segment (start 104.422157 128.195988) (end 104.457761 128.2) (width 0.155) (layer "B.Cu") (net 72))
  (segment (start 104.422157 123.084011) (end 104.388339 123.095844) (width 0.155) (layer "B.Cu") (net 72))
  (segment (start 104.388339 126.984155) (end 104.422157 126.995988) (width 0.155) (layer "B.Cu") (net 72))
  (segment (start 105.098944 126.445302) (end 105.049552 126.523908) (width 0.155) (layer "B.Cu") (net 72))
  (segment (start 104.332667 126.740241) (end 104.313605 126.770578) (width 0.155) (layer "B.Cu") (net 72))
  (segment (start 105.129605 123.722323) (end 105.14 123.814575) (width 0.155) (layer "B.Cu") (net 72))
  (segment (start 104.54 121.25799) (end 104.54 121.54201) (width 0.155) (layer "B.Cu") (net 72))
  (segment (start 105.14 126.214575) (end 105.14 126.265424) (width 0.155) (layer "B.Cu") (net 72))
  (segment (start 104.725424 123.08) (end 104.457761 123.08) (width 0.155) (layer "B.Cu") (net 72))
  (segment (start 104.358002 124.565093) (end 104.388339 124.584155) (width 0.155) (layer "B.Cu") (net 72))
  (segment (start 105.129605 125.157676) (end 105.098944 125.245302) (width 0.155) (layer "B.Cu") (net 72))
  (segment (start 104.388339 126.695844) (end 104.358002 126.714906) (width 0.155) (layer "B.Cu") (net 72))
  (segment (start 104.983908 125.389552) (end 104.905302 125.438944) (width 0.155) (layer "B.Cu") (net 72))
  (segment (start 105.098944 125.245302) (end 105.049552 125.323908) (width 0.155) (layer "B.Cu") (net 72))
  (segment (start 104.905302 123.038944) (end 104.817676 123.069605) (width 0.155) (layer "B.Cu") (net 72))
  (segment (start 104.905302 125.438944) (end 104.817676 125.469605) (width 0.155) (layer "B.Cu") (net 72))
  (segment (start 104.332667 123.339758) (end 104.358002 123.365093) (width 0.155) (layer "B.Cu") (net 72))
  (segment (start 104.388339 123.384155) (end 104.422157 123.395988) (width 0.155) (layer "B.Cu") (net 72))
  (segment (start 104.725424 127.88) (end 104.457761 127.88) (width 0.155) (layer "B.Cu") (net 72))
  (segment (start 104.457761 124.6) (end 104.725424 124.6) (width 0.155) (layer "B.Cu") (net 72))
  (segment (start 104.817676 125.810394) (end 104.905302 125.841055) (width 0.155) (layer "B.Cu") (net 72))
  (segment (start 105.14 123.865424) (end 105.129605 123.957676) (width 0.155) (layer "B.Cu") (net 72))
  (segment (start 104.388339 123.095844) (end 104.358002 123.114906) (width 0.155) (layer "B.Cu") (net 72))
  (segment (start 104.313605 127.970578) (end 104.301772 128.004396) (width 0.155) (layer "B.Cu") (net 72))
  (segment (start 104.725424 126.68) (end 104.457761 126.68) (width 0.155) (layer "B.Cu") (net 72))
  (segment (start 105.195 121.193308) (end 104.972499 120.970807) (width 0.155) (layer "B.Cu") (net 72))
  (segment (start 104.983908 127.090447) (end 105.049552 127.156091) (width 0.155) (layer "B.Cu") (net 72))
  (segment (start 105.098944 126.034697) (end 105.129605 126.122323) (width 0.155) (layer "B.Cu") (net 72))
  (segment (start 104.301772 123.275603) (end 104.313605 123.309421) (width 0.155) (layer "B.Cu") (net 72))
  (segment (start 104.388339 125.495844) (end 104.358002 125.514906) (width 0.155) (layer "B.Cu") (net 72))
  (segment (start 104.301772 125.604396) (end 104.297761 125.64) (width 0.155) (layer "B.Cu") (net 72))
  (segment (start 105.129605 122.757676) (end 105.098944 122.845302) (width 0.155) (layer "B.Cu") (net 72))
  (segment (start 104.332667 123.140241) (end 104.313605 123.170578) (width 0.155) (layer "B.Cu") (net 72))
  (segment (start 105.64 136.44201) (end 105.64 137.255) (width 0.155) (layer "B.Cu") (net 72))
  (segment (start 104.817676 124.269605) (end 104.725424 124.28) (width 0.155) (layer "B.Cu") (net 72))
  (segment (start 104.313605 123.309421) (end 104.332667 123.339758) (width 0.155) (layer "B.Cu") (net 72))
  (segment (start 104.301772 128.004396) (end 104.297761 128.04) (width 0.155) (layer "B.Cu") (net 72))
  (segment (start 105.049552 125.323908) (end 104.983908 125.389552) (width 0.155) (layer "B.Cu") (net 72))
  (segment (start 104.422157 127.884011) (end 104.388339 127.895844) (width 0.155) (layer "B.Cu") (net 72))
  (segment (start 104.332667 124.539758) (end 104.358002 124.565093) (width 0.155) (layer "B.Cu") (net 72))
  (segment (start 104.301772 123.204396) (end 104.297761 123.24) (width 0.155) (layer "B.Cu") (net 72))
  (segment (start 104.983908 123.490447) (end 105.049552 123.556091) (width 0.155) (layer "B.Cu") (net 72))
  (segment (start 104.388339 128.184155) (end 104.422157 128.195988) (width 0.155) (layer "B.Cu") (net 72))
  (segment (start 104.725424 123.4) (end 104.817676 123.410394) (width 0.155) (layer "B.Cu") (net 72))
  (segment (start 105.049552 126.523908) (end 104.983908 126.589552) (width 0.155) (layer "B.Cu") (net 72))
  (segment (start 104.422157 123.395988) (end 104.457761 123.4) (width 0.155) (layer "B.Cu") (net 72))
  (segment (start 104.422157 124.595988) (end 104.457761 124.6) (width 0.155) (layer "B.Cu") (net 72))
  (segment (start 105.129605 123.957676) (end 105.098944 124.045302) (width 0.155) (layer "B.Cu") (net 72))
  (segment (start 105.14 126.265424) (end 105.129605 126.357676) (width 0.155) (layer "B.Cu") (net 72))
  (segment (start 104.313605 125.709421) (end 104.332667 125.739758) (width 0.155) (layer "B.Cu") (net 72))
  (segment (start 104.297761 125.64) (end 104.301772 125.675603) (width 0.155) (layer "B.Cu") (net 72))
  (segment (start 105.049552 125.956091) (end 105.098944 126.034697) (width 0.155) (layer "B.Cu") (net 72))
  (segment (start 104.457761 127) (end 104.725424 127) (width 0.155) (layer "B.Cu") (net 72))
  (segment (start 104.313605 125.570578) (end 104.301772 125.604396) (width 0.155) (layer "B.Cu") (net 72))
  (segment (start 104.358002 126.965093) (end 104.388339 126.984155) (width 0.155) (layer "B.Cu") (net 72))
  (segment (start 104.725424 124.28) (end 104.457761 124.28) (width 0.155) (layer "B.Cu") (net 72))
  (segment (start 105.049552 124.756091) (end 105.098944 124.834697) (width 0.155) (layer "B.Cu") (net 72))
  (segment (start 104.358002 125.765093) (end 104.388339 125.784155) (width 0.155) (layer "B.Cu") (net 72))
  (segment (start 104.905302 126.638944) (end 104.817676 126.669605) (width 0.155) (layer "B.Cu") (net 72))
  (segment (start 104.983908 126.589552) (end 104.905302 126.638944) (width 0.155) (layer "B.Cu") (net 72))
  (segment (start 104.358002 128.165093) (end 104.388339 128.184155) (width 0.155) (layer "B.Cu") (net 72))
  (segment (start 105.14 127.414575) (end 105.14 127.465424) (width 0.155) (layer "B.Cu") (net 72))
  (segment (start 104.983908 128.290447) (end 105.049552 128.356091) (width 0.155) (layer "B.Cu") (net 72))
  (segment (start 104.905302 124.641055) (end 104.983908 124.690447) (width 0.155) (layer "B.Cu") (net 72))
  (segment (start 105.64 137.255) (end 106 137.615) (width 0.155) (layer "B.Cu") (net 72))
  (segment (start 104.332667 125.739758) (end 104.358002 125.765093) (width 0.155) (layer "B.Cu") (net 72))
  (segment (start 105.14 123.814575) (end 105.14 123.865424) (width 0.155) (layer "B.Cu") (net 72))
  (segment (start 105.129605 127.322323) (end 105.14 127.414575) (width 0.155) (layer "B.Cu") (net 72))
  (segment (start 104.905302 124.238944) (end 104.817676 124.269605) (width 0.155) (layer "B.Cu") (net 72))
  (segment (start 104.358002 125.514906) (end 104.332667 125.540241) (width 0.155) (layer "B.Cu") (net 72))
  (segment (start 104.983908 127.789552) (end 104.905302 127.838944) (width 0.155) (layer "B.Cu") (net 72))
  (segment (start 104.332667 124.340241) (end 104.313605 124.370578) (width 0.155) (layer "B.Cu") (net 72))
  (segment (start 104.905302 127.838944) (end 104.817676 127.869605) (width 0.155) (layer "B.Cu") (net 72))
  (segment (start 104.301772 124.404396) (end 104.297761 124.44) (width 0.155) (layer "B.Cu") (net 72))
  (segment (start 104.457761 124.28) (end 104.422157 124.284011) (width 0.155) (layer "B.Cu") (net 72))
  (segment (start 104.297761 126.84) (end 104.301772 126.875603) (width 0.155) (layer "B.Cu") (net 72))
  (segment (start 104.972499 120.970807) (end 104.827183 120.970807) (width 0.155) (layer "B.Cu") (net 72))
  (segment (start 105.14 128.614575) (end 105.14 135.94201) (width 0.155) (layer "B.Cu") (net 72))
  (segment (start 104.725424 127) (end 104.817676 127.010394) (width 0.155) (layer "B.Cu") (net 72))
  (segment (start 104.388339 124.295844) (end 104.358002 124.314906) (width 0.155) (layer "B.Cu") (net 72))
  (segment (start 104.817676 123.410394) (end 104.905302 123.441055) (width 0.155) (layer "B.Cu") (net 72))
  (segment (start 105.129605 127.557676) (end 105.098944 127.645302) (width 0.155) (layer "B.Cu") (net 72))
  (segment (start 105.098944 122.845302) (end 105.049552 122.923908) (width 0.155) (layer "B.Cu") (net 72))
  (segment (start 104.817676 126.669605) (end 104.725424 126.68) (width 0.155) (layer "B.Cu") (net 72))
  (segment (start 105.049552 127.156091) (end 105.098944 127.234697) (width 0.155) (layer "B.Cu") (net 72))
  (segment (start 104.905302 128.241055) (end 104.983908 128.290447) (width 0.155) (layer "B.Cu") (net 72))
  (segment (start 104.301772 126.875603) (end 104.313605 126.909421) (width 0.155) (layer "B.Cu") (net 72))
  (segment (start 105.129605 126.357676) (end 105.098944 126.445302) (width 0.155) (layer "B.Cu") (net 72))
  (segment (start 105.14 122.665424) (end 105.129605 122.757676) (width 0.155) (layer "B.Cu") (net 72))
  (segment (start 105.129605 128.522323) (end 105.14 128.614575) (width 0.155) (layer "B.Cu") (net 72))
  (segment (start 104.983908 124.690447) (end 105.049552 124.756091) (width 0.155) (layer "B.Cu") (net 72))
  (segment (start 104.388339 124.584155) (end 104.422157 124.595988) (width 0.155) (layer "B.Cu") (net 72))
  (segment (start 105.129605 126.122323) (end 105.14 126.214575) (width 0.155) (layer "B.Cu") (net 72))
  (segment (start 105.098944 127.234697) (end 105.129605 127.322323) (width 0.155) (layer "B.Cu") (net 72))
  (segment (start 104.313605 126.770578) (end 104.301772 126.804396) (width 0.155) (layer "B.Cu") (net 72))
  (segment (start 104.817676 127.010394) (end 104.905302 127.041055) (width 0.155) (layer "B.Cu") (net 72))
  (segment (start 105.098944 124.045302) (end 105.049552 124.123908) (width 0.155) (layer "B.Cu") (net 72))
  (segment (start 104.358002 124.314906) (end 104.332667 124.340241) (width 0.155) (layer "B.Cu") (net 72))
  (segment (start 104.422157 126.995988) (end 104.457761 127) (width 0.155) (layer "B.Cu") (net 72))
  (segment (start 104.457761 125.48) (end 104.422157 125.484011) (width 0.155) (layer "B.Cu") (net 72))
  (segment (start 104.422157 126.684011) (end 104.388339 126.695844) (width 0.155) (layer "B.Cu") (net 72))
  (segment (start 104.457761 123.08) (end 104.422157 123.084011) (width 0.155) (layer "B.Cu") (net 72))
  (segment (start 104.905302 123.441055) (end 104.983908 123.490447) (width 0.155) (layer "B.Cu") (net 72))
  (segment (start 104.457761 123.4) (end 104.725424 123.4) (width 0.155) (layer "B.Cu") (net 72))
  (segment (start 105.098944 127.645302) (end 105.049552 127.723908) (width 0.155) (layer "B.Cu") (net 72))
  (segment (start 104.983908 124.189552) (end 104.905302 124.238944) (width 0.155) (layer "B.Cu") (net 72))
  (segment (start 105.098944 124.834697) (end 105.129605 124.922323) (width 0.155) (layer "B.Cu") (net 72))
  (segment (start 104.983908 122.989552) (end 104.905302 123.038944) (width 0.155) (layer "B.Cu") (net 72))
  (segment (start 104.297761 128.04) (end 104.301772 128.075603) (width 0.155) (layer "B.Cu") (net 72))
  (segment (start 104.422157 125.795988) (end 104.457761 125.8) (width 0.155) (layer "B.Cu") (net 72))
  (segment (start 104.54 121.54201) (end 105.14 122.14201) (width 0.155) (layer "B.Cu") (net 72))
  (segment (start 104.301772 124.475603) (end 104.313605 124.509421) (width 0.155) (layer "B.Cu") (net 72))
  (segment (start 104.457761 125.8) (end 104.725424 125.8) (width 0.155) (layer "B.Cu") (net 72))
  (segment (start 105.14 127.465424) (end 105.129605 127.557676) (width 0.155) (layer "B.Cu") (net 72))
  (segment (start 104.313605 124.370578) (end 104.301772 124.404396) (width 0.155) (layer "B.Cu") (net 72))
  (segment (start 105.14 122.14201) (end 105.14 122.665424) (width 0.155) (layer "B.Cu") (net 72))
  (segment (start 104.297761 123.24) (end 104.301772 123.275603) (width 0.155) (layer "B.Cu") (net 72))
  (segment (start 105.049552 127.723908) (end 104.983908 127.789552) (width 0.155) (layer "B.Cu") (net 72))
  (segment (start 104.388339 127.895844) (end 104.358002 127.914906) (width 0.155) (layer "B.Cu") (net 72))
  (segment (start 104.817676 127.869605) (end 104.725424 127.88) (width 0.155) (layer "B.Cu") (net 72))
  (segment (start 104.422157 124.284011) (end 104.388339 124.295844) (width 0.155) (layer "B.Cu") (net 72))
  (segment (start 104.827183 120.970807) (end 104.54 121.25799) (width 0.155) (layer "B.Cu") (net 72))
  (segment (start 104.358002 123.114906) (end 104.332667 123.140241) (width 0.155) (layer "B.Cu") (net 72))
  (segment (start 104.905302 127.041055) (end 104.983908 127.090447) (width 0.155) (layer "B.Cu") (net 72))
  (segment (start 104.332667 125.540241) (end 104.313605 125.570578) (width 0.155) (layer "B.Cu") (net 72))
  (segment (start 104.313605 128.109421) (end 104.332667 128.139758) (width 0.155) (layer "B.Cu") (net 72))
  (segment (start 104.358002 123.365093) (end 104.388339 123.384155) (width 0.155) (layer "B.Cu") (net 72))
  (segment (start 104.332667 126.939758) (end 104.358002 126.965093) (width 0.155) (layer "B.Cu") (net 72))
  (segment (start 104.817676 128.210394) (end 104.905302 128.241055) (width 0.155) (layer "B.Cu") (net 72))
  (segment (start 104.983908 125.890447) (end 105.049552 125.956091) (width 0.155) (layer "B.Cu") (net 72))
  (segment (start 105.049552 128.356091) (end 105.098944 128.434697) (width 0.155) (layer "B.Cu") (net 72))
  (segment (start 105.049552 123.556091) (end 105.098944 123.634697) (width 0.155) (layer "B.Cu") (net 72))
  (segment (start 105.098944 128.434697) (end 105.129605 128.522323) (width 0.155) (layer "B.Cu") (net 72))
  (segment (start 104.725424 128.2) (end 104.817676 128.210394) (width 0.155) (layer "B.Cu") (net 72))
  (segment (start 104.332667 128.139758) (end 104.358002 128.165093) (width 0.155) (layer "B.Cu") (net 72))
  (segment (start 105.049552 122.923908) (end 104.983908 122.989552) (width 0.155) (layer "B.Cu") (net 72))
  (segment (start 104.358002 126.714906) (end 104.332667 126.740241) (width 0.155) (layer "B.Cu") (net 72))
  (via (at 65.5 110.5) (size 0.6) (drill 0.25) (layers "F.Cu" "B.Cu") (net 73))
  (via (at 58.9 101.8) (size 0.6) (drill 0.25) (layers "F.Cu" "B.Cu") (net 73))
  (via (at 66.5 110.5) (size 0.6) (drill 0.25) (layers "F.Cu" "B.Cu") (net 73))
  (via (at 65.5 112) (size 0.6) (drill 0.25) (layers "F.Cu" "B.Cu") (net 73))
  (via (at 66.5 112) (size 0.6) (drill 0.25) (layers "F.Cu" "B.Cu") (net 73))
  (via (at 67.5 110.5) (size 0.6) (drill 0.25) (layers "F.Cu" "B.Cu") (net 73))
  (via (at 68 111.25) (size 0.6) (drill 0.25) (layers "F.Cu" "B.Cu") (net 73))
  (via (at 67.35 122.55) (size 0.6) (drill 0.25) (layers "F.Cu" "B.Cu") (net 73))
  (via (at 65 111.25) (size 0.6) (drill 0.25) (layers "F.Cu" "B.Cu") (net 73))
  (via (at 67 111.25) (size 0.6) (drill 0.25) (layers "F.Cu" "B.Cu") (net 73))
  (via (at 64.5 112) (size 0.6) (drill 0.25) (layers "F.Cu" "B.Cu") (net 73))
  (via (at 67.5 112) (size 0.6) (drill 0.25) (layers "F.Cu" "B.Cu") (net 73))
  (via (at 66 111.25) (size 0.6) (drill 0.25) (layers "F.Cu" "B.Cu") (net 73))
  (via (at 64.5 110.5) (size 0.6) (drill 0.25) (layers "F.Cu" "B.Cu") (net 73))
  (segment (start 63.4 115.9) (end 64 116.5) (width 0.15) (layer "B.Cu") (net 73))
  (segment (start 68.6 122.575) (end 67.375 122.575) (width 0.2) (layer "B.Cu") (net 73))
  (segment (start 62.15 118.5) (end 63.95 118.5) (width 0.15) (layer "B.Cu") (net 73))
  (segment (start 62.605 112.212) (end 62.605 113.58) (width 0.15) (layer "B.Cu") (net 73))
  (segment (start 62.605 113.58) (end 62.385 113.8) (width 0.15) (layer "B.Cu") (net 73))
  (segment (start 67.375 122.575) (end 67.35 122.55) (width 0.2) (layer "B.Cu") (net 73))
  (segment (start 58.915 101.815) (end 58.9 101.8) (width 0.15) (layer "B.Cu") (net 73))
  (segment (start 58.915 103.2) (end 58.915 101.815) (width 0.15) (layer "B.Cu") (net 73))
  (segment (start 64 116.5) (end 64 118.45) (width 0.15) (layer "B.Cu") (net 73))
  (segment (start 62.385 113.8) (end 62.385 115.285) (width 0.15) (layer "B.Cu") (net 73))
  (segment (start 73.697601 122.447601) (end 73.5 122.25) (width 0.15) (layer "F.Cu") (net 74))
  (segment (start 76.485 137.3) (end 76.485 135.25) (width 0.2) (layer "F.Cu") (net 74))
  (segment (start 86.7 101.9) (end 85.9 101.9) (width 0.15) (layer "F.Cu") (net 74))
  (segment (start 74 122.447601) (end 73.697601 122.447601) (width 0.15) (layer "F.Cu") (net 74))
  (segment (start 76.485 136.3) (end 76.485 135.25) (width 0.15) (layer "F.Cu") (net 74))
  (segment (start 76 128.9) (end 75.15 128.9) (width 0.2) (layer "F.Cu") (net 74))
  (segment (start 83.45 102.285) (end 84.815 102.285) (width 0.155) (layer "F.Cu") (net 74))
  (segment (start 86.9 103.215) (end 86.9 102.1) (width 0.15) (layer "F.Cu") (net 74))
  (segment (start 85.9 101.9) (end 85.2 101.9) (width 0.15) (layer "F.Cu") (net 74))
  (segment (start 84.815 102.285) (end 85.2 101.9) (width 0.155) (layer "F.Cu") (net 74))
  (segment (start 86.9 102.1) (end 86.7 101.9) (width 0.15) (layer "F.Cu") (net 74))
  (segment (start 74.95 129.1) (end 74.95 129.715) (width 0.2) (layer "F.Cu") (net 74))
  (segment (start 82.65 123) (end 82.65 123.95) (width 0.15) (layer "F.Cu") (net 74))
  (segment (start 76.485 137.3) (end 76.485 136.3) (width 0.2) (layer "F.Cu") (net 74))
  (segment (start 75.15 128.9) (end 74.95 129.1) (width 0.2) (layer "F.Cu") (net 74))
  (via (at 75.6 114.6) (size 0.6) (drill 0.25) (layers "F.Cu" "B.Cu") (net 74))
  (via (at 75.6 115.2) (size 0.6) (drill 0.25) (layers "F.Cu" "B.Cu") (net 74))
  (via (at 75.65 109.35) (size 0.6) (drill 0.25) (layers "F.Cu" "B.Cu") (net 74))
  (via (at 75.05 108.75) (size 0.6) (drill 0.25) (layers "F.Cu" "B.Cu") (net 74))
  (via (at 75.65 108.75) (size 0.6) (drill 0.25) (layers "F.Cu" "B.Cu") (net 74))
  (via (at 75.05 109.95) (size 0.6) (drill 0.25) (layers "F.Cu" "B.Cu") (free) (net 74))
  (via (at 75.05 109.35) (size 0.6) (drill 0.25) (layers "F.Cu" "B.Cu") (net 74))
  (via (at 75.65 109.95) (size 0.6) (drill 0.25) (layers "F.Cu" "B.Cu") (free) (net 74))
  (via (at 82.65 123) (size 0.6) (drill 0.25) (layers "F.Cu" "B.Cu") (net 74))
  (via (at 76.485 135.25) (size 0.6) (drill 0.25) (layers "F.Cu" "B.Cu") (net 74))
  (via (at 77.2 128.9) (size 0.6) (drill 0.25) (layers "F.Cu" "B.Cu") (net 74))
  (via (at 75.6 115.8) (size 0.6) (drill 0.25) (layers "F.Cu" "B.Cu") (free) (net 74))
  (via (at 73.5 122.25) (size 0.6) (drill 0.25) (layers "F.Cu" "B.Cu") (net 74))
  (via (at 85.2 101.9) (size 0.6) (drill 0.25) (layers "F.Cu" "B.Cu") (net 74))
  (via (at 81.4 99) (size 0.6) (drill 0.25) (layers "F.Cu" "B.Cu") (free) (net 74))
  (via (at 81.4 98.2) (size 0.6) (drill 0.25) (layers "F.Cu" "B.Cu") (free) (net 74))
  (via (at 74.45 120.25) (size 0.6) (drill 0.25) (layers "F.Cu" "B.Cu") (net 74))
  (via (at 77.2 128.3) (size 0.6) (drill 0.25) (layers "F.Cu" "B.Cu") (net 74))
  (via (at 75 115.2) (size 0.6) (drill 0.25) (layers "F.Cu" "B.Cu") (net 74))
  (via (at 79 128.3) (size 0.6) (drill 0.25) (layers "F.Cu" "B.Cu") (net 74))
  (via (at 76.6 128.3) (size 0.6) (drill 0.25) (layers "F.Cu" "B.Cu") (net 74))
  (via (at 78.4 128.3) (size 0.6) (drill 0.25) (layers "F.Cu" "B.Cu") (net 74))
  (via (at 76 128.3) (size 0.6) (drill 0.25) (layers "F.Cu" "B.Cu") (net 74))
  (via (at 76 128.9) (size 0.6) (drill 0.25) (layers "F.Cu" "B.Cu") (net 74))
  (via (at 77.8 128.9) (size 0.6) (drill 0.25) (layers "F.Cu" "B.Cu") (net 74))
  (via (at 75 114.6) (size 0.6) (drill 0.25) (layers "F.Cu" "B.Cu") (net 74))
  (via (at 79.6 128.3) (size 0.6) (drill 0.25) (layers "F.Cu" "B.Cu") (net 74))
  (via (at 81.9 98.6) (size 0.6) (drill 0.25) (layers "F.Cu" "B.Cu") (free) (net 74))
  (via (at 76.6 128.9) (size 0.6) (drill 0.25) (layers "F.Cu" "B.Cu") (net 74))
  (via (at 81.8 128.3) (size 0.6) (drill 0.25) (layers "F.Cu" "B.Cu") (net 74))
  (via (at 77.8 128.3) (size 0.6) (drill 0.25) (layers "F.Cu" "B.Cu") (net 74))
  (via (at 79 128.9) (size 0.6) (drill 0.25) (layers "F.Cu" "B.Cu") (net 74))
  (via (at 78.4 128.9) (size 0.6) (drill 0.25) (layers "F.Cu" "B.Cu") (net 74))
  (via (at 79.6 128.9) (size 0.6) (drill 0.25) (layers "F.Cu" "B.Cu") (net 74))
  (via (at 75 115.8) (size 0.6) (drill 0.25) (layers "F.Cu" "B.Cu") (net 74))
  (segment (start 82.3 123.35) (end 82.3 127.8) (width 0.125) (layer "In2.Cu") (net 74))
  (segment (start 82.65 123) (end 82.3 123.35) (width 0.125) (layer "In2.Cu") (net 74))
  (segment (start 82.3 127.8) (end 81.8 128.3) (width 0.125) (layer "In2.Cu") (net 74))
  (segment (start 86 128) (end 86 125) (width 0.15) (layer "B.Cu") (net 74))
  (segment (start 75.9 114.6) (end 75.6 114.6) (width 0.15) (layer "B.Cu") (net 74))
  (segment (start 72.7 115.8) (end 72.2 116.3) (width 0.15) (layer "B.Cu") (net 74))
  (segment (start 75.115 120.25) (end 75.115 121.25) (width 0.15) (layer "B.Cu") (net 74))
  (segment (start 86 125) (end 86.4 124.6) (width 0.15) (layer "B.Cu") (net 74))
  (segment (start 86.4 124.6) (end 87.2 124.6) (width 0.15) (layer "B.Cu") (net 74))
  (segment (start 82.9 99) (end 82.9 100.9) (width 0.155) (layer "B.Cu") (net 74))
  (segment (start 75 115.8) (end 72.7 115.8) (width 0.15) (layer "B.Cu") (net 74))
  (segment (start 78.5 112) (end 75.9 114.6) (width 0.15) (layer "B.Cu") (net 74))
  (segment (start 82.65 128.29) (end 81.81 128.29) (width 0.125) (layer "B.Cu") (net 74))
  (segment (start 75.115 120.25) (end 74.45 120.25) (width 0.15) (layer "B.Cu") (net 74))
  (segment (start 85.7 128.3) (end 86 128) (width 0.15) (layer "B.Cu") (net 74))
  (segment (start 72.2 116.3) (end 72.2 117.55) (width 0.15) (layer "B.Cu") (net 74))
  (segment (start 82.9 100.9) (end 83.9 101.9) (width 0.155) (layer "B.Cu") (net 74))
  (segment (start 87.2 124.6) (end 87.6 124.2) (width 0.15) (layer "B.Cu") (net 74))
  (segment (start 81.81 128.29) (end 81.8 128.3) (width 0.125) (layer "B.Cu") (net 74))
  (segment (start 84.15 128.3) (end 85.7 128.3) (width 0.15) (layer "B.Cu") (net 74))
  (segment (start 83.9 101.9) (end 85.2 101.9) (width 0.155) (layer "B.Cu") (net 74))
  (segment (start 85.2 101.9) (end 86.1 101.9) (width 0.2) (layer "B.Cu") (net 74))
  (segment (start 87.6 119.2) (end 87.6 124.2) (width 0.15) (layer "B.Cu") (net 74))
  (segment (start 86.1 101.9) (end 87.6 100.4) (width 0.2) (layer "B.Cu") (net 74))
  (segment (start 151.285 134.2) (end 152.25 134.2) (width 0.2) (layer "F.Cu") (net 75))
  (segment (start 57.84 84.84) (end 57.84 88.64) (width 0.15) (layer "B.Cu") (net 76))
  (segment (start 57.84 88.64) (end 58.4 89.2) (width 0.15) (layer "B.Cu") (net 76))
  (segment (start 60.1 103.415) (end 59.885 103.2) (width 0.155) (layer "B.Cu") (net 76))
  (segment (start 60.4 89.2) (end 60.915 89.715) (width 0.15) (layer "B.Cu") (net 76))
  (segment (start 61.515 101.32) (end 60.945 101.32) (width 0.2) (layer "B.Cu") (net 76))
  (segment (start 60.1 104.215) (end 60.1 103.415) (width 0.155) (layer "B.Cu") (net 76))
  (segment (start 58.4 89.2) (end 60.4 89.2) (width 0.15) (layer "B.Cu") (net 76))
  (segment (start 60.915 103.2) (end 60.915 101.485) (width 0.155) (layer "B.Cu") (net 76))
  (segment (start 60.915 101.485) (end 60.915 89.715) (width 0.155) (layer "B.Cu") (net 76))
  (segment (start 60.915 103.2) (end 59.885 103.2) (width 0.155) (layer "B.Cu") (net 76))
  (segment (start 59.6 144.8) (end 71.915 144.8) (width 0.15) (layer "B.Cu") (net 77))
  (segment (start 59.9 144.8) (end 59.6 144.8) (width 0.15) (layer "B.Cu") (net 77))
  (segment (start 71.915 144.8) (end 72.415 144.3) (width 0.15) (layer "B.Cu") (net 77))
  (segment (start 57.9 144.8) (end 57.574998 145.125002) (width 0.15) (layer "B.Cu") (net 77))
  (segment (start 59.6 144.8) (end 57.9 144.8) (width 0.15) (layer "B.Cu") (net 77))
  (segment (start 57.574998 145.125002) (end 57.574998 146.659999) (width 0.15) (layer "B.Cu") (net 77))
  (segment (start 71.915 144.8) (end 59.9 144.8) (width 0.125) (layer "B.Cu") (net 77))
  (segment (start 68.315002 145.484998) (end 68.5 145.3) (width 0.15) (layer "B.Cu") (net 78))
  (segment (start 68.315002 146.659999) (end 68.315002 145.484998) (width 0.15) (layer "B.Cu") (net 78))
  (segment (start 68.5 145.3) (end 72.415 145.3) (width 0.15) (layer "B.Cu") (net 78))
  (segment (start 116 143.04) (end 116 142.514999) (width 0.155) (layer "F.Cu") (net 79))
  (segment (start 115.89 141.8225) (end 116.1125 141.6) (width 0.155) (layer "F.Cu") (net 79))
  (segment (start 116 142.514999) (end 115.89 142.404999) (width 0.155) (layer "F.Cu") (net 79))
  (segment (start 115.89 142.404999) (end 115.89 141.8225) (width 0.155) (layer "F.Cu") (net 79))
  (segment (start 114.836474 146.79432) (end 114.52181 146.79432) (width 0.155) (layer "F.Cu") (net 79))
  (segment (start 115.36 145.375001) (end 115.36 146.270794) (width 0.155) (layer "F.Cu") (net 79))
  (segment (start 115.25 145.265001) (end 115.36 145.375001) (width 0.155) (layer "F.Cu") (net 79))
  (segment (start 115.25 144.74) (end 115.25 145.265001) (width 0.155) (layer "F.Cu") (net 79))
  (segment (start 115.36 146.270794) (end 114.836474 146.79432) (width 0.155) (layer "F.Cu") (net 79))
  (segment (start 105.86 116.950895) (end 105.6375 116.728395) (width 0.155) (layer "F.Cu") (net 79))
  (segment (start 105.75 117.349999) (end 105.86 117.239999) (width 0.155) (layer "F.Cu") (net 79))
  (segment (start 116.35 139.0875) (end 116.2875 139.0875) (width 0.155) (layer "F.Cu") (net 79))
  (segment (start 112.54 135.803628) (end 112.54 136.34201) (width 0.155) (layer "F.Cu") (net 79))
  (segment (start 115.89 141.00799) (end 115.89 141.3775) (width 0.155) (layer "F.Cu") (net 79))
  (segment (start 116.24 140.65799) (end 115.89 141.00799) (width 0.155) (layer "F.Cu") (net 79))
  (segment (start 112.75799 136.56) (end 115.35799 136.56) (width 0.155) (layer "F.Cu") (net 79))
  (segment (start 105.86 117.239999) (end 105.86 116.950895) (width 0.155) (layer "F.Cu") (net 79))
  (segment (start 116.35 138.3125) (end 116.2875 138.3125) (width 0.155) (layer "F.Cu") (net 79))
  (segment (start 112.875893 135.467735) (end 112.54 135.803628) (width 0.155) (layer "F.Cu") (net 79))
  (segment (start 116.24 139.04) (end 116.24 140.65799) (width 0.155) (layer "F.Cu") (net 79))
  (segment (start 112.54 136.34201) (end 112.75799 136.56) (width 0.155) (layer "F.Cu") (net 79))
  (segment (start 116.24 138.36) (end 116.24 139.04) (width 0.155) (layer "F.Cu") (net 79))
  (segment (start 116.24 137.44201) (end 116.24 138.36) (width 0.155) (layer "F.Cu") (net 79))
  (segment (start 116.2875 139.0875) (end 116.24 139.04) (width 0.155) (layer "F.Cu") (net 79))
  (segment (start 113.190557 135.467735) (end 112.875893 135.467735) (width 0.155) (layer "F.Cu") (net 79))
  (segment (start 105.75 118.55) (end 105.75 117.349999) (width 0.155) (layer "F.Cu") (net 79))
  (segment (start 116.24 137.44201) (end 115.35799 136.56) (width 0.155) (layer "F.Cu") (net 79))
  (segment (start 116.2875 138.3125) (end 116.24 138.36) (width 0.155) (layer "F.Cu") (net 79))
  (segment (start 115.89 141.3775) (end 116.1125 141.6) (width 0.155) (layer "F.Cu") (net 79))
  (via (at 116.1125 141.6) (size 0.6) (drill 0.25) (layers "F.Cu" "B.Cu") (net 79))
  (via (at 114.52181 146.79432) (size 0.6) (drill 0.25) (layers "F.Cu" "B.Cu") (net 79))
  (via (at 105.6375 116.728395) (size 0.6) (drill 0.25) (layers "F.Cu" "B.Cu") (net 79))
  (via (at 113.190557 135.467735) (size 0.6) (drill 0.25) (layers "F.Cu" "B.Cu") (net 79))
  (segment (start 115.89 141.8225) (end 116.1125 141.6) (width 0.155) (layer "B.Cu") (net 79))
  (segment (start 114.54201 148.44) (end 115.45799 148.44) (width 0.155) (layer "B.Cu") (net 79))
  (segment (start 115.64 146.56312) (end 115.64 144.15799) (width 0.155) (layer "B.Cu") (net 79))
  (segment (start 114.16 147.470794) (end 114.16 148.05799) (width 0.155) (layer "B.Cu") (net 79))
  (segment (start 115.45799 148.44) (end 115.84 148.05799) (width 0.155) (layer "B.Cu") (net 79))
  (segment (start 115.64 144.15799) (end 115.89 143.90799) (width 0.155) (layer "B.Cu") (net 79))
  (segment (start 115.89 143.90799) (end 115.89 141.8225) (width 0.155) (layer "B.Cu") (net 79))
  (segment (start 114.52181 146.79432) (end 114.52181 147.108984) (width 0.155) (layer "B.Cu") (net 79))
  (segment (start 114.16 148.05799) (end 114.54201 148.44) (width 0.155) (layer "B.Cu") (net 79))
  (segment (start 115.84 146.76312) (end 115.64 146.56312) (width 0.155) (layer "B.Cu") (net 79))
  (segment (start 115.84 148.05799) (end 115.84 146.76312) (width 0.155) (layer "B.Cu") (net 79))
  (segment (start 114.52181 147.108984) (end 114.16 147.470794) (width 0.155) (layer "B.Cu") (net 79))
  (segment (start 111.14201 134.94) (end 106.74201 134.94) (width 0.155) (layer "B.Cu") (net 79))
  (segment (start 113.190557 135.467735) (end 112.875893 135.467735) (width 0.155) (layer "B.Cu") (net 79))
  (segment (start 105.86 116.950895) (end 105.6375 116.728395) (width 0.155) (layer "B.Cu") (net 79))
  (segment (start 106.74201 134.94) (end 105.86 134.05799) (width 0.155) (layer "B.Cu") (net 79))
  (segment (start 112.875893 135.467735) (end 112.553628 135.79) (width 0.155) (layer "B.Cu") (net 79))
  (segment (start 105.86 134.05799) (end 105.86 116.950895) (width 0.155) (layer "B.Cu") (net 79))
  (segment (start 112.553628 135.79) (end 111.99201 135.79) (width 0.155) (layer "B.Cu") (net 79))
  (segment (start 111.99201 135.79) (end 111.14201 134.94) (width 0.155) (layer "B.Cu") (net 79))
  (segment (start 115.5 142.514999) (end 115.61 142.404999) (width 0.155) (layer "F.Cu") (net 80))
  (segment (start 115.5 143.04) (end 115.5 142.514999) (width 0.155) (layer "F.Cu") (net 80))
  (segment (start 115.61 141.8225) (end 115.3875 141.6) (width 0.155) (layer "F.Cu") (net 80))
  (segment (start 115.61 142.404999) (end 115.61 141.8225) (width 0.155) (layer "F.Cu") (net 80))
  (segment (start 115.034464 146.99231) (end 115.034464 147.306974) (width 0.155) (layer "F.Cu") (net 80))
  (segment (start 115.75 145.265001) (end 115.64 145.375001) (width 0.155) (layer "F.Cu") (net 80))
  (segment (start 115.64 146.386774) (end 115.034464 146.99231) (width 0.155) (layer "F.Cu") (net 80))
  (segment (start 115.64 145.375001) (end 115.64 146.386774) (width 0.155) (layer "F.Cu") (net 80))
  (segment (start 115.75 144.74) (end 115.75 145.265001) (width 0.155) (layer "F.Cu") (net 80))
  (segment (start 112.677903 135.269745) (end 112.26 135.687648) (width 0.155) (layer "F.Cu") (net 80))
  (segment (start 115.96 139.04) (end 115.96 140.54201) (width 0.155) (layer "F.Cu") (net 80))
  (segment (start 115.96 137.55799) (end 115.24201 136.84) (width 0.155) (layer "F.Cu") (net 80))
  (segment (start 115.61 140.89201) (end 115.61 141.3775) (width 0.155) (layer "F.Cu") (net 80))
  (segment (start 106.25 118.55) (end 106.25 117.349999) (width 0.155) (layer "F.Cu") (net 80))
  (segment (start 106.25 117.349999) (end 106.14 117.239999) (width 0.155) (layer "F.Cu") (net 80))
  (segment (start 112.26 136.45799) (end 112.64201 136.84) (width 0.155) (layer "F.Cu") (net 80))
  (segment (start 115.85 139.0875) (end 115.9125 139.0875) (width 0.155) (layer "F.Cu") (net 80))
  (segment (start 115.96 138.36) (end 115.96 139.04) (width 0.155) (layer "F.Cu") (net 80))
  (segment (start 106.14 117.239999) (end 106.14 116.950895) (width 0.155) (layer "F.Cu") (net 80))
  (segment (start 115.61 141.3775) (end 115.3875 141.6) (width 0.155) (layer "F.Cu") (net 80))
  (segment (start 115.9125 138.3125) (end 115.96 138.36) (width 0.155) (layer "F.Cu") (net 80))
  (segment (start 115.85 138.3125) (end 115.9125 138.3125) (width 0.155) (layer "F.Cu") (net 80))
  (segment (start 112.26 135.687648) (end 112.26 136.45799) (width 0.155) (layer "F.Cu") (net 80))
  (segment (start 115.96 140.54201) (end 115.61 140.89201) (width 0.155) (layer "F.Cu") (net 80))
  (segment (start 115.96 137.55799) (end 115.96 138.36) (width 0.155) (layer "F.Cu") (net 80))
  (segment (start 112.64201 136.84) (end 115.24201 136.84) (width 0.155) (layer "F.Cu") (net 80))
  (segment (start 106.14 116.950895) (end 106.3625 116.728395) (width 0.155) (layer "F.Cu") (net 80))
  (segment (start 112.677903 134.955081) (end 112.677903 135.269745) (width 0.155) (layer "F.Cu") (net 80))
  (segment (start 115.9125 139.0875) (end 115.96 139.04) (width 0.155) (layer "F.Cu") (net 80))
  (via (at 115.034464 147.306974) (size 0.6) (drill 0.25) (layers "F.Cu" "B.Cu") (net 80))
  (via (at 115.3875 141.6) (size 0.6) (drill 0.25) (layers "F.Cu" "B.Cu") (net 80))
  (via (at 106.3625 116.728395) (size 0.6) (drill 0.25) (layers "F.Cu" "B.Cu") (net 80))
  (via (at 112.677903 134.955081) (size 0.6) (drill 0.25) (layers "F.Cu" "B.Cu") (net 80))
  (segment (start 115.239491 145.351113) (end 115.272252 145.33965) (width 0.155) (layer "B.Cu") (net 80))
  (segment (start 115.11447 145.661113) (end 115.081709 145.64965) (width 0.155) (layer "B.Cu") (net 80))
  (segment (start 115.14896 145.975) (end 115.205 145.975) (width 0.155) (layer "B.Cu") (net 80))
  (segment (start 115.36 146.44) (end 115.356114 146.405509) (width 0.155) (layer "B.Cu") (net 80))
  (segment (start 115.081709 145.64965) (end 115.05232 145.631183) (width 0.155) (layer "B.Cu") (net 80))
  (segment (start 115.344651 146.372748) (end 115.326184 146.343359) (width 0.155) (layer "B.Cu") (net 80))
  (segment (start 115.05232 146.008816) (end 115.081709 145.990349) (width 0.155) (layer "B.Cu") (net 80))
  (segment (start 114.44 147.586774) (end 114.44 147.94201) (width 0.155) (layer "B.Cu") (net 80))
  (segment (start 106.85799 134.66) (end 111.25799 134.66) (width 0.155) (layer "B.Cu") (net 80))
  (segment (start 115.56 146.8791) (end 115.36 146.6791) (width 0.155) (layer "B.Cu") (net 80))
  (segment (start 115.11447 145.978886) (end 115.14896 145.975) (width 0.155) (layer "B.Cu") (net 80))
  (segment (start 115.356114 145.785509) (end 115.344651 145.752748) (width 0.155) (layer "B.Cu") (net 80))
  (segment (start 111.877025 134.980583) (end 111.837399 135.020206) (width 0.155) (layer "B.Cu") (net 80))
  (segment (start 106.3625 116.728395) (end 106.14 116.950895) (width 0.155) (layer "B.Cu") (net 80))
  (segment (start 115.205 145.665) (end 115.14896 145.665) (width 0.155) (layer "B.Cu") (net 80))
  (segment (start 111.25799 134.66) (end 111.398995 134.801005) (width 0.155) (layer "B.Cu") (net 80))
  (segment (start 111.559789 134.837705) (end 111.591061 134.822645) (width 0.155) (layer "B.Cu") (net 80))
  (segment (start 111.792976 135.112454) (end 111.792975 135.147162) (width 0.155) (layer "B.Cu") (net 80))
  (segment (start 115.61 143.79201) (end 115.61 141.8225) (width 0.155) (layer "B.Cu") (net 80))
  (segment (start 115.05232 145.631183) (end 115.027777 145.60664) (width 0.155) (layer "B.Cu") (net 80))
  (segment (start 111.913724 134.922173) (end 111.898664 134.953445) (width 0.155) (layer "B.Cu") (net 80))
  (segment (start 111.618197 134.801004) (end 111.657822 134.76138) (width 0.155) (layer "B.Cu") (net 80))
  (segment (start 114.997847 145.475509) (end 115.00931 145.442748) (width 0.155) (layer "B.Cu") (net 80))
  (segment (start 114.65799 148.16) (end 115.34201 148.16) (width 0.155) (layer "B.Cu") (net 80))
  (segment (start 115.61 141.8225) (end 115.3875 141.6) (width 0.155) (layer "B.Cu") (net 80))
  (segment (start 115.272252 145.95965) (end 115.301641 145.941183) (width 0.155) (layer "B.Cu") (net 80))
  (segment (start 115.11447 145.358886) (end 115.14896 145.355) (width 0.155) (layer "B.Cu") (net 80))
  (segment (start 115.344651 145.887251) (end 115.356114 145.85449) (width 0.155) (layer "B.Cu") (net 80))
  (segment (start 111.921447 134.853626) (end 111.921448 134.888336) (width 0.155) (layer "B.Cu") (net 80))
  (segment (start 114.99396 145.51) (end 114.997847 145.475509) (width 0.155) (layer "B.Cu") (net 80))
  (segment (start 115.301641 145.941183) (end 115.326184 145.91664) (width 0.155) (layer "B.Cu") (net 80))
  (segment (start 111.426131 134.822645) (end 111.457403 134.837705) (width 0.155) (layer "B.Cu") (net 80))
  (segment (start 111.792975 135.147162) (end 111.800698 135.181001) (width 0.155) (layer "B.Cu") (net 80))
  (segment (start 115.205 146.285) (end 115.14896 146.285) (width 0.155) (layer "B.Cu") (net 80))
  (segment (start 111.657822 134.76138) (end 111.684959 134.739739) (width 0.155) (layer "B.Cu") (net 80))
  (segment (start 112.10799 135.51) (end 112.437648 135.51) (width 0.155) (layer "B.Cu") (net 80))
  (segment (start 115.34201 148.16) (end 115.56 147.94201) (width 0.155) (layer "B.Cu") (net 80))
  (segment (start 111.800698 135.181001) (end 111.815758 135.212273) (width 0.155) (layer "B.Cu") (net 80))
  (segment (start 115.00931 145.577251) (end 114.997847 145.54449) (width 0.155) (layer "B.Cu") (net 80))
  (segment (start 115.239491 145.668886) (end 115.205 145.665) (width 0.155) (layer "B.Cu") (net 80))
  (segment (start 115.239491 145.971113) (end 115.272252 145.95965) (width 0.155) (layer "B.Cu") (net 80))
  (segment (start 114.44 147.94201) (end 114.65799 148.16) (width 0.155) (layer "B.Cu") (net 80))
  (segment (start 115.356114 146.405509) (end 115.344651 146.372748) (width 0.155) (layer "B.Cu") (net 80))
  (segment (start 115.027777 146.033359) (end 115.05232 146.008816) (width 0.155) (layer "B.Cu") (net 80))
  (segment (start 111.877024 134.761379) (end 111.898664 134.788515) (width 0.155) (layer "B.Cu") (net 80))
  (segment (start 111.837401 135.239411) (end 112.10799 135.51) (width 0.155) (layer "B.Cu") (net 80))
  (segment (start 115.272252 145.33965) (end 115.301641 145.321183) (width 0.155) (layer "B.Cu") (net 80))
  (segment (start 115.14896 145.355) (end 115.205 145.355) (width 0.155) (layer "B.Cu") (net 80))
  (segment (start 111.800698 135.078615) (end 111.792976 135.112454) (width 0.155) (layer "B.Cu") (net 80))
  (segment (start 115.272252 146.300349) (end 115.239491 146.288886) (width 0.155) (layer "B.Cu") (net 80))
  (segment (start 115.56 147.94201) (end 115.56 146.8791) (width 0.155) (layer "B.Cu") (net 80))
  (segment (start 115.14896 146.285) (end 115.11447 146.281113) (width 0.155) (layer "B.Cu") (net 80))
  (segment (start 111.837399 135.020206) (end 111.815758 135.047343) (width 0.155) (layer "B.Cu") (net 80))
  (segment (start 115.36 144.04201) (end 115.61 143.79201) (width 0.155) (layer "B.Cu") (net 80))
  (segment (start 112.677903 135.269745) (end 112.677903 134.955081) (width 0.155) (layer "B.Cu") (net 80))
  (segment (start 111.591061 134.822645) (end 111.618197 134.801004) (width 0.155) (layer "B.Cu") (net 80))
  (segment (start 115.36 146.6791) (end 115.36 146.44) (width 0.155) (layer "B.Cu") (net 80))
  (segment (start 115.301641 145.321183) (end 115.326184 145.29664) (width 0.155) (layer "B.Cu") (net 80))
  (segment (start 115.356114 145.85449) (end 115.36 145.82) (width 0.155) (layer "B.Cu") (net 80))
  (segment (start 111.491242 134.845428) (end 111.52595 134.845427) (width 0.155) (layer "B.Cu") (net 80))
  (segment (start 115.081709 145.990349) (end 115.11447 145.978886) (width 0.155) (layer "B.Cu") (net 80))
  (segment (start 115.14896 145.665) (end 115.11447 145.661113) (width 0.155) (layer "B.Cu") (net 80))
  (segment (start 115.36 145.2) (end 115.36 144.04201) (width 0.155) (layer "B.Cu") (net 80))
  (segment (start 111.921448 134.888336) (end 111.913724 134.922173) (width 0.155) (layer "B.Cu") (net 80))
  (segment (start 115.326184 145.29664) (end 115.344651 145.267251) (width 0.155) (layer "B.Cu") (net 80))
  (segment (start 111.398995 134.801005) (end 111.426131 134.822645) (width 0.155) (layer "B.Cu") (net 80))
  (segment (start 106.14 116.950895) (end 106.14 133.94201) (width 0.155) (layer "B.Cu") (net 80))
  (segment (start 115.272252 145.680349) (end 115.239491 145.668886) (width 0.155) (layer "B.Cu") (net 80))
  (segment (start 111.716231 134.724679) (end 111.750068 134.716955) (width 0.155) (layer "B.Cu") (net 80))
  (segment (start 111.898664 134.953445) (end 111.877025 134.980583) (width 0.155) (layer "B.Cu") (net 80))
  (segment (start 115.36 145.82) (end 115.356114 145.785509) (width 0.155) (layer "B.Cu") (net 80))
  (segment (start 115.326184 145.91664) (end 115.344651 145.887251) (width 0.155) (layer "B.Cu") (net 80))
  (segment (start 115.301641 145.698816) (end 115.272252 145.680349) (width 0.155) (layer "B.Cu") (net 80))
  (segment (start 114.997847 146.16449) (end 114.99396 146.13) (width 0.155) (layer "B.Cu") (net 80))
  (segment (start 115.344651 145.267251) (end 115.356114 145.23449) (width 0.155) (layer "B.Cu") (net 80))
  (segment (start 111.784778 134.716956) (end 111.818617 134.724679) (width 0.155) (layer "B.Cu") (net 80))
  (segment (start 111.849889 134.739739) (end 111.877024 134.761379) (width 0.155) (layer "B.Cu") (net 80))
  (segment (start 111.457403 134.837705) (end 111.491242 134.845428) (width 0.155) (layer "B.Cu") (net 80))
  (segment (start 115.00931 145.442748) (end 115.027777 145.413359) (width 0.155) (layer "B.Cu") (net 80))
  (segment (start 111.750068 134.716955) (end 111.784778 134.716956) (width 0.155) (layer "B.Cu") (net 80))
  (segment (start 112.437648 135.51) (end 112.677903 135.269745) (width 0.155) (layer "B.Cu") (net 80))
  (segment (start 114.99396 146.13) (end 114.997847 146.095509) (width 0.155) (layer "B.Cu") (net 80))
  (segment (start 111.815758 135.047343) (end 111.800698 135.078615) (width 0.155) (layer "B.Cu") (net 80))
  (segment (start 114.997847 146.095509) (end 115.00931 146.062748) (width 0.155) (layer "B.Cu") (net 80))
  (segment (start 115.344651 145.752748) (end 115.326184 145.723359) (width 0.155) (layer "B.Cu") (net 80))
  (segment (start 115.034464 147.306974) (end 114.7198 147.306974) (width 0.155) (layer "B.Cu") (net 80))
  (segment (start 115.356114 145.23449) (end 115.36 145.2) (width 0.155) (layer "B.Cu") (net 80))
  (segment (start 115.11447 146.281113) (end 115.081709 146.26965) (width 0.155) (layer "B.Cu") (net 80))
  (segment (start 115.05232 145.388816) (end 115.081709 145.370349) (width 0.155) (layer "B.Cu") (net 80))
  (segment (start 114.997847 145.54449) (end 114.99396 145.51) (width 0.155) (layer "B.Cu") (net 80))
  (segment (start 115.05232 146.251183) (end 115.027777 146.22664) (width 0.155) (layer "B.Cu") (net 80))
  (segment (start 106.14 133.94201) (end 106.85799 134.66) (width 0.155) (layer "B.Cu") (net 80))
  (segment (start 115.301641 146.318816) (end 115.272252 146.300349) (width 0.155) (layer "B.Cu") (net 80))
  (segment (start 115.027777 145.413359) (end 115.05232 145.388816) (width 0.155) (layer "B.Cu") (net 80))
  (segment (start 115.00931 146.197251) (end 114.997847 146.16449) (width 0.155) (layer "B.Cu") (net 80))
  (segment (start 111.913724 134.819787) (end 111.921447 134.853626) (width 0.155) (layer "B.Cu") (net 80))
  (segment (start 115.239491 146.288886) (end 115.205 146.285) (width 0.155) (layer "B.Cu") (net 80))
  (segment (start 115.081709 145.370349) (end 115.11447 145.358886) (width 0.155) (layer "B.Cu") (net 80))
  (segment (start 115.205 145.975) (end 115.239491 145.971113) (width 0.155) (layer "B.Cu") (net 80))
  (segment (start 111.52595 134.845427) (end 111.559789 134.837705) (width 0.155) (layer "B.Cu") (net 80))
  (segment (start 115.027777 145.60664) (end 115.00931 145.577251) (width 0.155) (layer "B.Cu") (net 80))
  (segment (start 115.205 145.355) (end 115.239491 145.351113) (width 0.155) (layer "B.Cu") (net 80))
  (segment (start 115.00931 146.062748) (end 115.027777 146.033359) (width 0.155) (layer "B.Cu") (net 80))
  (segment (start 115.326184 146.343359) (end 115.301641 146.318816) (width 0.155) (layer "B.Cu") (net 80))
  (segment (start 111.898664 134.788515) (end 111.913724 134.819787) (width 0.155) (layer "B.Cu") (net 80))
  (segment (start 114.7198 147.306974) (end 114.44 147.586774) (width 0.155) (layer "B.Cu") (net 80))
  (segment (start 115.081709 146.26965) (end 115.05232 146.251183) (width 0.155) (layer "B.Cu") (net 80))
  (segment (start 111.815758 135.212273) (end 111.837401 135.239411) (width 0.155) (layer "B.Cu") (net 80))
  (segment (start 115.027777 146.22664) (end 115.00931 146.197251) (width 0.155) (layer "B.Cu") (net 80))
  (segment (start 111.684959 134.739739) (end 111.716231 134.724679) (width 0.155) (layer "B.Cu") (net 80))
  (segment (start 111.818617 134.724679) (end 111.849889 134.739739) (width 0.155) (layer "B.Cu") (net 80))
  (segment (start 115.326184 145.723359) (end 115.301641 145.698816) (width 0.155) (layer "B.Cu") (net 80))
  (segment (start 121.19 109.35) (end 121.865 109.35) (width 0.15) (layer "F.Cu") (net 81))
  (segment (start 121.75 112.45) (end 121.75 110.75) (width 0.15) (layer "F.Cu") (net 81))
  (segment (start 121.75 110.75) (end 121.19 110.19) (width 0.15) (layer "F.Cu") (net 81))
  (segment (start 121.865 109.35) (end 122.315 109.8) (width 0.15) (layer "F.Cu") (net 81))
  (segment (start 121.19 110.19) (end 121.19 109.35) (width 0.15) (layer "F.Cu") (net 81))
  (segment (start 121.25 112.45) (end 121.25 111.05) (width 0.15) (layer "F.Cu") (net 82))
  (segment (start 121.25 111.05) (end 120.6 110.4) (width 0.15) (layer "F.Cu") (net 82))
  (segment (start 120.6 109.35) (end 119.935 109.35) (width 0.15) (layer "F.Cu") (net 82))
  (segment (start 119.935 109.35) (end 119.485 109.8) (width 0.15) (layer "F.Cu") (net 82))
  (segment (start 120.6 110.4) (end 120.6 109.35) (width 0.15) (layer "F.Cu") (net 82))
  (segment (start 124.749999 112.45) (end 124.749999 111.249849) (width 0.125) (layer "F.Cu") (net 83))
  (segment (start 152.475001 124.26) (end 152.590001 124.375) (width 0.125) (layer "F.Cu") (net 83))
  (segment (start 152.590001 124.375) (end 152.9625 124.375) (width 0.125) (layer "F.Cu") (net 83))
  (segment (start 152.25 124.26) (end 152.475001 124.26) (width 0.125) (layer "F.Cu") (net 83))
  (segment (start 124.624999 111.124849) (end 124.624999 110.548222) (width 0.125) (layer "F.Cu") (net 83))
  (segment (start 124.624999 110.548222) (end 124.456327 110.37955) (width 0.125) (layer "F.Cu") (net 83))
  (segment (start 152.9625 124.375) (end 153.2 124.1375) (width 0.125) (layer "F.Cu") (net 83))
  (segment (start 124.749999 111.249849) (end 124.624999 111.124849) (width 0.125) (layer "F.Cu") (net 83))
  (segment (start 124.456327 110.37955) (end 124.456327 110.043673) (width 0.125) (layer "F.Cu") (net 83))
  (via (at 124.456327 110.043673) (size 0.6) (drill 0.25) (layers "F.Cu" "B.Cu") (net 83))
  (via (at 153.2 124.1375) (size 0.6) (drill 0.25) (layers "F.Cu" "B.Cu") (net 83))
  (segment (start 149.125 112.948222) (end 148.551778 112.375) (width 0.125) (layer "In2.Cu") (net 83))
  (segment (start 142.551778 110.875) (end 124.951777 110.875) (width 0.125) (layer "In2.Cu") (net 83))
  (segment (start 150.051778 122.875) (end 149.125 121.948222) (width 0.125) (layer "In2.Cu") (net 83))
  (segment (start 152.551778 124.375) (end 151.051778 122.875) (width 0.125) (layer "In2.Cu") (net 83))
  (segment (start 144.051778 112.375) (end 142.551778 110.875) (width 0.125) (layer "In2.Cu") (net 83))
  (segment (start 124.456327 110.37955) (end 124.456327 110.043673) (width 0.125) (layer "In2.Cu") (net 83))
  (segment (start 153.2 124.1375) (end 152.9625 124.375) (width 0.125) (layer "In2.Cu") (net 83))
  (segment (start 124.951777 110.875) (end 124.456327 110.37955) (width 0.125) (layer "In2.Cu") (net 83))
  (segment (start 149.125 121.948222) (end 149.125 112.948222) (width 0.125) (layer "In2.Cu") (net 83))
  (segment (start 148.551778 112.375) (end 144.051778 112.375) (width 0.125) (layer "In2.Cu") (net 83))
  (segment (start 152.9625 124.375) (end 152.551778 124.375) (width 0.125) (layer "In2.Cu") (net 83))
  (segment (start 151.051778 122.875) (end 150.051778 122.875) (width 0.125) (layer "In2.Cu") (net 83))
  (segment (start 124.25 112.45) (end 124.25 111.249849) (width 0.125) (layer "F.Cu") (net 84))
  (segment (start 124.375 111.124849) (end 124.375 110.651777) (width 0.125) (layer "F.Cu") (net 84))
  (segment (start 124.27955 110.556327) (end 123.943673 110.556327) (width 0.125) (layer "F.Cu") (net 84))
  (segment (start 124.25 111.249849) (end 124.375 111.124849) (width 0.125) (layer "F.Cu") (net 84))
  (segment (start 124.375 110.651777) (end 124.27955 110.556327) (width 0.125) (layer "F.Cu") (net 84))
  (segment (start 152.475001 124.74) (end 152.590001 124.625) (width 0.125) (layer "F.Cu") (net 84))
  (segment (start 152.25 124.74) (end 152.475001 124.74) (width 0.125) (layer "F.Cu") (net 84))
  (segment (start 152.9625 124.625) (end 153.2 124.8625) (width 0.125) (layer "F.Cu") (net 84))
  (segment (start 152.590001 124.625) (end 152.9625 124.625) (width 0.125) (layer "F.Cu") (net 84))
  (via (at 123.943673 110.556327) (size 0.6) (drill 0.25) (layers "F.Cu" "B.Cu") (net 84))
  (via (at 153.2 124.8625) (size 0.6) (drill 0.25) (layers "F.Cu" "B.Cu") (net 84))
  (segment (start 124.27955 110.556327) (end 123.943673 110.556327) (width 0.125) (layer "In2.Cu") (net 84))
  (segment (start 152.448222 124.625) (end 150.948222 123.125) (width 0.125) (layer "In2.Cu") (net 84))
  (segment (start 150.948222 123.125) (end 149.948222 123.125) (width 0.125) (layer "In2.Cu") (net 84))
  (segment (start 124.848223 111.125) (end 124.27955 110.556327) (width 0.125) (layer "In2.Cu") (net 84))
  (segment (start 149.948222 123.125) (end 148.875 122.051778) (width 0.125) (layer "In2.Cu") (net 84))
  (segment (start 143.948222 112.625) (end 142.448222 111.125) (width 0.125) (layer "In2.Cu") (net 84))
  (segment (start 148.875 122.051778) (end 148.875 113.051778) (width 0.125) (layer "In2.Cu") (net 84))
  (segment (start 142.448222 111.125) (end 124.848223 111.125) (width 0.125) (layer "In2.Cu") (net 84))
  (segment (start 152.9625 124.625) (end 152.448222 124.625) (width 0.125) (layer "In2.Cu") (net 84))
  (segment (start 148.875 113.051778) (end 148.448222 112.625) (width 0.125) (layer "In2.Cu") (net 84))
  (segment (start 148.448222 112.625) (end 143.948222 112.625) (width 0.125) (layer "In2.Cu") (net 84))
  (segment (start 153.2 124.8625) (end 152.9625 124.625) (width 0.125) (layer "In2.Cu") (net 84))
  (segment (start 125.749999 112.45) (end 125.749999 113.650151) (width 0.125) (layer "F.Cu") (net 85))
  (segment (start 152.590001 130.625) (end 152.950002 130.625) (width 0.125) (layer "F.Cu") (net 85))
  (segment (start 125.749999 113.650151) (end 125.875 113.775152) (width 0.125) (layer "F.Cu") (net 85))
  (segment (start 152.950002 130.625) (end 153.187502 130.8625) (width 0.125) (layer "F.Cu") (net 85))
  (segment (start 152.25 130.74) (end 152.475001 130.74) (width 0.125) (layer "F.Cu") (net 85))
  (segment (start 125.875 113.775152) (end 125.875 114.051778) (width 0.125) (layer "F.Cu") (net 85))
  (segment (start 128.7625 114.625) (end 129 114.8625) (width 0.125) (layer "F.Cu") (net 85))
  (segment (start 125.875 114.051778) (end 126.448222 114.625) (width 0.125) (layer "F.Cu") (net 85))
  (segment (start 126.448222 114.625) (end 128.7625 114.625) (width 0.125) (layer "F.Cu") (net 85))
  (segment (start 152.475001 130.74) (end 152.590001 130.625) (width 0.125) (layer "F.Cu") (net 85))
  (via (at 129 114.8625) (size 0.6) (drill 0.25) (layers "F.Cu" "B.Cu") (net 85))
  (via (at 153.187502 130.8625) (size 0.6) (drill 0.25) (layers "F.Cu" "B.Cu") (net 85))
  (segment (start 152.9625 130.625) (end 152.448222 130.625) (width 0.125) (layer "In2.Cu") (net 85))
  (segment (start 131.551778 113.125) (end 130.051778 114.625) (width 0.125) (layer "In2.Cu") (net 85))
  (segment (start 140.948222 113.125) (end 131.551778 113.125) (width 0.125) (layer "In2.Cu") (net 85))
  (segment (start 149.948222 129.125) (end 146.875 126.051778) (width 0.125) (layer "In2.Cu") (net 85))
  (segment (start 129.2375 114.625) (end 130.051778 114.625) (width 0.125) (layer "In2.Cu") (net 85))
  (segment (start 142.448222 114.625) (end 140.948222 113.125) (width 0.125) (layer "In2.Cu") (net 85))
  (segment (start 129 114.8625) (end 129.2375 114.625) (width 0.125) (layer "In2.Cu") (net 85))
  (segment (start 146.448222 114.625) (end 142.448222 114.625) (width 0.125) (layer "In2.Cu") (net 85))
  (segment (start 153.2 130.8625) (end 152.9625 130.625) (width 0.125) (layer "In2.Cu") (net 85))
  (segment (start 146.875 126.051778) (end 146.875 115.051778) (width 0.125) (layer "In2.Cu") (net 85))
  (segment (start 152.448222 130.625) (end 150.948222 129.125) (width 0.125) (layer "In2.Cu") (net 85))
  (segment (start 150.948222 129.125) (end 149.948222 129.125) (width 0.125) (layer "In2.Cu") (net 85))
  (segment (start 146.875 115.051778) (end 146.448222 114.625) (width 0.125) (layer "In2.Cu") (net 85))
  (segment (start 128.7625 114.375) (end 129 114.1375) (width 0.125) (layer "F.Cu") (net 86))
  (segment (start 152.475001 130.26) (end 152.590001 130.375) (width 0.125) (layer "F.Cu") (net 86))
  (segment (start 126.250001 112.45) (end 126.250001 113.650151) (width 0.125) (layer "F.Cu") (net 86))
  (segment (start 126.125 113.775152) (end 126.125 113.948222) (width 0.125) (layer "F.Cu") (net 86))
  (segment (start 126.125 113.948222) (end 126.551778 114.375) (width 0.125) (layer "F.Cu") (net 86))
  (segment (start 152.25 130.26) (end 152.475001 130.26) (width 0.125) (layer "F.Cu") (net 86))
  (segment (start 152.950002 130.375) (end 153.187502 130.1375) (width 0.125) (layer "F.Cu") (net 86))
  (segment (start 152.590001 130.375) (end 152.950002 130.375) (width 0.125) (layer "F.Cu") (net 86))
  (segment (start 126.250001 113.650151) (end 126.125 113.775152) (width 0.125) (layer "F.Cu") (net 86))
  (segment (start 126.551778 114.375) (end 128.7625 114.375) (width 0.125) (layer "F.Cu") (net 86))
  (via (at 153.187502 130.1375) (size 0.6) (drill 0.25) (layers "F.Cu" "B.Cu") (net 86))
  (via (at 129 114.1375) (size 0.6) (drill 0.25) (layers "F.Cu" "B.Cu") (net 86))
  (segment (start 146.551778 114.375) (end 142.551778 114.375) (width 0.125) (layer "In2.Cu") (net 86))
  (segment (start 147.125 114.948222) (end 146.551778 114.375) (width 0.125) (layer "In2.Cu") (net 86))
  (segment (start 153.2 130.1375) (end 152.9625 130.375) (width 0.125) (layer "In2.Cu") (net 86))
  (segment (start 147.125 125.948222) (end 147.125 114.948222) (width 0.125) (layer "In2.Cu") (net 86))
  (segment (start 129 114.1375) (end 129.2375 114.375) (width 0.125) (layer "In2.Cu") (net 86))
  (segment (start 152.551778 130.375) (end 151.051778 128.875) (width 0.125) (layer "In2.Cu") (net 86))
  (segment (start 150.051778 128.875) (end 147.125 125.948222) (width 0.125) (layer "In2.Cu") (net 86))
  (segment (start 129.2375 114.375) (end 129.948222 114.375) (width 0.125) (layer "In2.Cu") (net 86))
  (segment (start 131.448222 112.875) (end 129.948222 114.375) (width 0.125) (layer "In2.Cu") (net 86))
  (segment (start 152.9625 130.375) (end 152.551778 130.375) (width 0.125) (layer "In2.Cu") (net 86))
  (segment (start 151.051778 128.875) (end 150.051778 128.875) (width 0.125) (layer "In2.Cu") (net 86))
  (segment (start 141.051778 112.875) (end 131.448222 112.875) (width 0.125) (layer "In2.Cu") (net 86))
  (segment (start 142.551778 114.375) (end 141.051778 112.875) (width 0.125) (layer "In2.Cu") (net 86))
  (segment (start 123.551778 114.375) (end 123.124999 113.948221) (width 0.125) (layer "F.Cu") (net 87))
  (segment (start 123.249999 113.650151) (end 123.249999 112.45) (width 0.125) (layer "F.Cu") (net 87))
  (segment (start 123.7625 114.375) (end 123.551778 114.375) (width 0.125) (layer "F.Cu") (net 87))
  (segment (start 123.124999 113.775151) (end 123.249999 113.650151) (width 0.125) (layer "F.Cu") (net 87))
  (segment (start 152.950002 127.375) (end 153.187502 127.1375) (width 0.125) (layer "F.Cu") (net 87))
  (segment (start 152.590001 127.375) (end 152.950002 127.375) (width 0.125) (layer "F.Cu") (net 87))
  (segment (start 152.25 127.26) (end 152.475001 127.26) (width 0.125) (layer "F.Cu") (net 87))
  (segment (start 124 114.1375) (end 123.7625 114.375) (width 0.125) (layer "F.Cu") (net 87))
  (segment (start 123.124999 113.948221) (end 123.124999 113.775151) (width 0.125) (layer "F.Cu") (net 87))
  (segment (start 152.475001 127.26) (end 152.590001 127.375) (width 0.125) (layer "F.Cu") (net 87))
  (via (at 153.187502 127.1375) (size 0.6) (drill 0.25) (layers "F.Cu" "B.Cu") (net 87))
  (via (at 124 114.1375) (size 0.6) (drill 0.25) (layers "F.Cu" "B.Cu") (net 87))
  (segment (start 143.051778 113.375) (end 141.551778 111.875) (width 0.125) (layer "In2.Cu") (net 87))
  (segment (start 149.551778 125.875) (end 148.125 124.448222) (width 0.125) (layer "In2.Cu") (net 87))
  (segment (start 148.125 113.948222) (end 147.551778 113.375) (width 0.125) (layer "In2.Cu") (net 87))
  (segment (start 151.051778 125.875) (end 149.551778 125.875) (width 0.125) (layer "In2.Cu") (net 87))
  (segment (start 148.125 124.448222) (end 148.125 113.948222) (width 0.125) (layer "In2.Cu") (net 87))
  (segment (start 124.2375 114.375) (end 124 114.1375) (width 0.125) (layer "In2.Cu") (net 87))
  (segment (start 152.551778 127.375) (end 151.051778 125.875) (width 0.125) (layer "In2.Cu") (net 87))
  (segment (start 152.9625 127.375) (end 152.551778 127.375) (width 0.125) (layer "In2.Cu") (net 87))
  (segment (start 141.551778 111.875) (end 127.448222 111.875) (width 0.125) (layer "In2.Cu") (net 87))
  (segment (start 147.551778 113.375) (end 143.051778 113.375) (width 0.125) (layer "In2.Cu") (net 87))
  (segment (start 124.948222 114.375) (end 124.2375 114.375) (width 0.125) (layer "In2.Cu") (net 87))
  (segment (start 153.2 127.1375) (end 152.9625 127.375) (width 0.125) (layer "In2.Cu") (net 87))
  (segment (start 127.448222 111.875) (end 124.948222 114.375) (width 0.125) (layer "In2.Cu") (net 87))
  (segment (start 124 114.8625) (end 123.7625 114.625) (width 0.125) (layer "F.Cu") (net 88))
  (segment (start 123.7625 114.625) (end 123.448222 114.625) (width 0.125) (layer "F.Cu") (net 88))
  (segment (start 152.950002 127.625) (end 153.187502 127.8625) (width 0.125) (layer "F.Cu") (net 88))
  (segment (start 152.25 127.74) (end 152.475001 127.74) (width 0.125) (layer "F.Cu") (net 88))
  (segment (start 152.590001 127.625) (end 152.950002 127.625) (width 0.125) (layer "F.Cu") (net 88))
  (segment (start 122.875 114.051778) (end 122.875 113.775151) (width 0.125) (layer "F.Cu") (net 88))
  (segment (start 152.475001 127.74) (end 152.590001 127.625) (width 0.125) (layer "F.Cu") (net 88))
  (segment (start 123.448222 114.625) (end 122.875 114.051778) (width 0.125) (layer "F.Cu") (net 88))
  (segment (start 122.875 113.775151) (end 122.75 113.650151) (width 0.125) (layer "F.Cu") (net 88))
  (segment (start 122.75 113.650151) (end 122.75 112.45) (width 0.125) (layer "F.Cu") (net 88))
  (via (at 153.187502 127.8625) (size 0.6) (drill 0.25) (layers "F.Cu" "B.Cu") (net 88))
  (via (at 124 114.8625) (size 0.6) (drill 0.25) (layers "F.Cu" "B.Cu") (net 88))
  (segment (start 147.875 114.051778) (end 147.448222 113.625) (width 0.125) (layer "In2.Cu") (net 88))
  (segment (start 124.2375 114.625) (end 124 114.8625) (width 0.125) (layer "In2.Cu") (net 88))
  (segment (start 141.448222 112.125) (end 127.551778 112.125) (width 0.125) (layer "In2.Cu") (net 88))
  (segment (start 149.448222 126.125) (end 147.875 124.551778) (width 0.125) (layer "In2.Cu") (net 88))
  (segment (start 153.2 127.8625) (end 152.9625 127.625) (width 0.125) (layer "In2.Cu") (net 88))
  (segment (start 127.551778 112.125) (end 125.051778 114.625) (width 0.125) (layer "In2.Cu") (net 88))
  (segment (start 152.9625 127.625) (end 152.448222 127.625) (width 0.125) (layer "In2.Cu") (net 88))
  (segment (start 142.948222 113.625) (end 141.448222 112.125) (width 0.125) (layer "In2.Cu") (net 88))
  (segment (start 125.051778 114.625) (end 124.2375 114.625) (width 0.125) (layer "In2.Cu") (net 88))
  (segment (start 152.448222 127.625) (end 150.948222 126.125) (width 0.125) (layer "In2.Cu") (net 88))
  (segment (start 147.875 124.551778) (end 147.875 114.051778) (width 0.125) (layer "In2.Cu") (net 88))
  (segment (start 150.948222 126.125) (end 149.448222 126.125) (width 0.125) (layer "In2.Cu") (net 88))
  (segment (start 147.448222 113.625) (end 142.948222 113.625) (width 0.125) (layer "In2.Cu") (net 88))
  (segment (start 152.590001 118.625) (end 152.950002 118.625) (width 0.125) (layer "F.Cu") (net 89))
  (segment (start 152.950002 118.625) (end 153.187502 118.8625) (width 0.125) (layer "F.Cu") (net 89))
  (segment (start 152.475001 118.74) (end 152.590001 118.625) (width 0.125) (layer "F.Cu") (net 89))
  (segment (start 128.875001 111.124849) (end 128.875001 108.351778) (width 0.125) (layer "F.Cu") (net 89))
  (segment (start 128.750001 111.249849) (end 128.875001 111.124849) (width 0.125) (layer "F.Cu") (net 89))
  (segment (start 152.25 118.74) (end 152.475001 118.74) (width 0.125) (layer "F.Cu") (net 89))
  (segment (start 128.875001 108.351778) (end 128.77955 108.256327) (width 0.125) (layer "F.Cu") (net 89))
  (segment (start 128.750001 112.45) (end 128.750001 111.249849) (width 0.125) (layer "F.Cu") (net 89))
  (segment (start 128.77955 108.256327) (end 128.443673 108.256327) (width 0.125) (layer "F.Cu") (net 89))
  (via (at 153.187502 118.8625) (size 0.6) (drill 0.25) (layers "F.Cu" "B.Cu") (net 89))
  (via (at 128.443673 108.256327) (size 0.6) (drill 0.25) (layers "F.Cu" "B.Cu") (net 89))
  (segment (start 150.875 111.551778) (end 149.948222 110.625) (width 0.125) (layer "In2.Cu") (net 89))
  (segment (start 149.948222 110.625) (end 147.448222 110.625) (width 0.125) (layer "In2.Cu") (net 89))
  (segment (start 145.948222 109.125) (end 129.648223 109.125) (width 0.125) (layer "In2.Cu") (net 89))
  (segment (start 153.187502 118.8625) (end 152.950002 118.625) (width 0.125) (layer "In2.Cu") (net 89))
  (segment (start 152.950002 118.625) (end 152.448222 118.625) (width 0.125) (layer "In2.Cu") (net 89))
  (segment (start 147.448222 110.625) (end 145.948222 109.125) (width 0.125) (layer "In2.Cu") (net 89))
  (segment (start 129.648223 109.125) (end 128.77955 108.256327) (width 0.125) (layer "In2.Cu") (net 89))
  (segment (start 152.448222 118.625) (end 150.875 117.051778) (width 0.125) (layer "In2.Cu") (net 89))
  (segment (start 128.77955 108.256327) (end 128.443673 108.256327) (width 0.125) (layer "In2.Cu") (net 89))
  (segment (start 150.875 117.051778) (end 150.875 111.551778) (width 0.125) (layer "In2.Cu") (net 89))
  (segment (start 152.475001 118.26) (end 152.590001 118.375) (width 0.125) (layer "F.Cu") (net 90))
  (segment (start 152.590001 118.375) (end 152.950002 118.375) (width 0.125) (layer "F.Cu") (net 90))
  (segment (start 152.950002 118.375) (end 153.187502 118.1375) (width 0.125) (layer "F.Cu") (net 90))
  (segment (start 129.25 112.45) (end 129.25 111.249849) (width 0.125) (layer "F.Cu") (net 90))
  (segment (start 128.956327 108.07955) (end 128.956327 107.743673) (width 0.125) (layer "F.Cu") (net 90))
  (segment (start 129.125 108.248223) (end 128.956327 108.07955) (width 0.125) (layer "F.Cu") (net 90))
  (segment (start 129.125 111.124849) (end 129.125 108.248223) (width 0.125) (layer "F.Cu") (net 90))
  (segment (start 152.25 118.26) (end 152.475001 118.26) (width 0.125) (layer "F.Cu") (net 90))
  (segment (start 129.25 111.249849) (end 129.125 111.124849) (width 0.125) (layer "F.Cu") (net 90))
  (via (at 153.187502 118.1375) (size 0.6) (drill 0.25) (layers "F.Cu" "B.Cu") (net 90))
  (via (at 128.956327 107.743673) (size 0.6) (drill 0.25) (layers "F.Cu" "B.Cu") (net 90))
  (segment (start 146.051778 108.875) (end 129.751777 108.875) (width 0.125) (layer "In2.Cu") (net 90))
  (segment (start 147.551778 110.375) (end 146.051778 108.875) (width 0.125) (layer "In2.Cu") (net 90))
  (segment (start 150.051778 110.375) (end 147.551778 110.375) (width 0.125) (layer "In2.Cu") (net 90))
  (segment (start 128.956327 108.07955) (end 128.956327 107.743673) (width 0.125) (layer "In2.Cu") (net 90))
  (segment (start 153.187502 118.1375) (end 152.950002 118.375) (width 0.125) (layer "In2.Cu") (net 90))
  (segment (start 151.125 116.948222) (end 151.125 111.448222) (width 0.125) (layer "In2.Cu") (net 90))
  (segment (start 152.551778 118.375) (end 151.125 116.948222) (width 0.125) (layer "In2.Cu") (net 90))
  (segment (start 152.950002 118.375) (end 152.551778 118.375) (width 0.125) (layer "In2.Cu") (net 90))
  (segment (start 129.751777 108.875) (end 128.956327 108.07955) (width 0.125) (layer "In2.Cu") (net 90))
  (segment (start 151.125 111.448222) (end 150.051778 110.375) (width 0.125) (layer "In2.Cu") (net 90))
  (segment (start 127.625 111.124848) (end 127.625 109.448223) (width 0.125) (layer "F.Cu") (net 91))
  (segment (start 127.256327 109.07955) (end 127.256327 108.743673) (width 0.125) (layer "F.Cu") (net 91))
  (segment (start 127.750001 111.249849) (end 127.625 111.124848) (width 0.125) (layer "F.Cu") (net 91))
  (segment (start 127.625 109.448223) (end 127.256327 109.07955) (width 0.125) (layer "F.Cu") (net 91))
  (segment (start 152.25 121.26) (end 152.475001 121.26) (width 0.125) (layer "F.Cu") (net 91))
  (segment (start 152.475001 121.26) (end 152.590001 121.375) (width 0.125) (layer "F.Cu") (net 91))
  (segment (start 127.750001 112.45) (end 127.750001 111.249849) (width 0.125) (layer "F.Cu") (net 91))
  (segment (start 152.949945 121.375) (end 153.187445 121.1375) (width 0.125) (layer "F.Cu") (net 91))
  (segment (start 152.590001 121.375) (end 152.949945 121.375) (width 0.125) (layer "F.Cu") (net 91))
  (via (at 127.256327 108.743673) (size 0.6) (drill 0.25) (layers "F.Cu" "B.Cu") (net 91))
  (via (at 153.187445 121.1375) (size 0.6) (drill 0.25) (layers "F.Cu" "B.Cu") (net 91))
  (segment (start 151.051778 119.875) (end 150.551778 119.875) (width 0.125) (layer "In2.Cu") (net 91))
  (segment (start 150.125 111.948222) (end 149.551778 111.375) (width 0.125) (layer "In2.Cu") (net 91))
  (segment (start 128.051777 109.875) (end 127.256327 109.07955) (width 0.125) (layer "In2.Cu") (net 91))
  (segment (start 144.551778 111.375) (end 143.051778 109.875) (width 0.125) (layer "In2.Cu") (net 91))
  (segment (start 149.551778 111.375) (end 144.551778 111.375) (width 0.125) (layer "In2.Cu") (net 91))
  (segment (start 150.125 119.448222) (end 150.125 111.948222) (width 0.125) (layer "In2.Cu") (net 91))
  (segment (start 152.9625 121.375) (end 152.551778 121.375) (width 0.125) (layer "In2.Cu") (net 91))
  (segment (start 127.256327 109.07955) (end 127.256327 108.743673) (width 0.125) (layer "In2.Cu") (net 91))
  (segment (start 143.051778 109.875) (end 128.051777 109.875) (width 0.125) (layer "In2.Cu") (net 91))
  (segment (start 152.551778 121.375) (end 151.051778 119.875) (width 0.125) (layer "In2.Cu") (net 91))
  (segment (start 153.2 121.1375) (end 152.9625 121.375) (width 0.125) (layer "In2.Cu") (net 91))
  (segment (start 150.551778 119.875) (end 150.125 119.448222) (width 0.125) (layer "In2.Cu") (net 91))
  (segment (start 127.07955 109.256327) (end 126.743673 109.256327) (width 0.125) (layer "F.Cu") (net 92))
  (segment (start 127.249999 112.45) (end 127.249999 111.249849) (width 0.125) (layer "F.Cu") (net 92))
  (segment (start 152.949945 121.625) (end 153.187445 121.8625) (width 0.125) (layer "F.Cu") (net 92))
  (segment (start 127.375 109.551777) (end 127.07955 109.256327) (width 0.125) (layer "F.Cu") (net 92))
  (segment (start 127.375 111.124848) (end 127.375 109.551777) (width 0.125) (layer "F.Cu") (net 92))
  (segment (start 152.475001 121.74) (end 152.590001 121.625) (width 0.125) (layer "F.Cu") (net 92))
  (segment (start 152.590001 121.625) (end 152.949945 121.625) (width 0.125) (layer "F.Cu") (net 92))
  (segment (start 127.249999 111.249849) (end 127.375 111.124848) (width 0.125) (layer "F.Cu") (net 92))
  (segment (start 152.25 121.74) (end 152.475001 121.74) (width 0.125) (layer "F.Cu") (net 92))
  (via (at 126.743673 109.256327) (size 0.6) (drill 0.25) (layers "F.Cu" "B.Cu") (net 92))
  (via (at 153.187445 121.8625) (size 0.6) (drill 0.25) (layers "F.Cu" "B.Cu") (net 92))
  (segment (start 142.948222 110.125) (end 127.948223 110.125) (width 0.125) (layer "In2.Cu") (net 92))
  (segment (start 149.875 119.551778) (end 149.875 112.051778) (width 0.125) (layer "In2.Cu") (net 92))
  (segment (start 150.948222 120.125) (end 150.448222 120.125) (width 0.125) (layer "In2.Cu") (net 92))
  (segment (start 149.875 112.051778) (end 149.448222 111.625) (width 0.125) (layer "In2.Cu") (net 92))
  (segment (start 153.2 121.8625) (end 152.9625 121.625) (width 0.125) (layer "In2.Cu") (net 92))
  (segment (start 152.448222 121.625) (end 150.948222 120.125) (width 0.125) (layer "In2.Cu") (net 92))
  (segment (start 127.07955 109.256327) (end 126.743673 109.256327) (width 0.125) (layer "In2.Cu") (net 92))
  (segment (start 150.448222 120.125) (end 149.875 119.551778) (width 0.125) (layer "In2.Cu") (net 92))
  (segment (start 144.448222 111.625) (end 142.948222 110.125) (width 0.125) (layer "In2.Cu") (net 92))
  (segment (start 127.948223 110.125) (end 127.07955 109.256327) (width 0.125) (layer "In2.Cu") (net 92))
  (segment (start 149.448222 111.625) (end 144.448222 111.625) (width 0.125) (layer "In2.Cu") (net 92))
  (segment (start 152.9625 121.625) (end 152.448222 121.625) (width 0.125) (layer "In2.Cu") (net 92))
  (segment (start 93.775 143.825) (end 93.7 143.9) (width 0.155) (layer "F.Cu") (net 93))
  (segment (start 94.4 143.825) (end 93.775 143.825) (width 0.155) (layer "F.Cu") (net 93))
  (segment (start 131.1 121.815) (end 131.1 121.040002) (width 0.15) (layer "F.Cu") (net 93))
  (segment (start 132.25 118.55) (end 132.25 119.624997) (width 0.15) (layer "F.Cu") (net 93))
  (segment (start 132.425003 119.8) (end 132.340002 119.8) (width 0.15) (layer "F.Cu") (net 93))
  (segment (start 132.340002 119.8) (end 131.720001 120.420001) (width 0.15) (layer "F.Cu") (net 93))
  (segment (start 132.25 119.624997) (end 132.425003 119.8) (width 0.15) (layer "F.Cu") (net 93))
  (segment (start 131.1 121.040002) (end 131.720001 120.420001) (width 0.15) (layer "F.Cu") (net 93))
  (via (at 93.7 143.9) (size 0.6) (drill 0.25) (layers "F.Cu" "B.Cu") (net 93))
  (via (at 132.425003 119.8) (size 0.6) (drill 0.25) (layers "F.Cu" "B.Cu") (net 93))
  (segment (start 94.62499 143.67501) (end 94.4 143.9) (width 0.15) (layer "In2.Cu") (net 93))
  (segment (start 132.425003 119.325003) (end 132.1 119) (width 0.15) (layer "In2.Cu") (net 93))
  (segment (start 113.42499 140.17501) (end 113.125011 140.474989) (width 0.15) (layer "In2.Cu") (net 93))
  (segment (start 113.125011 140.474989) (end 97.436089 140.474989) (width 0.15) (layer "In2.Cu") (net 93))
  (segment (start 113.886088 138.32499) (end 113.42499 138.786088) (width 0.15) (layer "In2.Cu") (net 93))
  (segment (start 130.886088 138.32499) (end 113.886088 138.32499) (width 0.15) (layer "In2.Cu") (net 93))
  (segment (start 132.1 119) (end 131.4 119) (width 0.15) (layer "In2.Cu") (net 93))
  (segment (start 132.425003 119.8) (end 132.425003 119.325003) (width 0.15) (layer "In2.Cu") (net 93))
  (segment (start 131.1 119.3) (end 131.1 138.111078) (width 0.15) (layer "In2.Cu") (net 93))
  (segment (start 113.42499 138.786088) (end 113.42499 140.17501) (width 0.15) (layer "In2.Cu") (net 93))
  (segment (start 131.4 119) (end 131.1 119.3) (width 0.15) (layer "In2.Cu") (net 93))
  (segment (start 94.62499 143.286088) (end 94.62499 143.67501) (width 0.15) (layer "In2.Cu") (net 93))
  (segment (start 94.4 143.9) (end 93.7 143.9) (width 0.15) (layer "In2.Cu") (net 93))
  (segment (start 97.436089 140.474989) (end 94.62499 143.286088) (width 0.15) (layer "In2.Cu") (net 93))
  (segment (start 131.1 138.111078) (end 130.886088 138.32499) (width 0.15) (layer "In2.Cu") (net 93))
  (segment (start 93.7 143.9) (end 93.7 144.5508) (width 0.15) (layer "B.Cu") (net 93))
  (segment (start 149.665 95.9) (end 149.115 95.35) (width 0.15) (layer "F.Cu") (net 94))
  (segment (start 149.115 95.35) (end 148.4 95.35) (width 0.15) (layer "F.Cu") (net 94))
  (segment (start 96.25 117.25) (end 96.35 117.15) (width 0.15) (layer "F.Cu") (net 94))
  (segment (start 96.25 118.55) (end 96.25 117.25) (width 0.15) (layer "F.Cu") (net 94))
  (via (at 145.8 93.65) (size 0.6) (drill 0.25) (layers "F.Cu" "B.Cu") (net 94))
  (via (at 96.35 117.15) (size 0.6) (drill 0.25) (layers "F.Cu" "B.Cu") (net 94))
  (via (at 148.4 95.35) (size 0.6) (drill 0.25) (layers "F.Cu" "B.Cu") (net 94))
  (segment (start 139.95002 104.24998) (end 133.872176 104.24998) (width 0.15) (layer "In2.Cu") (net 94))
  (segment (start 118.2 106.75) (end 114.859998 106.75) (width 0.15) (layer "In2.Cu") (net 94))
  (segment (start 114.859998 106.75) (end 114.309998 107.3) (width 0.15) (layer "In2.Cu") (net 94))
  (segment (start 118.2 106.75) (end 118.725 106.225) (width 0.15) (layer "In2.Cu") (net 94))
  (segment (start 98.4 115.4) (end 98.4 115.8) (width 0.15) (layer "In2.Cu") (net 94))
  (segment (start 98.4 115.8) (end 98.2 116) (width 0.15) (layer "In2.Cu") (net 94))
  (segment (start 124.372176 105.94998) (end 124.172177 106.149979) (width 0.15) (layer "In2.Cu") (net 94))
  (segment (start 96.6 116) (end 96.35 116.25) (width 0.15) (layer "In2.Cu") (net 94))
  (segment (start 110.4 115.2) (end 98.6 115.2) (width 0.15) (layer "In2.Cu") (net 94))
  (segment (start 110.8 114.8) (end 110.4 115.2) (width 0.155) (layer "In2.Cu") (net 94))
  (segment (start 112.75 106.75) (end 112 106.75) (width 0.15) (layer "In2.Cu") (net 94))
  (segment (start 145.8 94.2) (end 140.2 99.8) (width 0.15) (layer "In2.Cu") (net 94))
  (segment (start 118.800021 106.149979) (end 118.2 106.75) (width 0.15) (layer "In2.Cu") (net 94))
  (segment (start 98.6 115.2) (end 98.4 115.4) (width 0.15) (layer "In2.Cu") (net 94))
  (segment (start 112 106.75) (end 111.05 106.75) (width 0.155) (layer "In2.Cu") (net 94))
  (segment (start 96.35 116.25) (end 96.35 117.15) (width 0.15) (layer "In2.Cu") (net 94))
  (segment (start 132.172176 105.94998) (end 124.372176 105.94998) (width 0.15) (layer "In2.Cu") (net 94))
  (segment (start 98.2 116) (end 96.6 116) (width 0.15) (layer "In2.Cu") (net 94))
  (segment (start 113.3 107.3) (end 112.75 106.75) (width 0.15) (layer "In2.Cu") (net 94))
  (segment (start 140.2 99.8) (end 140.2 99.811078) (width 0.15) (layer "In2.Cu") (net 94))
  (segment (start 118.725 106.225) (end 118.8 106.15) (width 0.15) (layer "In2.Cu") (net 94))
  (segment (start 140.17497 104.02503) (end 139.95002 104.24998) (width 0.15) (layer "In2.Cu") (net 94))
  (segment (start 124.172177 106.149979) (end 118.800021 106.149979) (width 0.15) (layer "In2.Cu") (net 94))
  (segment (start 114.309998 107.3) (end 113.3 107.3) (width 0.15) (layer "In2.Cu") (net 94))
  (segment (start 145.8 93.65) (end 145.8 94.2) (width 0.15) (layer "In2.Cu") (net 94))
  (segment (start 110.8 107) (end 110.8 114.8) (width 0.155) (layer "In2.Cu") (net 94))
  (segment (start 133.872176 104.24998) (end 132.172176 105.94998) (width 0.15) (layer "In2.Cu") (net 94))
  (segment (start 140.2 99.811078) (end 140.17497 99.836108) (width 0.15) (layer "In2.Cu") (net 94))
  (segment (start 140.17497 99.836108) (end 140.17497 104.02503) (width 0.15) (layer "In2.Cu") (net 94))
  (segment (start 111.05 106.75) (end 110.8 107) (width 0.155) (layer "In2.Cu") (net 94))
  (segment (start 148.4 95.35) (end 148.4 94.865002) (width 0.15) (layer "B.Cu") (net 94))
  (segment (start 147.124264 93.65) (end 145.8 93.65) (width 0.15) (layer "B.Cu") (net 94))
  (segment (start 148.4 95.35) (end 148.4 94.925736) (width 0.15) (layer "B.Cu") (net 94))
  (segment (start 148.4 94.925736) (end 147.124264 93.65) (width 0.15) (layer "B.Cu") (net 94))
  (segment (start 148.7 113.2) (end 134.3 113.2) (width 0.125) (layer "F.Cu") (net 95))
  (segment (start 149.4 113.9) (end 148.7 113.2) (width 0.125) (layer "F.Cu") (net 95))
  (segment (start 131.25 116.65) (end 131.25 116.25) (width 0.125) (layer "F.Cu") (net 95))
  (segment (start 131.25 118.55) (end 131.25 116.25) (width 0.125) (layer "F.Cu") (net 95))
  (segment (start 131.25 118.55) (end 131.25 116.65) (width 0.125) (layer "F.Cu") (net 95))
  (segment (start 134.3 113.2) (end 131.25 116.25) (width 0.125) (layer "F.Cu") (net 95))
  (segment (start 149.0575 102.2575) (end 149.415 101.9) (width 0.125) (layer "F.Cu") (net 96))
  (segment (start 148.596454 112.69998) (end 148.8 112.496434) (width 0.125) (layer "F.Cu") (net 96))
  (segment (start 148.8 102.515) (end 149.0575 102.2575) (width 0.125) (layer "F.Cu") (net 96))
  (segment (start 148.8 112.496434) (end 148.8 102.515) (width 0.125) (layer "F.Cu") (net 96))
  (segment (start 130.25 118.55) (end 130.25 116.542867) (width 0.125) (layer "F.Cu") (net 96))
  (segment (start 130.25 116.542867) (end 134.092886 112.69998) (width 0.125) (layer "F.Cu") (net 96))
  (segment (start 134.092886 112.69998) (end 148.596454 112.69998) (width 0.125) (layer "F.Cu") (net 96))
  (segment (start 149.05001 112.59999) (end 149.05001 112.45001) (width 0.125) (layer "F.Cu") (net 97))
  (segment (start 130.75 118.55) (end 130.75 116.396434) (width 0.125) (layer "F.Cu") (net 97))
  (segment (start 149.05001 108.26499) (end 149.05001 112.45001) (width 0.125) (layer "F.Cu") (net 97))
  (segment (start 148.70001 112.94999) (end 149.05001 112.59999) (width 0.125) (layer "F.Cu") (net 97))
  (segment (start 149.05001 112.45001) (end 149.05001 112.54999) (width 0.125) (layer "F.Cu") (net 97))
  (segment (start 130.75 116.396434) (end 134.196443 112.94999) (width 0.125) (layer "F.Cu") (net 97))
  (segment (start 134.196443 112.94999) (end 148.70001 112.94999) (width 0.125) (layer "F.Cu") (net 97))
  (segment (start 149.415 107.9) (end 149.05001 108.26499) (width 0.125) (layer "F.Cu") (net 97))
  (segment (start 131.75 119.75) (end 131.75 118.55) (width 0.15) (layer "F.Cu") (net 98))
  (segment (start 95.2 143.825) (end 95.2 144.5) (width 0.15) (layer "F.Cu") (net 98))
  (segment (start 131.6 119.8) (end 131.75 119.75) (width 0.15) (layer "F.Cu") (net 98))
  (segment (start 95.2 144.5) (end 95.3 144.6) (width 0.15) (layer "F.Cu") (net 98))
  (via (at 95.3 144.6) (size 0.6) (drill 0.25) (layers "F.Cu" "B.Cu") (net 98))
  (via (at 131.6 119.8) (size 0.6) (drill 0.25) (layers "F.Cu" "B.Cu") (net 98))
  (segment (start 94.9 143.4) (end 97.550001 140.749999) (width 0.15) (layer "In2.Cu") (net 98))
  (segment (start 131.6 120.2) (end 131.4 120.4) (width 0.15) (layer "In2.Cu") (net 98))
  (segment (start 131.4 120.4) (end 131.4 138.2) (width 0.15) (layer "In2.Cu") (net 98))
  (segment (start 98.449999 140.749999) (end 97.550001 140.749999) (width 0.15) (layer "In2.Cu") (net 98))
  (segment (start 114 138.6) (end 113.7 138.9) (width 0.15) (layer "In2.Cu") (net 98))
  (segment (start 131 138.6) (end 114 138.6) (width 0.15) (layer "In2.Cu") (net 98))
  (segment (start 113.7 138.9) (end 113.7 140.288922) (width 0.15) (layer "In2.Cu") (net 98))
  (segment (start 112.249999 140.749999) (end 98.449999 140.749999) (width 0.15) (layer "In2.Cu") (net 98))
  (segment (start 113.238923 140.749999) (end 112.249999 140.749999) (width 0.15) (layer "In2.Cu") (net 98))
  (segment (start 94.9 144.2) (end 94.9 143.4) (width 0.15) (layer "In2.Cu") (net 98))
  (segment (start 113.7 140.288922) (end 113.238923 140.749999) (width 0.15) (layer "In2.Cu") (net 98))
  (segment (start 95.3 144.6) (end 94.9 144.2) (width 0.15) (layer "In2.Cu") (net 98))
  (segment (start 131.6 119.8) (end 131.6 120.2) (width 0.15) (layer "In2.Cu") (net 98))
  (segment (start 131.4 138.2) (end 131 138.6) (width 0.15) (layer "In2.Cu") (net 98))
  (segment (start 96.4 144.6508) (end 95.3508 144.6508) (width 0.15) (layer "B.Cu") (net 98))
  (segment (start 95.3508 144.6508) (end 95.3 144.6) (width 0.15) (layer "B.Cu") (net 98))
  (segment (start 111.028953 136.211049) (end 111.028953 135.981672) (width 0.15) (layer "F.Cu") (net 99))
  (segment (start 110.7 136.540002) (end 111.028953 136.211049) (width 0.15) (layer "F.Cu") (net 99))
  (segment (start 112.75 112.45) (end 112.75 113.65) (width 0.155) (layer "F.Cu") (net 99))
  (segment (start 110.7 137.45) (end 110.7 136.540002) (width 0.15) (layer "F.Cu") (net 99))
  (via (at 111.028953 135.981672) (size 0.6) (drill 0.25) (layers "F.Cu" "B.Cu") (net 99))
  (via (at 112.75 113.65) (size 0.6) (drill 0.25) (layers "F.Cu" "B.Cu") (net 99))
  (via (at 110.4 116.8) (size 0.6) (drill 0.25) (layers "F.Cu" "B.Cu") (net 99))
  (segment (start 112.1 120.8) (end 112.1 117.1) (width 0.15) (layer "In2.Cu") (net 99))
  (segment (start 119.77501 136.213912) (end 119.77501 131.886088) (width 0.15) (layer "In2.Cu") (net 99))
  (segment (start 119.77501 131.886088) (end 118.5 130.611078) (width 0.15) (layer "In2.Cu") (net 99))
  (segment (start 118.2 122) (end 113.3 122) (width 0.15) (layer "In2.Cu") (net 99))
  (segment (start 111.028953 136.628954) (end 111.3 136.900001) (width 0.15) (layer "In2.Cu") (net 99))
  (segment (start 111.028953 135.981672) (end 111.028953 136.628954) (width 0.15) (layer "In2.Cu") (net 99))
  (segment (start 119.088921 136.900001) (end 119.77501 136.213912) (width 0.15) (layer "In2.Cu") (net 99))
  (segment (start 118.5 130.611078) (end 118.5 122.3) (width 0.15) (layer "In2.Cu") (net 99))
  (segment (start 118.5 122.3) (end 118.2 122) (width 0.15) (layer "In2.Cu") (net 99))
  (segment (start 113.3 122) (end 112.1 120.8) (width 0.15) (layer "In2.Cu") (net 99))
  (segment (start 111.3 136.900001) (end 119.088921 136.900001) (width 0.15) (layer "In2.Cu") (net 99))
  (segment (start 111.8 116.8) (end 110.4 116.8) (width 0.15) (layer "In2.Cu") (net 99))
  (segment (start 112.1 117.1) (end 111.8 116.8) (width 0.15) (layer "In2.Cu") (net 99))
  (segment (start 112.75 114.95) (end 112.75 113.65) (width 0.155) (layer "B.Cu") (net 99))
  (segment (start 108.2492 135.9) (end 108.824201 135.324999) (width 0.15) (layer "B.Cu") (net 99))
  (segment (start 111.15 116.55) (end 112.75 114.95) (width 0.155) (layer "B.Cu") (net 99))
  (segment (start 108.824201 135.324999) (end 110.37228 135.324999) (width 0.15) (layer "B.Cu") (net 99))
  (segment (start 110.9 116.8) (end 111.15 116.55) (width 0.15) (layer "B.Cu") (net 99))
  (segment (start 110.4 116.8) (end 110.9 116.8) (width 0.15) (layer "B.Cu") (net 99))
  (segment (start 110.37228 135.324999) (end 111.028953 135.981672) (width 0.15) (layer "B.Cu") (net 99))
  (segment (start 115.1 88.2) (end 115.1 87) (width 0.15) (layer "F.Cu") (net 100))
  (segment (start 115.1 87) (end 114.6 86.5) (width 0.15) (layer "F.Cu") (net 100))
  (segment (start 105.5 86.5) (end 105.25 86.25) (width 0.15) (layer "F.Cu") (net 100))
  (segment (start 105.25 83.45) (end 105.25 85.65) (width 0.125) (layer "F.Cu") (net 100))
  (segment (start 105.25 83.45) (end 105.25 86.25) (width 0.15) (layer "F.Cu") (net 100))
  (segment (start 110.3 137.45) (end 110.3 136.2) (width 0.15) (layer "F.Cu") (net 100))
  (segment (start 114.6 86.5) (end 105.5 86.5) (width 0.15) (layer "F.Cu") (net 100))
  (segment (start 105.25 85.65) (end 105.25 86.25) (width 0.15) (layer "F.Cu") (net 100))
  (via (at 115.1 88.2) (size 0.6) (drill 0.25) (layers "F.Cu" "B.Cu") (net 100))
  (via (at 110.3 136.2) (size 0.6) (drill 0.25) (layers "F.Cu" "B.Cu") (net 100))
  (via (at 118.2 131.3) (size 0.6) (drill 0.25) (layers "F.Cu" "B.Cu") (net 100))
  (segment (start 119.5 136.1) (end 119.5 132) (width 0.15) (layer "In2.Cu") (net 100))
  (segment (start 112.3 136.3) (end 112.624991 136.624991) (width 0.15) (layer "In2.Cu") (net 100))
  (segment (start 118.975009 136.624991) (end 119.5 136.1) (width 0.15) (layer "In2.Cu") (net 100))
  (segment (start 110.3 136.2) (end 110.3 135.775736) (width 0.15) (layer "In2.Cu") (net 100))
  (segment (start 118.8 131.3) (end 118.2 131.3) (width 0.15) (layer "In2.Cu") (net 100))
  (segment (start 119.5 132) (end 118.8 131.3) (width 0.15) (layer "In2.Cu") (net 100))
  (segment (start 110.675736 135.4) (end 112 135.4) (width 0.15) (layer "In2.Cu") (net 100))
  (segment (start 112.624991 136.624991) (end 118.975009 136.624991) (width 0.15) (layer "In2.Cu") (net 100))
  (segment (start 112.3 135.7) (end 112.3 136.3) (width 0.15) (layer "In2.Cu") (net 100))
  (segment (start 110.3 135.775736) (end 110.675736 135.4) (width 0.15) (layer "In2.Cu") (net 100))
  (segment (start 112 135.4) (end 112.3 135.7) (width 0.15) (layer "In2.Cu") (net 100))
  (segment (start 107.7492 136.6) (end 107.0492 135.9) (width 0.15) (layer "B.Cu") (net 100))
  (segment (start 118.4 103.7) (end 118.4 131.1) (width 0.15) (layer "B.Cu") (net 100))
  (segment (start 114.749999 91.049999) (end 115.35002 91.65002) (width 0.15) (layer "B.Cu") (net 100))
  (segment (start 114.749999 88.750001) (end 114.749999 91.049999) (width 0.15) (layer "B.Cu") (net 100))
  (segment (start 115.8 102.7) (end 116.1 103) (width 0.15) (layer "B.Cu") (net 100))
  (segment (start 115.1 88.2) (end 115.1 88.4) (width 0.15) (layer "B.Cu") (net 100))
  (segment (start 109.259999 136.900001) (end 108.959998 136.6) (width 0.15) (layer "B.Cu") (net 100))
  (segment (start 115.35002 94.15002) (end 115.8 94.6) (width 0.15) (layer "B.Cu") (net 100))
  (segment (start 117.7 103) (end 118.4 103.7) (width 0.15) (layer "B.Cu") (net 100))
  (segment (start 116.1 103) (end 117.7 103) (width 0.15) (layer "B.Cu") (net 100))
  (segment (start 110.3 136.2) (end 110.3 136.624264) (width 0.15) (layer "B.Cu") (net 100))
  (segment (start 108.959998 136.6) (end 107.7492 136.6) (width 0.15) (layer "B.Cu") (net 100))
  (segment (start 118.4 131.1) (end 118.2 131.3) (width 0.15) (layer "B.Cu") (net 100))
  (segment (start 110.024263 136.900001) (end 109.899999 136.900001) (width 0.15) (layer "B.Cu") (net 100))
  (segment (start 110.3 136.624264) (end 110.024263 136.900001) (width 0.15) (layer "B.Cu") (net 100))
  (segment (start 109.899999 136.900001) (end 109.259999 136.900001) (width 0.15) (layer "B.Cu") (net 100))
  (segment (start 115.8 94.6) (end 115.8 102.7) (width 0.15) (layer "B.Cu") (net 100))
  (segment (start 115.35002 91.65002) (end 115.35002 94.15002) (width 0.15) (layer "B.Cu") (net 100))
  (segment (start 115.1 88.4) (end 114.749999 88.750001) (width 0.15) (layer "B.Cu") (net 100))
  (segment (start 119.8 113.955) (end 119.8 114.8) (width 0.155) (layer "F.Cu") (net 101))
  (segment (start 119.25 113.405) (end 119.8 113.955) (width 0.155) (layer "F.Cu") (net 101))
  (segment (start 109.9 136.8) (end 109.5 136.4) (width 0.15) (layer "F.Cu") (net 101))
  (segment (start 119.25 112.45) (end 119.25 113.405) (width 0.155) (layer "F.Cu") (net 101))
  (segment (start 109.9 137.45) (end 109.9 136.8) (width 0.15) (layer "F.Cu") (net 101))
  (via (at 109.5 136.4) (size 0.6) (drill 0.25) (layers "F.Cu" "B.Cu") (net 101))
  (via (at 119.8 114.8) (size 0.6) (drill 0.25) (layers "F.Cu" "B.Cu") (net 101))
  (via (at 119.5 130.8) (size 0.6) (drill 0.25) (layers "F.Cu" "B.Cu") (net 101))
  (segment (start 118.875011 137.175011) (end 118.724989 137.175011) (width 0.15) (layer "In2.Cu") (net 101))
  (segment (start 109.5 136.9) (end 109.5 136.4) (width 0.15) (layer "In2.Cu") (net 101))
  (segment (start 118.875011 137.175011) (end 119.202833 137.175011) (width 0.15) (layer "In2.Cu") (net 101))
  (segment (start 118.724989 137.175011) (end 109.775011 137.175011) (width 0.15) (layer "In2.Cu") (net 101))
  (segment (start 109.775011 137.175011) (end 109.5 136.9) (width 0.15) (layer "In2.Cu") (net 101))
  (segment (start 120.05002 136.327824) (end 120.05002 131.75002) (width 0.15) (layer "In2.Cu") (net 101))
  (segment (start 120.05002 131.75002) (end 119.5 131.2) (width 0.15) (layer "In2.Cu") (net 101))
  (segment (start 119.5 131.2) (end 119.5 130.8) (width 0.15) (layer "In2.Cu") (net 101))
  (segment (start 119.202833 137.175011) (end 120.05002 136.327824) (width 0.15) (layer "In2.Cu") (net 101))
  (segment (start 119.22503 130.52503) (end 119.5 130.8) (width 0.15) (layer "B.Cu") (net 101))
  (segment (start 119.22503 115.37497) (end 119.22503 130.52503) (width 0.15) (layer "B.Cu") (net 101))
  (segment (start 109.4492 136.3492) (end 109.5 136.4) (width 0.15) (layer "B.Cu") (net 101))
  (segment (start 119.8 114.8) (end 119.22503 115.37497) (width 0.15) (layer "B.Cu") (net 101))
  (segment (start 109.4492 135.9) (end 109.4492 136.3492) (width 0.15) (layer "B.Cu") (net 101))
  (segment (start 105.75 111.493702) (end 105.86 111.383702) (width 0.155) (layer "F.Cu") (net 102))
  (segment (start 105.75 112.45) (end 105.75 111.493702) (width 0.155) (layer "F.Cu") (net 102))
  (segment (start 105.86 111.383702) (end 105.86 110.684924) (width 0.155) (layer "F.Cu") (net 102))
  (segment (start 105.86 110.684924) (end 105.6375 110.462424) (width 0.155) (layer "F.Cu") (net 102))
  (via (at 105.6375 110.462424) (size 0.6) (drill 0.25) (layers "F.Cu" "B.Cu") (net 102))
  (segment (start 116.89 131.50799) (end 117.34 131.05799) (width 0.155) (layer "B.Cu") (net 102))
  (segment (start 117.34 131.05799) (end 117.34 129.64201) (width 0.155) (layer "B.Cu") (net 102))
  (segment (start 107.64 112.44201) (end 107.64 109.24201) (width 0.155) (layer "B.Cu") (net 102))
  (segment (start 107.25799 108.86) (end 106.34201 108.86) (width 0.155) (layer "B.Cu") (net 102))
  (segment (start 109.14 113.94201) (end 109.14 127.94201) (width 0.155) (layer "B.Cu") (net 102))
  (segment (start 117 131.795) (end 116.89 131.685) (width 0.155) (layer "B.Cu") (net 102))
  (segment (start 117 132.15) (end 117 131.795) (width 0.155) (layer "B.Cu") (net 102))
  (segment (start 105.86 110.239924) (end 105.6375 110.462424) (width 0.155) (layer "B.Cu") (net 102))
  (segment (start 107.64 109.24201) (end 107.25799 108.86) (width 0.155) (layer "B.Cu") (net 102))
  (segment (start 117.34 129.64201) (end 116.75799 129.06) (width 0.155) (layer "B.Cu") (net 102))
  (segment (start 109.14 127.94201) (end 110.25799 129.06) (width 0.155) (layer "B.Cu") (net 102))
  (segment (start 110.25799 129.06) (end 116.75799 129.06) (width 0.155) (layer "B.Cu") (net 102))
  (segment (start 105.86 109.34201) (end 105.86 110.239924) (width 0.155) (layer "B.Cu") (net 102))
  (segment (start 116.89 131.685) (end 116.89 131.50799) (width 0.155) (layer "B.Cu") (net 102))
  (segment (start 106.34201 108.86) (end 105.86 109.34201) (width 0.155) (layer "B.Cu") (net 102))
  (segment (start 109.14 113.94201) (end 107.64 112.44201) (width 0.155) (layer "B.Cu") (net 102))
  (segment (start 106.25 111.493702) (end 106.14 111.383702) (width 0.155) (layer "F.Cu") (net 103))
  (segment (start 106.14 110.684924) (end 106.3625 110.462424) (width 0.155) (layer "F.Cu") (net 103))
  (segment (start 106.14 111.383702) (end 106.14 110.684924) (width 0.155) (layer "F.Cu") (net 103))
  (segment (start 106.25 112.45) (end 106.25 111.493702) (width 0.155) (layer "F.Cu") (net 103))
  (via (at 106.3625 110.462424) (size 0.6) (drill 0.25) (layers "F.Cu" "B.Cu") (net 103))
  (segment (start 115.125509 129.343887) (end 115.16 129.34) (width 0.155) (layer "B.Cu") (net 103))
  (segment (start 114.917251 129.674651) (end 114.94664 129.656184) (width 0.155) (layer "B.Cu") (net 103))
  (segment (start 107.30164 110.258816) (end 107.326183 110.283359) (width 0.155) (layer "B.Cu") (net 103))
  (segment (start 114.710349 129.602252) (end 114.728816 129.631641) (width 0.155) (layer "B.Cu") (net 103))
  (segment (start 106.993269 110.137251) (end 107.011736 110.16664) (width 0.155) (layer "B.Cu") (net 103))
  (segment (start 115.16 129.34) (end 116.64201 129.34) (width 0.155) (layer "B.Cu") (net 103))
  (segment (start 114.85 129.69) (end 114.88449 129.686114) (width 0.155) (layer "B.Cu") (net 103))
  (segment (start 114.661183 129.39836) (end 114.67965 129.427749) (width 0.155) (layer "B.Cu") (net 103))
  (segment (start 107.036279 109.948816) (end 107.011736 109.973359) (width 0.155) (layer "B.Cu") (net 103))
  (segment (start 117.06 129.75799) (end 117.06 130.94201) (width 0.155) (layer "B.Cu") (net 103))
  (segment (start 106.993269 110.002748) (end 106.981806 110.035509) (width 0.155) (layer "B.Cu") (net 103))
  (segment (start 107.326183 109.85664) (end 107.30164 109.881183) (width 0.155) (layer "B.Cu") (net 103))
  (segment (start 106.97792 110.07) (end 106.981806 110.10449) (width 0.155) (layer "B.Cu") (net 103))
  (segment (start 114.698886 129.569491) (end 114.710349 129.602252) (width 0.155) (layer "B.Cu") (net 103))
  (segment (start 107.30164 109.881183) (end 107.272251 109.89965) (width 0.155) (layer "B.Cu") (net 103))
  (segment (start 107.205 110.225) (end 107.23949 110.228886) (width 0.155) (layer "B.Cu") (net 103))
  (segment (start 108.86 114.05799) (end 108.86 128.05799) (width 0.155) (layer "B.Cu") (net 103))
  (segment (start 107.23949 110.228886) (end 107.272251 110.240349) (width 0.155) (layer "B.Cu") (net 103))
  (segment (start 107.36 112.55799) (end 108.86 114.05799) (width 0.155) (layer "B.Cu") (net 103))
  (segment (start 115.038816 129.39836) (end 115.063359 129.373817) (width 0.155) (layer "B.Cu") (net 103))
  (segment (start 116.64201 129.34) (end 117.06 129.75799) (width 0.155) (layer "B.Cu") (net 103))
  (segment (start 115.001113 129.569491) (end 115.005 129.535) (width 0.155) (layer "B.Cu") (net 103))
  (segment (start 114.67965 129.427749) (end 114.691113 129.46051) (width 0.155) (layer "B.Cu") (net 103))
  (segment (start 107.356113 110.345509) (end 107.36 110.38) (width 0.155) (layer "B.Cu") (net 103))
  (segment (start 106.981806 110.10449) (end 106.993269 110.137251) (width 0.155) (layer "B.Cu") (net 103))
  (segment (start 106.14 109.45799) (end 106.45799 109.14) (width 0.155) (layer "B.Cu") (net 103))
  (segment (start 115.005 129.535) (end 115.005 129.495) (width 0.155) (layer "B.Cu") (net 103))
  (segment (start 114.63664 129.373817) (end 114.661183 129.39836) (width 0.155) (layer "B.Cu") (net 103))
  (segment (start 107.011736 109.973359) (end 106.993269 110.002748) (width 0.155) (layer "B.Cu") (net 103))
  (segment (start 115.092748 129.35535) (end 115.125509 129.343887) (width 0.155) (layer "B.Cu") (net 103))
  (segment (start 107.356113 109.79449) (end 107.34465 109.827251) (width 0.155) (layer "B.Cu") (net 103))
  (segment (start 116.61 131.685) (end 116.5 131.795) (width 0.155) (layer "B.Cu") (net 103))
  (segment (start 107.036279 110.191183) (end 107.065668 110.20965) (width 0.155) (layer "B.Cu") (net 103))
  (segment (start 114.753359 129.656184) (end 114.782748 129.674651) (width 0.155) (layer "B.Cu") (net 103))
  (segment (start 114.695 129.495) (end 114.695 129.535) (width 0.155) (layer "B.Cu") (net 103))
  (segment (start 114.88449 129.686114) (end 114.917251 129.674651) (width 0.155) (layer "B.Cu") (net 103))
  (segment (start 114.94664 129.656184) (end 114.971183 129.631641) (width 0.155) (layer "B.Cu") (net 103))
  (segment (start 114.815509 129.686114) (end 114.85 129.69) (width 0.155) (layer "B.Cu") (net 103))
  (segment (start 114.728816 129.631641) (end 114.753359 129.656184) (width 0.155) (layer "B.Cu") (net 103))
  (segment (start 114.54 129.34) (end 114.57449 129.343887) (width 0.155) (layer "B.Cu") (net 103))
  (segment (start 107.065668 110.20965) (end 107.098429 110.221113) (width 0.155) (layer "B.Cu") (net 103))
  (segment (start 114.691113 129.46051) (end 114.695 129.495) (width 0.155) (layer "B.Cu") (net 103))
  (segment (start 107.14201 109.14) (end 107.36 109.35799) (width 0.155) (layer "B.Cu") (net 103))
  (segment (start 107.36 110.38) (end 107.36 112.55799) (width 0.155) (layer "B.Cu") (net 103))
  (segment (start 106.981806 110.035509) (end 106.97792 110.07) (width 0.155) (layer "B.Cu") (net 103))
  (segment (start 107.23949 109.911113) (end 107.205 109.915) (width 0.155) (layer "B.Cu") (net 103))
  (segment (start 110.14201 129.34) (end 114.54 129.34) (width 0.155) (layer "B.Cu") (net 103))
  (segment (start 107.205 109.915) (end 107.13292 109.915) (width 0.155) (layer "B.Cu") (net 103))
  (segment (start 107.272251 109.89965) (end 107.23949 109.911113) (width 0.155) (layer "B.Cu") (net 103))
  (segment (start 115.005 129.495) (end 115.008886 129.46051) (width 0.155) (layer "B.Cu") (net 103))
  (segment (start 114.695 129.535) (end 114.698886 129.569491) (width 0.155) (layer "B.Cu") (net 103))
  (segment (start 107.36 109.35799) (end 107.36 109.76) (width 0.155) (layer "B.Cu") (net 103))
  (segment (start 116.61 131.39201) (end 116.61 131.685) (width 0.155) (layer "B.Cu") (net 103))
  (segment (start 106.45799 109.14) (end 107.14201 109.14) (width 0.155) (layer "B.Cu") (net 103))
  (segment (start 108.86 128.05799) (end 110.14201 129.34) (width 0.155) (layer "B.Cu") (net 103))
  (segment (start 114.57449 129.343887) (end 114.607251 129.35535) (width 0.155) (layer "B.Cu") (net 103))
  (segment (start 114.98965 129.602252) (end 115.001113 129.569491) (width 0.155) (layer "B.Cu") (net 103))
  (segment (start 115.063359 129.373817) (end 115.092748 129.35535) (width 0.155) (layer "B.Cu") (net 103))
  (segment (start 107.098429 110.221113) (end 107.13292 110.225) (width 0.155) (layer "B.Cu") (net 103))
  (segment (start 107.36 109.76) (end 107.356113 109.79449) (width 0.155) (layer "B.Cu") (net 103))
  (segment (start 106.14 110.239924) (end 106.14 109.45799) (width 0.155) (layer "B.Cu") (net 103))
  (segment (start 107.13292 110.225) (end 107.205 110.225) (width 0.155) (layer "B.Cu") (net 103))
  (segment (start 114.782748 129.674651) (end 114.815509 129.686114) (width 0.155) (layer "B.Cu") (net 103))
  (segment (start 107.13292 109.915) (end 107.098429 109.918886) (width 0.155) (layer "B.Cu") (net 103))
  (segment (start 107.34465 110.312748) (end 107.356113 110.345509) (width 0.155) (layer "B.Cu") (net 103))
  (segment (start 114.607251 129.35535) (end 114.63664 129.373817) (width 0.155) (layer "B.Cu") (net 103))
  (segment (start 107.326183 110.283359) (end 107.34465 110.312748) (width 0.155) (layer "B.Cu") (net 103))
  (segment (start 107.065668 109.930349) (end 107.036279 109.948816) (width 0.155) (layer "B.Cu") (net 103))
  (segment (start 107.011736 110.16664) (end 107.036279 110.191183) (width 0.155) (layer "B.Cu") (net 103))
  (segment (start 107.272251 110.240349) (end 107.30164 110.258816) (width 0.155) (layer "B.Cu") (net 103))
  (segment (start 115.008886 129.46051) (end 115.020349 129.427749) (width 0.155) (layer "B.Cu") (net 103))
  (segment (start 106.3625 110.462424) (end 106.14 110.239924) (width 0.155) (layer "B.Cu") (net 103))
  (segment (start 117.06 130.94201) (end 116.61 131.39201) (width 0.155) (layer "B.Cu") (net 103))
  (segment (start 116.5 131.795) (end 116.5 132.15) (width 0.155) (layer "B.Cu") (net 103))
  (segment (start 107.34465 109.827251) (end 107.326183 109.85664) (width 0.155) (layer "B.Cu") (net 103))
  (segment (start 115.020349 129.427749) (end 115.038816 129.39836) (width 0.155) (layer "B.Cu") (net 103))
  (segment (start 107.098429 109.918886) (end 107.065668 109.930349) (width 0.155) (layer "B.Cu") (net 103))
  (segment (start 114.971183 129.631641) (end 114.98965 129.602252) (width 0.155) (layer "B.Cu") (net 103))
  (segment (start 107.64 113.9775) (end 107.8625 114.2) (width 0.155) (layer "F.Cu") (net 104))
  (segment (start 107.64 113.760151) (end 107.64 113.9775) (width 0.155) (layer "F.Cu") (net 104))
  (segment (start 107.75 112.45) (end 107.75 113.650151) (width 0.155) (layer "F.Cu") (net 104))
  (segment (start 107.75 113.650151) (end 107.64 113.760151) (width 0.155) (layer "F.Cu") (net 104))
  (via (at 107.8625 114.2) (size 0.6) (drill 0.25) (layers "F.Cu" "B.Cu") (net 104))
  (segment (start 109.834697 129.951165) (end 109.922323 129.920504) (width 0.155) (layer "B.Cu") (net 104))
  (segment (start 111.804396 130.855989) (end 111.84 130.86) (width 0.155) (layer "B.Cu") (net 104))
  (segment (start 109.370578 131.794046) (end 109.404396 131.805879) (width 0.155) (layer "B.Cu") (net 104))
  (segment (start 111.84 130.86) (end 114.55799 130.86) (width 0.155) (layer "B.Cu") (net 104))
  (segment (start 107.225424 115.18) (end 106.66 115.18) (width 0.155) (layer "B.Cu") (net 104))
  (segment (start 107.700242 116.414906) (end 107.674907 116.440241) (width 0.155) (layer "B.Cu") (net 104))
  (segment (start 107.764397 116.384011) (end 107.730579 116.395844) (width 0.155) (layer "B.Cu") (net 104))
  (segment (start 106.624396 115.184011) (end 106.590578 115.195844) (width 0.155) (layer "B.Cu") (net 104))
  (segment (start 109.584155 131.719312) (end 109.595988 131.685494) (width 0.155) (layer "B.Cu") (net 104))
  (segment (start 110.8 131.649891) (end 110.8 130.324685) (width 0.155) (layer "B.Cu") (net 104))
  (segment (start 110.389552 130.066201) (end 110.438944 130.144807) (width 0.155) (layer "B.Cu") (net 104))
  (segment (start 111.68 130.7) (end 111.684011 130.735604) (width 0.155) (layer "B.Cu") (net 104))
  (segment (start 110.570578 131.794046) (end 110.604396 131.805879) (width 0.155) (layer "B.Cu") (net 104))
  (segment (start 110.484011 131.685494) (end 110.495844 131.719312) (width 0.155) (layer "B.Cu") (net 104))
  (segment (start 109.539758 131.774984) (end 109.565093 131.749649) (width 0.155) (layer "B.Cu") (net 104))
  (segment (start 106.5 115.34) (end 106.504011 115.375603) (width 0.155) (layer "B.Cu") (net 104))
  (segment (start 108.569606 116.057676) (end 108.538945 116.145302) (width 0.155) (layer "B.Cu") (net 104))
  (segment (start 106.560241 115.214906) (end 106.534906 115.240241) (width 0.155) (layer "B.Cu") (net 104))
  (segment (start 107.8625 114.2) (end 107.64 114.4225) (width 0.155) (layer "B.Cu") (net 104))
  (segment (start 106.515844 115.409421) (end 106.534906 115.439758) (width 0.155) (layer "B.Cu") (net 104))
  (segment (start 110.765093 131.749649) (end 110.784155 131.719312) (width 0.155) (layer "B.Cu") (net 104))
  (segment (start 107.64 114.4225) (end 107.64 114.765424) (width 0.155) (layer "B.Cu") (net 104))
  (segment (start 109.565093 131.749649) (end 109.584155 131.719312) (width 0.155) (layer "B.Cu") (net 104))
  (segment (start 107.644012 116.504396) (end 107.64 116.54) (width 0.155) (layer "B.Cu") (net 104))
  (segment (start 109.340241 131.774984) (end 109.370578 131.794046) (width 0.155) (layer "B.Cu") (net 104))
  (segment (start 109.595988 131.685494) (end 109.6 131.649891) (width 0.155) (layer "B.Cu") (net 104))
  (segment (start 107.674907 116.440241) (end 107.655845 116.470578) (width 0.155) (layer "B.Cu") (net 104))
  (segment (start 108.865424 130.86) (end 108.957676 130.870394) (width 0.155) (layer "B.Cu") (net 104))
  (segment (start 110.540241 131.774984) (end 110.570578 131.794046) (width 0.155) (layer "B.Cu") (net 104))
  (segment (start 114.55799 130.86) (end 114.89 131.19201) (width 0.155) (layer "B.Cu") (net 104))
  (segment (start 108.257677 116.369605) (end 108.165425 116.38) (width 0.155) (layer "B.Cu") (net 104))
  (segment (start 110.841055 130.144807) (end 110.890447 130.066201) (width 0.155) (layer "B.Cu") (net 104))
  (segment (start 111.638944 130.144807) (end 111.669605 130.232433) (width 0.155) (layer "B.Cu") (net 104))
  (segment (start 109.756091 130.000557) (end 109.834697 129.951165) (width 0.155) (layer "B.Cu") (net 104))
  (segment (start 108.957676 130.870394) (end 109.045302 130.901055) (width 0.155) (layer "B.Cu") (net 104))
  (segment (start 110.8 130.324685) (end 110.810394 130.232433) (width 0.155) (layer "B.Cu") (net 104))
  (segment (start 107.629605 114.857676) (end 107.598944 114.945302) (width 0.155) (layer "B.Cu") (net 104))
  (segment (start 108.58 115.914575) (end 108.58 115.965424) (width 0.155) (layer "B.Cu") (net 104))
  (segment (start 110.48 131.649891) (end 110.484011 131.685494) (width 0.155) (layer "B.Cu") (net 104))
  (segment (start 107.8 116.38) (end 107.764397 116.384011) (width 0.155) (layer "B.Cu") (net 104))
  (segment (start 110.739758 131.774984) (end 110.765093 131.749649) (width 0.155) (layer "B.Cu") (net 104))
  (segment (start 108.165425 115.5) (end 108.257677 115.510394) (width 0.155) (layer "B.Cu") (net 104))
  (segment (start 110.890447 130.066201) (end 110.956091 130.000557) (width 0.155) (layer "B.Cu") (net 104))
  (segment (start 107.317676 115.169605) (end 107.225424 115.18) (width 0.155) (layer "B.Cu") (net 104))
  (segment (start 111.445302 129.951165) (end 111.523908 130.000557) (width 0.155) (layer "B.Cu") (net 104))
  (segment (start 110.245302 129.951165) (end 110.323908 130.000557) (width 0.155) (layer "B.Cu") (net 104))
  (segment (start 109.295844 131.719312) (end 109.314906 131.749649) (width 0.155) (layer "B.Cu") (net 104))
  (segment (start 109.922323 129.920504) (end 110.014575 129.910109) (width 0.155) (layer "B.Cu") (net 104))
  (segment (start 107.598944 114.945302) (end 107.549552 115.023908) (width 0.155) (layer "B.Cu") (net 104))
  (segment (start 110.795988 131.685494) (end 110.8 131.649891) (width 0.155) (layer "B.Cu") (net 104))
  (segment (start 106.534906 115.240241) (end 106.515844 115.270578) (width 0.155) (layer "B.Cu") (net 104))
  (segment (start 106.504011 115.304396) (end 106.5 115.34) (width 0.155) (layer "B.Cu") (net 104))
  (segment (start 111.770578 130.844156) (end 111.804396 130.855989) (width 0.155) (layer "B.Cu") (net 104))
  (segment (start 109.045302 130.901055) (end 109.123908 130.950447) (width 0.155) (layer "B.Cu") (net 104))
  (segment (start 111.034697 129.951165) (end 111.122323 129.920504) (width 0.155) (layer "B.Cu") (net 104))
  (segment (start 108.58 115.965424) (end 108.569606 116.057676) (width 0.155) (layer "B.Cu") (net 104))
  (segment (start 115 131.795) (end 115 132.15) (width 0.155) (layer "B.Cu") (net 104))
  (segment (start 106.515844 115.270578) (end 106.504011 115.304396) (width 0.155) (layer "B.Cu") (net 104))
  (segment (start 111.523908 130.000557) (end 111.589552 130.066201) (width 0.155) (layer "B.Cu") (net 104))
  (segment (start 108.489553 115.656091) (end 108.538945 115.734697) (width 0.155) (layer "B.Cu") (net 104))
  (segment (start 111.695844 130.769422) (end 111.714906 130.799759) (width 0.155) (layer "B.Cu") (net 104))
  (segment (start 109.6 131.649891) (end 109.6 130.324685) (width 0.155) (layer "B.Cu") (net 104))
  (segment (start 108.423909 115.590447) (end 108.489553 115.656091) (width 0.155) (layer "B.Cu") (net 104))
  (segment (start 107.64 114.765424) (end 107.629605 114.857676) (width 0.155) (layer "B.Cu") (net 104))
  (segment (start 106.624396 115.495988) (end 106.66 115.5) (width 0.155) (layer "B.Cu") (net 104))
  (segment (start 109.28 131.274575) (end 109.28 131.649891) (width 0.155) (layer "B.Cu") (net 104))
  (segment (start 108.538945 115.734697) (end 108.569606 115.822323) (width 0.155) (layer "B.Cu") (net 104))
  (segment (start 110.065424 129.910109) (end 110.157676 129.920504) (width 0.155) (layer "B.Cu") (net 104))
  (segment (start 110.157676 129.920504) (end 110.245302 129.951165) (width 0.155) (layer "B.Cu") (net 104))
  (segment (start 109.44 131.809891) (end 109.475603 131.805879) (width 0.155) (layer "B.Cu") (net 104))
  (segment (start 110.604396 131.805879) (end 110.64 131.809891) (width 0.155) (layer "B.Cu") (net 104))
  (segment (start 107.64 130.24201) (end 108.25799 130.86) (width 0.155) (layer "B.Cu") (net 104))
  (segment (start 109.123908 130.950447) (end 109.189552 131.016091) (width 0.155) (layer "B.Cu") (net 104))
  (segment (start 111.265424 129.910109) (end 111.357676 129.920504) (width 0.155) (layer "B.Cu") (net 104))
  (segment (start 109.404396 131.805879) (end 109.44 131.809891) (width 0.155) (layer "B.Cu") (net 104))
  (segment (start 106.560241 115.465093) (end 106.590578 115.484155) (width 0.155) (layer "B.Cu") (net 104))
  (segment (start 108.165425 116.38) (end 107.8 116.38) (width 0.155) (layer "B.Cu") (net 104))
  (segment (start 107.483908 115.089552) (end 107.405302 115.138944) (width 0.155) (layer "B.Cu") (net 104))
  (segment (start 114.89 131.19201) (end 114.89 131.685) (width 0.155) (layer "B.Cu") (net 104))
  (segment (start 110.956091 130.000557) (end 111.034697 129.951165) (width 0.155) (layer "B.Cu") (net 104))
  (segment (start 109.641055 130.144807) (end 109.690447 130.066201) (width 0.155) (layer "B.Cu") (net 104))
  (segment (start 109.238944 131.094697) (end 109.269605 131.182323) (width 0.155) (layer "B.Cu") (net 104))
  (segment (start 110.469605 130.232433) (end 110.48 130.324685) (width 0.155) (layer "B.Cu") (net 104))
  (segment (start 108.538945 116.145302) (end 108.489553 116.223908) (width 0.155) (layer "B.Cu") (net 104))
  (segment (start 106.590578 115.195844) (end 106.560241 115.214906) (width 0.155) (layer "B.Cu") (net 104))
  (segment (start 109.475603 131.805879) (end 109.509421 131.794046) (width 0.155) (layer "B.Cu") (net 104))
  (segment (start 111.589552 130.066201) (end 111.638944 130.144807) (width 0.155) (layer "B.Cu") (net 104))
  (segment (start 107.405302 115.138944) (end 107.317676 115.169605) (width 0.155) (layer "B.Cu") (net 104))
  (segment (start 108.345303 116.338944) (end 108.257677 116.369605) (width 0.155) (layer "B.Cu") (net 104))
  (segment (start 109.509421 131.794046) (end 109.539758 131.774984) (width 0.155) (layer "B.Cu") (net 104))
  (segment (start 106.66 115.18) (end 106.624396 115.184011) (width 0.155) (layer "B.Cu") (net 104))
  (segment (start 109.28 131.649891) (end 109.284011 131.685494) (width 0.155) (layer "B.Cu") (net 104))
  (segment (start 108.423909 116.289552) (end 108.345303 116.338944) (width 0.155) (layer "B.Cu") (net 104))
  (segment (start 110.784155 131.719312) (end 110.795988 131.685494) (width 0.155) (layer "B.Cu") (net 104))
  (segment (start 110.438944 130.144807) (end 110.469605 130.232433) (width 0.155) (layer "B.Cu") (net 104))
  (segment (start 110.810394 130.232433) (end 110.841055 130.144807) (width 0.155) (layer "B.Cu") (net 104))
  (segment (start 109.690447 130.066201) (end 109.756091 130.000557) (width 0.155) (layer "B.Cu") (net 104))
  (segment (start 109.6 130.324685) (end 109.610394 130.232433) (width 0.155) (layer "B.Cu") (net 104))
  (segment (start 110.514906 131.749649) (end 110.540241 131.774984) (width 0.155) (layer "B.Cu") (net 104))
  (segment (start 107.64 116.54) (end 107.64 130.24201) (width 0.155) (layer "B.Cu") (net 104))
  (segment (start 107.549552 115.023908) (end 107.483908 115.089552) (width 0.155) (layer "B.Cu") (net 104))
  (segment (start 108.345303 115.541055) (end 108.423909 115.590447) (width 0.155) (layer "B.Cu") (net 104))
  (segment (start 106.534906 115.439758) (end 106.560241 115.465093) (width 0.155) (layer "B.Cu") (net 104))
  (segment (start 109.269605 131.182323) (end 109.28 131.274575) (width 0.155) (layer "B.Cu") (net 104))
  (segment (start 106.66 115.5) (end 108.165425 115.5) (width 0.155) (layer "B.Cu") (net 104))
  (segment (start 111.68 130.324685) (end 111.68 130.7) (width 0.155) (layer "B.Cu") (net 104))
  (segment (start 106.590578 115.484155) (end 106.624396 115.495988) (width 0.155) (layer "B.Cu") (net 104))
  (segment (start 111.714906 130.799759) (end 111.740241 130.825094) (width 0.155) (layer "B.Cu") (net 104))
  (segment (start 109.610394 130.232433) (end 109.641055 130.144807) (width 0.155) (layer "B.Cu") (net 104))
  (segment (start 110.64 131.809891) (end 110.675603 131.805879) (width 0.155) (layer "B.Cu") (net 104))
  (segment (start 110.495844 131.719312) (end 110.514906 131.749649) (width 0.155) (layer "B.Cu") (net 104))
  (segment (start 110.675603 131.805879) (end 110.709421 131.794046) (width 0.155) (layer "B.Cu") (net 104))
  (segment (start 110.014575 129.910109) (end 110.065424 129.910109) (width 0.155) (layer "B.Cu") (net 104))
  (segment (start 111.357676 129.920504) (end 111.445302 129.951165) (width 0.155) (layer "B.Cu") (net 104))
  (segment (start 114.89 131.685) (end 115 131.795) (width 0.155) (layer "B.Cu") (net 104))
  (segment (start 106.504011 115.375603) (end 106.515844 115.409421) (width 0.155) (layer "B.Cu") (net 104))
  (segment (start 111.740241 130.825094) (end 111.770578 130.844156) (width 0.155) (layer "B.Cu") (net 104))
  (segment (start 109.189552 131.016091) (end 109.238944 131.094697) (width 0.155) (layer "B.Cu") (net 104))
  (segment (start 108.569606 115.822323) (end 108.58 115.914575) (width 0.155) (layer "B.Cu") (net 104))
  (segment (start 111.122323 129.920504) (end 111.214575 129.910109) (width 0.155) (layer "B.Cu") (net 104))
  (segment (start 108.257677 115.510394) (end 108.345303 115.541055) (width 0.155) (layer "B.Cu") (net 104))
  (segment (start 109.284011 131.685494) (end 109.295844 131.719312) (width 0.155) (layer "B.Cu") (net 104))
  (segment (start 107.730579 116.395844) (end 107.700242 116.414906) (width 0.155) (layer "B.Cu") (net 104))
  (segment (start 110.709421 131.794046) (end 110.739758 131.774984) (width 0.155) (layer "B.Cu") (net 104))
  (segment (start 111.684011 130.735604) (end 111.695844 130.769422) (width 0.155) (layer "B.Cu") (net 104))
  (segment (start 111.214575 129.910109) (end 111.265424 129.910109) (width 0.155) (layer "B.Cu") (net 104))
  (segment (start 107.655845 116.470578) (end 107.644012 116.504396) (width 0.155) (layer "B.Cu") (net 104))
  (segment (start 110.323908 130.000557) (end 110.389552 130.066201) (width 0.155) (layer "B.Cu") (net 104))
  (segment (start 108.489553 116.223908) (end 108.423909 116.289552) (width 0.155) (layer "B.Cu") (net 104))
  (segment (start 111.669605 130.232433) (end 111.68 130.324685) (width 0.155) (layer "B.Cu") (net 104))
  (segment (start 109.314906 131.749649) (end 109.340241 131.774984) (width 0.155) (layer "B.Cu") (net 104))
  (segment (start 108.25799 130.86) (end 108.865424 130.86) (width 0.155) (layer "B.Cu") (net 104))
  (segment (start 110.48 130.324685) (end 110.48 131.649891) (width 0.155) (layer "B.Cu") (net 104))
  (segment (start 107.36 113.9775) (end 107.1375 114.2) (width 0.155) (layer "F.Cu") (net 105))
  (segment (start 107.250001 112.45) (end 107.250001 113.650151) (width 0.155) (layer "F.Cu") (net 105))
  (segment (start 107.250001 113.650151) (end 107.360001 113.760151) (width 0.155) (layer "F.Cu") (net 105))
  (segment (start 107.360001 113.760151) (end 107.36 113.9775) (width 0.155) (layer "F.Cu") (net 105))
  (via (at 107.1375 114.2) (size 0.6) (drill 0.25) (layers "F.Cu" "B.Cu") (net 105))
  (segment (start 114.44201 131.14) (end 114.61 131.30799) (width 0.155) (layer "B.Cu") (net 105))
  (segment (start 106.542323 115.769605) (end 106.634575 115.78) (width 0.155) (layer "B.Cu") (net 105))
  (segment (start 108.995988 131.264396) (end 109 131.3) (width 0.155) (layer "B.Cu") (net 105))
  (segment (start 106.376091 114.990447) (end 106.310447 115.056091) (width 0.155) (layer "B.Cu") (net 105))
  (segment (start 114.61 131.30799) (end 114.61 131.685) (width 0.155) (layer "B.Cu") (net 105))
  (segment (start 106.310447 115.623908) (end 106.376091 115.689552) (width 0.155) (layer "B.Cu") (net 105))
  (segment (start 107.235603 114.895988) (end 107.2 114.9) (width 0.155) (layer "B.Cu") (net 105))
  (segment (start 107.401056 116.334697) (end 107.370395 116.422323) (width 0.155) (layer "B.Cu") (net 105))
  (segment (start 109.838944 131.855193) (end 109.869605 131.767567) (width 0.155) (layer "B.Cu") (net 105))
  (segment (start 107.325093 114.839758) (end 107.299758 114.865093) (width 0.155) (layer "B.Cu") (net 105))
  (segment (start 106.454697 115.738944) (end 106.542323 115.769605) (width 0.155) (layer "B.Cu") (net 105))
  (segment (start 107.299758 114.865093) (end 107.269421 114.884155) (width 0.155) (layer "B.Cu") (net 105))
  (segment (start 110.184155 130.280688) (end 110.195988 130.314506) (width 0.155) (layer "B.Cu") (net 105))
  (segment (start 114.61 131.685) (end 114.5 131.795) (width 0.155) (layer "B.Cu") (net 105))
  (segment (start 106.261055 115.134697) (end 106.230394 115.222323) (width 0.155) (layer "B.Cu") (net 105))
  (segment (start 106.230394 115.222323) (end 106.22 115.314575) (width 0.155) (layer "B.Cu") (net 105))
  (segment (start 109.88 131.675315) (end 109.88 130.350109) (width 0.155) (layer "B.Cu") (net 105))
  (segment (start 111.410394 130.817677) (end 111.441055 130.905303) (width 0.155) (layer "B.Cu") (net 105))
  (segment (start 109.723908 131.999443) (end 109.789552 131.933799) (width 0.155) (layer "B.Cu") (net 105))
  (segment (start 106.22 115.365424) (end 106.230394 115.457676) (width 0.155) (layer "B.Cu") (net 105))
  (segment (start 111.095844 130.280688) (end 111.114906 130.250351) (width 0.155) (layer "B.Cu") (net 105))
  (segment (start 109.88 130.350109) (end 109.884011 130.314506) (width 0.155) (layer "B.Cu") (net 105))
  (segment (start 111.490447 130.983909) (end 111.556091 131.049553) (width 0.155) (layer "B.Cu") (net 105))
  (segment (start 108.909421 131.155844) (end 108.939758 131.174906) (width 0.155) (layer "B.Cu") (net 105))
  (segment (start 111.384155 130.280688) (end 111.395988 130.314506) (width 0.155) (layer "B.Cu") (net 105))
  (segment (start 107.36 114.74) (end 107.355988 114.775603) (width 0.155) (layer "B.Cu") (net 105))
  (segment (start 111.08 130.350109) (end 111.084011 130.314506) (width 0.155) (layer "B.Cu") (net 105))
  (segment (start 108.239759 116.065093) (end 108.209422 116.084155) (width 0.155) (layer "B.Cu") (net 105))
  (segment (start 109.414575 132.089891) (end 109.465424 132.089891) (width 0.155) (layer "B.Cu") (net 105))
  (segment (start 106.376091 115.689552) (end 106.454697 115.738944) (width 0.155) (layer "B.Cu") (net 105))
  (segment (start 110.923908 131.999443) (end 110.989552 131.933799) (width 0.155) (layer "B.Cu") (net 105))
  (segment (start 110.004396 130.194121) (end 110.04 130.190109) (width 0.155) (layer "B.Cu") (net 105))
  (segment (start 106.634575 115.78) (end 108.14 115.78) (width 0.155) (layer "B.Cu") (net 105))
  (segment (start 110.109421 130.205954) (end 110.139758 130.225016) (width 0.155) (layer "B.Cu") (net 105))
  (segment (start 107.450448 116.256091) (end 107.401056 116.334697) (width 0.155) (layer "B.Cu") (net 105))
  (segment (start 107.2 114.9) (end 106.634575 114.9) (width 0.155) (layer "B.Cu") (net 105))
  (segment (start 110.241055 131.855193) (end 110.290447 131.933799) (width 0.155) (layer "B.Cu") (net 105))
  (segment (start 110.665424 132.089891) (end 110.757676 132.079496) (width 0.155) (layer "B.Cu") (net 105))
  (segment (start 108.265094 115.840241) (end 108.284156 115.870578) (width 0.155) (layer "B.Cu") (net 105))
  (segment (start 110.139758 130.225016) (end 110.165093 130.250351) (width 0.155) (layer "B.Cu") (net 105))
  (segment (start 107.774576 116.1) (end 107.682324 116.110394) (width 0.155) (layer "B.Cu") (net 105))
  (segment (start 106.454697 114.941055) (end 106.376091 114.990447) (width 0.155) (layer "B.Cu") (net 105))
  (segment (start 111.441055 130.905303) (end 111.490447 130.983909) (width 0.155) (layer "B.Cu") (net 105))
  (segment (start 109.557676 132.079496) (end 109.645302 132.048835) (width 0.155) (layer "B.Cu") (net 105))
  (segment (start 110.195988 130.314506) (end 110.2 130.350109) (width 0.155) (layer "B.Cu") (net 105))
  (segment (start 110.614575 132.089891) (end 110.665424 132.089891) (width 0.155) (layer "B.Cu") (net 105))
  (segment (start 109.940241 130.225016) (end 109.970578 130.205954) (width 0.155) (layer "B.Cu") (net 105))
  (segment (start 107.516092 116.190447) (end 107.450448 116.256091) (width 0.155) (layer "B.Cu") (net 105))
  (segment (start 107.682324 116.110394) (end 107.594698 116.141055) (width 0.155) (layer "B.Cu") (net 105))
  (segment (start 108.209422 116.084155) (end 108.175604 116.095988) (width 0.155) (layer "B.Cu") (net 105))
  (segment (start 110.290447 131.933799) (end 110.356091 131.999443) (width 0.155) (layer "B.Cu") (net 105))
  (segment (start 107.344155 114.809421) (end 107.325093 114.839758) (width 0.155) (layer "B.Cu") (net 105))
  (segment (start 111.140241 130.225016) (end 111.170578 130.205954) (width 0.155) (layer "B.Cu") (net 105))
  (segment (start 109.322323 132.079496) (end 109.414575 132.089891) (width 0.155) (layer "B.Cu") (net 105))
  (segment (start 111.084011 130.314506) (end 111.095844 130.280688) (width 0.155) (layer "B.Cu") (net 105))
  (segment (start 108.295989 115.904396) (end 108.3 115.94) (width 0.155) (layer "B.Cu") (net 105))
  (segment (start 111.365093 130.250351) (end 111.384155 130.280688) (width 0.155) (layer "B.Cu") (net 105))
  (segment (start 111.309421 130.205954) (end 111.339758 130.225016) (width 0.155) (layer "B.Cu") (net 105))
  (segment (start 110.165093 130.250351) (end 110.184155 130.280688) (width 0.155) (layer "B.Cu") (net 105))
  (segment (start 106.542323 114.910394) (end 106.454697 114.941055) (width 0.155) (layer "B.Cu") (net 105))
  (segment (start 111.4 130.350109) (end 111.4 130.725425) (width 0.155) (layer "B.Cu") (net 105))
  (segment (start 108.939758 131.174906) (end 108.965093 131.200241) (width 0.155) (layer "B.Cu") (net 105))
  (segment (start 111.038944 131.855193) (end 111.069605 131.767567) (width 0.155) (layer "B.Cu") (net 105))
  (segment (start 107.36 114.4225) (end 107.36 114.74) (width 0.155) (layer "B.Cu") (net 105))
  (segment (start 111.204396 130.194121) (end 111.24 130.190109) (width 0.155) (layer "B.Cu") (net 105))
  (segment (start 111.395988 130.314506) (end 111.4 130.350109) (width 0.155) (layer "B.Cu") (net 105))
  (segment (start 108.14 116.1) (end 107.774576 116.1) (width 0.155) (layer "B.Cu") (net 105))
  (segment (start 110.757676 132.079496) (end 110.845302 132.048835) (width 0.155) (layer "B.Cu") (net 105))
  (segment (start 106.634575 114.9) (end 106.542323 114.910394) (width 0.155) (layer "B.Cu") (net 105))
  (segment (start 108.84 131.14) (end 108.875603 131.144011) (width 0.155) (layer "B.Cu") (net 105))
  (segment (start 109.090447 131.933799) (end 109.156091 131.999443) (width 0.155) (layer "B.Cu") (net 105))
  (segment (start 110.522323 132.079496) (end 110.614575 132.089891) (width 0.155) (layer "B.Cu") (net 105))
  (segment (start 107.1375 114.2) (end 107.36 114.4225) (width 0.155) (layer "B.Cu") (net 105))
  (segment (start 108.3 115.94) (end 108.295989 115.975603) (width 0.155) (layer "B.Cu") (net 105))
  (segment (start 108.14201 131.14) (end 108.84 131.14) (width 0.155) (layer "B.Cu") (net 105))
  (segment (start 107.370395 116.422323) (end 107.36 116.514575) (width 0.155) (layer "B.Cu") (net 105))
  (segment (start 109.895844 130.280688) (end 109.914906 130.250351) (width 0.155) (layer "B.Cu") (net 105))
  (segment (start 111.275603 130.194121) (end 111.309421 130.205954) (width 0.155) (layer "B.Cu") (net 105))
  (segment (start 111.634697 131.098945) (end 111.722323 131.129606) (width 0.155) (layer "B.Cu") (net 105))
  (segment (start 108.965093 131.200241) (end 108.984155 131.230578) (width 0.155) (layer "B.Cu") (net 105))
  (segment (start 107.269421 114.884155) (end 107.235603 114.895988) (width 0.155) (layer "B.Cu") (net 105))
  (segment (start 111.339758 130.225016) (end 111.365093 130.250351) (width 0.155) (layer "B.Cu") (net 105))
  (segment (start 109.041055 131.855193) (end 109.090447 131.933799) (width 0.155) (layer "B.Cu") (net 105))
  (segment (start 107.594698 116.141055) (end 107.516092 116.190447) (width 0.155) (layer "B.Cu") (net 105))
  (segment (start 107.36 130.35799) (end 108.14201 131.14) (width 0.155) (layer "B.Cu") (net 105))
  (segment (start 108.175604 115.784011) (end 108.209422 115.795844) (width 0.155) (layer "B.Cu") (net 105))
  (segment (start 108.265094 116.039758) (end 108.239759 116.065093) (width 0.155) (layer "B.Cu") (net 105))
  (segment (start 108.295989 115.975603) (end 108.284156 116.009421) (width 0.155) (layer "B.Cu") (net 105))
  (segment (start 111.114906 130.250351) (end 111.140241 130.225016) (width 0.155) (layer "B.Cu") (net 105))
  (segment (start 111.556091 131.049553) (end 111.634697 131.098945) (width 0.155) (layer "B.Cu") (net 105))
  (segment (start 109.465424 132.089891) (end 109.557676 132.079496) (width 0.155) (layer "B.Cu") (net 105))
  (segment (start 108.209422 115.795844) (end 108.239759 115.814906) (width 0.155) (layer "B.Cu") (net 105))
  (segment (start 111.814575 131.14) (end 114.44201 131.14) (width 0.155) (layer "B.Cu") (net 105))
  (segment (start 108.14 115.78) (end 108.175604 115.784011) (width 0.155) (layer "B.Cu") (net 105))
  (segment (start 110.434697 132.048835) (end 110.522323 132.079496) (width 0.155) (layer "B.Cu") (net 105))
  (segment (start 107.36 116.514575) (end 107.36 130.35799) (width 0.155) (layer "B.Cu") (net 105))
  (segment (start 110.989552 131.933799) (end 111.038944 131.855193) (width 0.155) (layer "B.Cu") (net 105))
  (segment (start 109.156091 131.999443) (end 109.234697 132.048835) (width 0.155) (layer "B.Cu") (net 105))
  (segment (start 109.234697 132.048835) (end 109.322323 132.079496) (width 0.155) (layer "B.Cu") (net 105))
  (segment (start 114.5 131.795) (end 114.5 132.15) (width 0.155) (layer "B.Cu") (net 105))
  (segment (start 110.356091 131.999443) (end 110.434697 132.048835) (width 0.155) (layer "B.Cu") (net 105))
  (segment (start 106.22 115.314575) (end 106.22 115.365424) (width 0.155) (layer "B.Cu") (net 105))
  (segment (start 111.08 131.675315) (end 111.08 130.350109) (width 0.155) (layer "B.Cu") (net 105))
  (segment (start 108.284156 115.870578) (end 108.295989 115.904396) (width 0.155) (layer "B.Cu") (net 105))
  (segment (start 106.261055 115.545302) (end 106.310447 115.623908) (width 0.155) (layer "B.Cu") (net 105))
  (segment (start 109.914906 130.250351) (end 109.940241 130.225016) (width 0.155) (layer "B.Cu") (net 105))
  (segment (start 111.069605 131.767567) (end 111.08 131.675315) (width 0.155) (layer "B.Cu") (net 105))
  (segment (start 110.2 130.350109) (end 110.2 131.675315) (width 0.155) (layer "B.Cu") (net 105))
  (segment (start 110.2 131.675315) (end 110.210394 131.767567) (width 0.155) (layer "B.Cu") (net 105))
  (segment (start 106.310447 115.056091) (end 106.261055 115.134697) (width 0.155) (layer "B.Cu") (net 105))
  (segment (start 109.645302 132.048835) (end 109.723908 131.999443) (width 0.155) (layer "B.Cu") (net 105))
  (segment (start 111.24 130.190109) (end 111.275603 130.194121) (width 0.155) (layer "B.Cu") (net 105))
  (segment (start 111.170578 130.205954) (end 111.204396 130.194121) (width 0.155) (layer "B.Cu") (net 105))
  (segment (start 108.239759 115.814906) (end 108.265094 115.840241) (width 0.155) (layer "B.Cu") (net 105))
  (segment (start 110.210394 131.767567) (end 110.241055 131.855193) (width 0.155) (layer "B.Cu") (net 105))
  (segment (start 110.04 130.190109) (end 110.075603 130.194121) (width 0.155) (layer "B.Cu") (net 105))
  (segment (start 108.875603 131.144011) (end 108.909421 131.155844) (width 0.155) (layer "B.Cu") (net 105))
  (segment (start 109.869605 131.767567) (end 109.88 131.675315) (width 0.155) (layer "B.Cu") (net 105))
  (segment (start 109.010394 131.767567) (end 109.041055 131.855193) (width 0.155) (layer "B.Cu") (net 105))
  (segment (start 111.722323 131.129606) (end 111.814575 131.14) (width 0.155) (layer "B.Cu") (net 105))
  (segment (start 107.355988 114.775603) (end 107.344155 114.809421) (width 0.155) (layer "B.Cu") (net 105))
  (segment (start 109.884011 130.314506) (end 109.895844 130.280688) (width 0.155) (layer "B.Cu") (net 105))
  (segment (start 110.075603 130.194121) (end 110.109421 130.205954) (width 0.155) (layer "B.Cu") (net 105))
  (segment (start 110.845302 132.048835) (end 110.923908 131.999443) (width 0.155) (layer "B.Cu") (net 105))
  (segment (start 108.284156 116.009421) (end 108.265094 116.039758) (width 0.155) (layer "B.Cu") (net 105))
  (segment (start 106.230394 115.457676) (end 106.261055 115.545302) (width 0.155) (layer "B.Cu") (net 105))
  (segment (start 109.970578 130.205954) (end 110.004396 130.194121) (width 0.155) (layer "B.Cu") (net 105))
  (segment (start 108.175604 116.095988) (end 108.14 116.1) (width 0.155) (layer "B.Cu") (net 105))
  (segment (start 109 131.675315) (end 109.010394 131.767567) (width 0.155) (layer "B.Cu") (net 105))
  (segment (start 109 131.3) (end 109 131.675315) (width 0.155) (layer "B.Cu") (net 105))
  (segment (start 109.789552 131.933799) (end 109.838944 131.855193) (width 0.155) (layer "B.Cu") (net 105))
  (segment (start 111.4 130.725425) (end 111.410394 130.817677) (width 0.155) (layer "B.Cu") (net 105))
  (segment (start 108.984155 131.230578) (end 108.995988 131.264396) (width 0.155) (layer "B.Cu") (net 105))
  (via (at 127.65 103.6) (size 0.6) (drill 0.25) (layers "F.Cu" "B.Cu") (net 106))
  (via (at 127.65 104.3) (size 0.6) (drill 0.25) (layers "F.Cu" "B.Cu") (net 106))
  (via (at 126.85 103.6) (size 0.6) (drill 0.25) (layers "F.Cu" "B.Cu") (net 106))
  (via (at 126.85 104.3) (size 0.6) (drill 0.25) (layers "F.Cu" "B.Cu") (net 106))
  (via (at 98.4 91) (size 0.6) (drill 0.25) (layers "F.Cu" "B.Cu") (net 106))
  (via (at 99.2 91.7) (size 0.6) (drill 0.25) (layers "F.Cu" "B.Cu") (net 106))
  (via (at 98.4 91.7) (size 0.6) (drill 0.25) (layers "F.Cu" "B.Cu") (net 106))
  (via (at 99.2 91) (size 0.6) (drill 0.25) (layers "F.Cu" "B.Cu") (net 106))
  (segment (start 107.5 104) (end 99.2 95.7) (width 1) (layer "In3.Cu") (net 106))
  (segment (start 99.2 95.7) (end 99.2 91.7) (width 1) (layer "In3.Cu") (net 106))
  (segment (start 127 104) (end 107.5 104) (width 1) (layer "In3.Cu") (net 106))
  (segment (start 81.5 143.5) (end 81.4 143.6) (width 0.15) (layer "F.Cu") (net 107))
  (segment (start 81.5 142.4) (end 81.5 143.5) (width 0.15) (layer "F.Cu") (net 107))
  (segment (start 88.3 138.205) (end 88.3 138.89) (width 0.25) (layer "F.Cu") (net 107))
  (segment (start 80.965 141.865) (end 81.5 142.4) (width 0.15) (layer "F.Cu") (net 107))
  (segment (start 88.3 138.89) (end 88.8 139.39) (width 0.25) (layer "F.Cu") (net 107))
  (segment (start 80.965 139.3) (end 80.965 141.865) (width 0.15) (layer "F.Cu") (net 107))
  (segment (start 80.375 139.3) (end 80.965 139.3) (width 0.15) (layer "F.Cu") (net 107))
  (segment (start 80.05 137.01) (end 80.05 138.975) (width 0.15) (layer "F.Cu") (net 107))
  (segment (start 88.81 139.39) (end 89.3 138.9) (width 0.2) (layer "F.Cu") (net 107))
  (segment (start 80.05 138.975) (end 80.375 139.3) (width 0.15) (layer "F.Cu") (net 107))
  (segment (start 89.3 138.9) (end 89.3 138.8) (width 0.2) (layer "F.Cu") (net 107))
  (via (at 85.7 141.8) (size 0.6) (drill 0.25) (layers "F.Cu" "B.Cu") (net 107))
  (via (at 89.8 141.8) (size 0.6) (drill 0.25) (layers "F.Cu" "B.Cu") (net 107))
  (via (at 89.2 141.4) (size 0.6) (drill 0.25) (layers "F.Cu" "B.Cu") (net 107))
  (via (at 89.2 142.2) (size 0.6) (drill 0.25) (layers "F.Cu" "B.Cu") (net 107))
  (via (at 89.55 145.95) (size 0.6) (drill 0.25) (layers "F.Cu" "B.Cu") (net 107))
  (via (at 81.4 143.6) (size 0.6) (drill 0.25) (layers "F.Cu" "B.Cu") (net 107))
  (via (at 85.45 145.95) (size 0.6) (drill 0.25) (layers "F.Cu" "B.Cu") (net 107))
  (via (at 89.3 138.8) (size 0.6) (drill 0.25) (layers "F.Cu" "B.Cu") (net 107))
  (via (at 86.3 141.4) (size 0.6) (drill 0.25) (layers "F.Cu" "B.Cu") (net 107))
  (via (at 86.05 146.35) (size 0.6) (drill 0.25) (layers "F.Cu" "B.Cu") (net 107))
  (via (at 86.3 142.2) (size 0.6) (drill 0.25) (layers "F.Cu" "B.Cu") (net 107))
  (via (at 86.05 145.55) (size 0.6) (drill 0.25) (layers "F.Cu" "B.Cu") (net 107))
  (via (at 88.95 146.35) (size 0.6) (drill 0.25) (layers "F.Cu" "B.Cu") (net 107))
  (via (at 88.95 145.55) (size 0.6) (drill 0.25) (layers "F.Cu" "B.Cu") (net 107))
  (segment (start 90.0508 138.8) (end 91 137.8508) (width 0.15) (layer "B.Cu") (net 107))
  (segment (start 88.875001 140.823999) (end 88.875001 141.075001) (width 0.3) (layer "B.Cu") (net 107))
  (segment (start 82.68 143.12) (end 82.68 142.435) (width 0.15) (layer "B.Cu") (net 107))
  (segment (start 81.4 143.6) (end 82.2 143.6) (width 0.15) (layer "B.Cu") (net 107))
  (segment (start 82.2 143.6) (end 82.68 143.12) (width 0.15) (layer "B.Cu") (net 107))
  (segment (start 88.875001 141.075001) (end 89.2 141.4) (width 0.3) (layer "B.Cu") (net 107))
  (segment (start 88.749999 140.698997) (end 88.875001 140.823999) (width 0.3) (layer "B.Cu") (net 107))
  (segment (start 89.3 138.8) (end 90.0508 138.8) (width 0.15) (layer "B.Cu") (net 107))
  (segment (start 89.3 138.8) (end 88.749999 139.350001) (width 0.3) (layer "B.Cu") (net 107))
  (segment (start 88.749999 139.350001) (end 88.749999 140.698997) (width 0.3) (layer "B.Cu") (net 107))
  (segment (start 141.69254 96.551772) (end 141.654629 96.5475) (width 0.17) (layer "F.Cu") (net 108))
  (segment (start 141.477129 96.892263) (end 141.466135 96.989834) (width 0.17) (layer "F.Cu") (net 108))
  (segment (start 141.820728 96.67996) (end 141.808127 96.64395) (width 0.17) (layer "F.Cu") (net 108))
  (segment (start 143.225 95.366757) (end 143.219922 95.321696) (width 0.17) (layer "F.Cu") (net 108))
  (segment (start 143.18082 95.2405) (end 143.148756 95.208436) (width 0.17) (layer "F.Cu") (net 108))
  (segment (start 140.730359 97.28732) (end 140.647221 97.235081) (width 0.17) (layer "F.Cu") (net 108))
  (segment (start 142.840053 95.278895) (end 142.825077 95.321696) (width 0.17) (layer "F.Cu") (net 108))
  (segment (start 142.776576 97.082513) (end 142.724337 97.165651) (width 0.17) (layer "F.Cu") (net 108))
  (segment (start 140.444959 96.611647) (end 140.417982 96.58467) (width 0.17) (layer "F.Cu") (net 108))
  (segment (start 143.225 96.078747) (end 143.225 95.366757) (width 0.17) (layer "F.Cu") (net 108))
  (segment (start 140.417982 96.58467) (end 140.385679 96.564373) (width 0.17) (layer "F.Cu") (net 108))
  (segment (start 141.990092 97.235081) (end 141.920662 97.165651) (width 0.17) (layer "F.Cu") (net 108))
  (segment (start 144.3625 96.5475) (end 143.693752 96.5475) (width 0.17) (layer "F.Cu") (net 108))
  (segment (start 143.490368 96.501078) (end 143.40149 96.445232) (width 0.17) (layer "F.Cu") (net 108))
  (segment (start 140.465256 96.64395) (end 140.444959 96.611647) (width 0.17) (layer "F.Cu") (net 108))
  (segment (start 131.8525 92.161098) (end 131.8525 90.852656) (width 0.17) (layer "F.Cu") (net 108))
  (segment (start 143.219922 95.321696) (end 143.204946 95.278895) (width 0.17) (layer "F.Cu") (net 108))
  (segment (start 142.864179 95.2405) (end 142.840053 95.278895) (width 0.17) (layer "F.Cu") (net 108))
  (segment (start 142.82 96.892263) (end 142.809006 96.989834) (width 0.17) (layer "F.Cu") (net 108))
  (segment (start 142.825077 95.321696) (end 142.82 95.366757) (width 0.17) (layer "F.Cu") (net 108))
  (segment (start 140.349669 96.551772) (end 140.311758 96.5475) (width 0.17) (layer "F.Cu") (net 108))
  (segment (start 142.47909 97.31975) (end 142.381519 97.330743) (width 0.17) (layer "F.Cu") (net 108))
  (segment (start 142.809006 96.989834) (end 142.776576 97.082513) (width 0.17) (layer "F.Cu") (net 108))
  (segment (start 140.311758 96.5475) (end 136.238902 96.5475) (width 0.17) (layer "F.Cu") (net 108))
  (segment (start 131.8525 90.852656) (end 131.749999 90.750155) (width 0.17) (layer "F.Cu") (net 108))
  (segment (start 140.823038 97.31975) (end 140.730359 97.28732) (width 0.17) (layer "F.Cu") (net 108))
  (segment (start 141.868423 97.082513) (end 141.835993 96.989834) (width 0.17) (layer "F.Cu") (net 108))
  (segment (start 141.573578 96.564373) (end 141.541275 96.58467) (width 0.17) (layer "F.Cu") (net 108))
  (segment (start 143.236752 96.183054) (end 143.225 96.078747) (width 0.17) (layer "F.Cu") (net 108))
  (segment (start 142.165909 97.31975) (end 142.07323 97.28732) (width 0.17) (layer "F.Cu") (net 108))
  (segment (start 141.4814 96.67996) (end 141.477129 96.717871) (width 0.17) (layer "F.Cu") (net 108))
  (segment (start 142.381519 97.330743) (end 142.26348 97.330743) (width 0.17) (layer "F.Cu") (net 108))
  (segment (start 141.541275 96.58467) (end 141.514298 96.611647) (width 0.17) (layer "F.Cu") (net 108))
  (segment (start 140.482129 96.717871) (end 140.477857 96.67996) (width 0.17) (layer "F.Cu") (net 108))
  (segment (start 143.148756 95.208436) (end 143.110361 95.18431) (width 0.17) (layer "F.Cu") (net 108))
  (segment (start 141.381466 97.165651) (end 141.312036 97.235081) (width 0.17) (layer "F.Cu") (net 108))
  (segment (start 140.577791 97.165651) (end 140.525552 97.082513) (width 0.17) (layer "F.Cu") (net 108))
  (segment (start 142.82 95.366757) (end 142.82 96.892263) (width 0.17) (layer "F.Cu") (net 108))
  (segment (start 141.312036 97.235081) (end 141.228898 97.28732) (width 0.17) (layer "F.Cu") (net 108))
  (segment (start 141.433705 97.082513) (end 141.381466 97.165651) (width 0.17) (layer "F.Cu") (net 108))
  (segment (start 141.825 96.717871) (end 141.820728 96.67996) (width 0.17) (layer "F.Cu") (net 108))
  (segment (start 141.609588 96.551772) (end 141.573578 96.564373) (width 0.17) (layer "F.Cu") (net 108))
  (segment (start 141.6475 96.5475) (end 141.609588 96.551772) (width 0.17) (layer "F.Cu") (net 108))
  (segment (start 141.136219 97.31975) (end 141.038648 97.330743) (width 0.17) (layer "F.Cu") (net 108))
  (segment (start 143.06756 95.169334) (end 143.0225 95.164257) (width 0.17) (layer "F.Cu") (net 108))
  (segment (start 140.525552 97.082513) (end 140.493122 96.989834) (width 0.17) (layer "F.Cu") (net 108))
  (segment (start 141.466135 96.989834) (end 141.433705 97.082513) (width 0.17) (layer "F.Cu") (net 108))
  (segment (start 143.0225 95.164257) (end 142.977439 95.169334) (width 0.17) (layer "F.Cu") (net 108))
  (segment (start 141.78783 96.611647) (end 141.760853 96.58467) (width 0.17) (layer "F.Cu") (net 108))
  (segment (start 144.715 96.9) (end 144.3625 96.5475) (width 0.17) (layer "F.Cu") (net 108))
  (segment (start 142.26348 97.330743) (end 142.165909 97.31975) (width 0.17) (layer "F.Cu") (net 108))
  (segment (start 141.920662 97.165651) (end 141.868423 97.082513) (width 0.17) (layer "F.Cu") (net 108))
  (segment (start 143.589445 96.535747) (end 143.490368 96.501078) (width 0.17) (layer "F.Cu") (net 108))
  (segment (start 142.724337 97.165651) (end 142.654907 97.235081) (width 0.17) (layer "F.Cu") (net 108))
  (segment (start 142.07323 97.28732) (end 141.990092 97.235081) (width 0.17) (layer "F.Cu") (net 108))
  (segment (start 136.238902 96.5475) (end 131.8525 92.161098) (width 0.17) (layer "F.Cu") (net 108))
  (segment (start 141.72855 96.564373) (end 141.69254 96.551772) (width 0.17) (layer "F.Cu") (net 108))
  (segment (start 140.482129 96.892263) (end 140.482129 96.717871) (width 0.17) (layer "F.Cu") (net 108))
  (segment (start 140.385679 96.564373) (end 140.349669 96.551772) (width 0.17) (layer "F.Cu") (net 108))
  (segment (start 141.228898 97.28732) (end 141.136219 97.31975) (width 0.17) (layer "F.Cu") (net 108))
  (segment (start 142.571769 97.28732) (end 142.47909 97.31975) (width 0.17) (layer "F.Cu") (net 108))
  (segment (start 141.808127 96.64395) (end 141.78783 96.611647) (width 0.17) (layer "F.Cu") (net 108))
  (segment (start 140.493122 96.989834) (end 140.482129 96.892263) (width 0.17) (layer "F.Cu") (net 108))
  (segment (start 141.477129 96.717871) (end 141.477129 96.892263) (width 0.17) (layer "F.Cu") (net 108))
  (segment (start 140.647221 97.235081) (end 140.577791 97.165651) (width 0.17) (layer "F.Cu") (net 108))
  (segment (start 140.477857 96.67996) (end 140.465256 96.64395) (width 0.17) (layer "F.Cu") (net 108))
  (segment (start 141.654629 96.5475) (end 141.6475 96.5475) (width 0.17) (layer "F.Cu") (net 108))
  (segment (start 141.494001 96.64395) (end 141.4814 96.67996) (width 0.17) (layer "F.Cu") (net 108))
  (segment (start 142.934638 95.18431) (end 142.896243 95.208436) (width 0.17) (layer "F.Cu") (net 108))
  (segment (start 141.835993 96.989834) (end 141.825 96.892263) (width 0.17) (layer "F.Cu") (net 108))
  (segment (start 142.896243 95.208436) (end 142.864179 95.2405) (width 0.17) (layer "F.Cu") (net 108))
  (segment (start 143.327267 96.371009) (end 143.271421 96.282131) (width 0.17) (layer "F.Cu") (net 108))
  (segment (start 141.514298 96.611647) (end 141.494001 96.64395) (width 0.17) (layer "F.Cu") (net 108))
  (segment (start 140.920609 97.330743) (end 140.823038 97.31975) (width 0.17) (layer "F.Cu") (net 108))
  (segment (start 143.693752 96.5475) (end 143.589445 96.535747) (width 0.17) (layer "F.Cu") (net 108))
  (segment (start 142.977439 95.169334) (end 142.934638 95.18431) (width 0.17) (layer "F.Cu") (net 108))
  (segment (start 143.204946 95.278895) (end 143.18082 95.2405) (width 0.17) (layer "F.Cu") (net 108))
  (segment (start 143.40149 96.445232) (end 143.327267 96.371009) (width 0.17) (layer "F.Cu") (net 108))
  (segment (start 143.110361 95.18431) (end 143.06756 95.169334) (width 0.17) (layer "F.Cu") (net 108))
  (segment (start 142.654907 97.235081) (end 142.571769 97.28732) (width 0.17) (layer "F.Cu") (net 108))
  (segment (start 141.825 96.892263) (end 141.825 96.717871) (width 0.17) (layer "F.Cu") (net 108))
  (segment (start 131.749999 90.750155) (end 131.749999 89.550004) (width 0.17) (layer "F.Cu") (net 108))
  (segment (start 141.038648 97.330743) (end 140.920609 97.330743) (width 0.17) (layer "F.Cu") (net 108))
  (segment (start 141.760853 96.58467) (end 141.72855 96.564373) (width 0.17) (layer "F.Cu") (net 108))
  (segment (start 143.271421 96.282131) (end 143.236752 96.183054) (width 0.17) (layer "F.Cu") (net 108))
  (segment (start 146.761098 96.5475) (end 146.0375 96.5475) (width 0.17) (layer "F.Cu") (net 109))
  (segment (start 147.6625 95.3) (end 147.4475 95.515) (width 0.17) (layer "F.Cu") (net 109))
  (segment (start 146.0375 96.5475) (end 145.685 96.9) (width 0.17) (layer "F.Cu") (net 109))
  (segment (start 147.4475 95.861098) (end 146.761098 96.5475) (width 0.17) (layer "F.Cu") (net 109))
  (segment (start 147.4475 95.515) (end 147.4475 95.861098) (width 0.17) (layer "F.Cu") (net 109))
  (via (at 147.6625 95.3) (size 0.6) (drill 0.25) (layers "F.Cu" "B.Cu") (net 109))
  (segment (start 148.111098 97.7025) (end 147.4475 97.038902) (width 0.17) (layer "B.Cu") (net 109))
  (segment (start 149.232489 97.6) (end 149.129989 97.7025) (width 0.17) (layer "B.Cu") (net 109))
  (segment (start 149.129989 97.7025) (end 148.111098 97.7025) (width 0.17) (layer "B.Cu") (net 109))
  (segment (start 150.39499 97.6) (end 149.232489 97.6) (width 0.17) (layer "B.Cu") (net 109))
  (segment (start 147.4475 97.038902) (end 147.4475 95.515) (width 0.17) (layer "B.Cu") (net 109))
  (segment (start 147.4475 95.515) (end 147.6625 95.3) (width 0.17) (layer "B.Cu") (net 109))
  (segment (start 141.144959 96.971597) (end 141.165256 96.939294) (width 0.17) (layer "F.Cu") (net 110))
  (segment (start 142.124271 96.903284) (end 142.136872 96.939294) (width 0.17) (layer "F.Cu") (net 110))
  (segment (start 134.386408 94.18729) (end 134.386408 94.225358) (width 0.17) (layer "F.Cu") (net 110))
  (segment (start 143.52 96.05) (end 143.525077 96.09506) (width 0.17) (layer "F.Cu") (net 110))
  (segment (start 140.841275 96.998574) (end 140.873578 97.018871) (width 0.17) (layer "F.Cu") (net 110))
  (segment (start 143.051247 94.869257) (end 143.155554 94.881009) (width 0.17) (layer "F.Cu") (net 110))
  (segment (start 141.049669 97.031472) (end 141.085679 97.018871) (width 0.17) (layer "F.Cu") (net 110))
  (segment (start 142.520728 96.903284) (end 142.525 96.865372) (width 0.17) (layer "F.Cu") (net 110))
  (segment (start 134.441459 93.785875) (end 134.471222 93.80961) (width 0.17) (layer "F.Cu") (net 110))
  (segment (start 143.254631 94.915678) (end 143.343509 94.971524) (width 0.17) (layer "F.Cu") (net 110))
  (segment (start 132.250001 90.750155) (end 132.1475 90.852656) (width 0.17) (layer "F.Cu") (net 110))
  (segment (start 142.12 96.690981) (end 142.12 96.865372) (width 0.17) (layer "F.Cu") (net 110))
  (segment (start 132.250001 89.550004) (end 132.250001 90.750155) (width 0.17) (layer "F.Cu") (net 110))
  (segment (start 134.511474 93.87367) (end 134.519944 93.910784) (width 0.17) (layer "F.Cu") (net 110))
  (segment (start 134.40716 93.769357) (end 134.441459 93.785875) (width 0.17) (layer "F.Cu") (net 110))
  (segment (start 134.194715 93.845701) (end 134.230804 93.809609) (width 0.17) (layer "F.Cu") (net 110))
  (segment (start 142.184146 96.998574) (end 142.216449 97.018871) (width 0.17) (layer "F.Cu") (net 110))
  (segment (start 134.494955 94.020262) (end 134.471222 94.050026) (width 0.17) (layer "F.Cu") (net 110))
  (segment (start 141.193122 96.59341) (end 141.225552 96.500731) (width 0.17) (layer "F.Cu") (net 110))
  (segment (start 141.085679 97.018871) (end 141.117982 96.998574) (width 0.17) (layer "F.Cu") (net 110))
  (segment (start 134.394879 94.150177) (end 134.386408 94.18729) (width 0.17) (layer "F.Cu") (net 110))
  (segment (start 142.252459 97.031472) (end 142.290371 97.035743) (width 0.17) (layer "F.Cu") (net 110))
  (segment (start 134.130653 93.885952) (end 134.164951 93.869434) (width 0.17) (layer "F.Cu") (net 110))
  (segment (start 134.471222 94.050026) (end 134.43513 94.086115) (width 0.17) (layer "F.Cu") (net 110))
  (segment (start 141.954907 96.348163) (end 142.024337 96.417593) (width 0.17) (layer "F.Cu") (net 110))
  (segment (start 132.1475 92.038902) (end 133.954299 93.845701) (width 0.17) (layer "F.Cu") (net 110))
  (segment (start 134.43513 94.086115) (end 134.411395 94.115878) (width 0.17) (layer "F.Cu") (net 110))
  (segment (start 140.814298 96.971597) (end 140.841275 96.998574) (width 0.17) (layer "F.Cu") (net 110))
  (segment (start 134.093541 93.894423) (end 134.130653 93.885952) (width 0.17) (layer "F.Cu") (net 110))
  (segment (start 134.519944 93.910784) (end 134.519944 93.948852) (width 0.17) (layer "F.Cu") (net 110))
  (segment (start 141.165256 96.939294) (end 141.177857 96.903284) (width 0.17) (layer "F.Cu") (net 110))
  (segment (start 134.164951 93.869434) (end 134.194715 93.845701) (width 0.17) (layer "F.Cu") (net 110))
  (segment (start 143.508247 95.233702) (end 143.52 95.338009) (width 0.17) (layer "F.Cu") (net 110))
  (segment (start 141.523038 96.263494) (end 141.620609 96.2525) (width 0.17) (layer "F.Cu") (net 110))
  (segment (start 141.177857 96.903284) (end 141.182129 96.865372) (width 0.17) (layer "F.Cu") (net 110))
  (segment (start 134.411395 94.115878) (end 134.394879 94.150177) (width 0.17) (layer "F.Cu") (net 110))
  (segment (start 141.77909 96.263494) (end 141.871769 96.295924) (width 0.17) (layer "F.Cu") (net 110))
  (segment (start 132.1475 90.852656) (end 132.1475 92.038902) (width 0.17) (layer "F.Cu") (net 110))
  (segment (start 142.525 95.338009) (end 142.536752 95.233702) (width 0.17) (layer "F.Cu") (net 110))
  (segment (start 142.889445 94.881009) (end 142.993752 94.869257) (width 0.17) (layer "F.Cu") (net 110))
  (segment (start 142.076576 96.500731) (end 142.109006 96.59341) (width 0.17) (layer "F.Cu") (net 110))
  (segment (start 142.525 96.865372) (end 142.525 95.338009) (width 0.17) (layer "F.Cu") (net 110))
  (segment (start 134.511473 93.985964) (end 134.494955 94.020262) (width 0.17) (layer "F.Cu") (net 110))
  (segment (start 144.3625 96.2525) (end 144.715 95.9) (width 0.17) (layer "F.Cu") (net 110))
  (segment (start 141.225552 96.500731) (end 141.277791 96.417593) (width 0.17) (layer "F.Cu") (net 110))
  (segment (start 140.436219 96.263494) (end 140.528898 96.295924) (width 0.17) (layer "F.Cu") (net 110))
  (segment (start 140.681466 96.417593) (end 140.733705 96.500731) (width 0.17) (layer "F.Cu") (net 110))
  (segment (start 142.70149 94.971524) (end 142.790368 94.915678) (width 0.17) (layer "F.Cu") (net 110))
  (segment (start 140.777129 96.865372) (end 140.7814 96.903284) (width 0.17) (layer "F.Cu") (net 110))
  (segment (start 142.157169 96.971597) (end 142.184146 96.998574) (width 0.17) (layer "F.Cu") (net 110))
  (segment (start 143.7225 96.2525) (end 144.3625 96.2525) (width 0.17) (layer "F.Cu") (net 110))
  (segment (start 141.182129 96.865372) (end 141.182129 96.690981) (width 0.17) (layer "F.Cu") (net 110))
  (segment (start 142.508127 96.939294) (end 142.520728 96.903284) (width 0.17) (layer "F.Cu") (net 110))
  (segment (start 134.055473 93.894423) (end 134.093541 93.894423) (width 0.17) (layer "F.Cu") (net 110))
  (segment (start 133.954299 93.845701) (end 133.984061 93.869435) (width 0.17) (layer "F.Cu") (net 110))
  (segment (start 134.331979 93.760887) (end 134.370047 93.760887) (width 0.17) (layer "F.Cu") (net 110))
  (segment (start 136.361098 96.2525) (end 140.338648 96.2525) (width 0.17) (layer "F.Cu") (net 110))
  (segment (start 141.620609 96.2525) (end 141.681519 96.2525) (width 0.17) (layer "F.Cu") (net 110))
  (segment (start 140.612036 96.348163) (end 140.681466 96.417593) (width 0.17) (layer "F.Cu") (net 110))
  (segment (start 134.471222 93.80961) (end 134.494956 93.839372) (width 0.17) (layer "F.Cu") (net 110))
  (segment (start 143.677439 96.247422) (end 143.7225 96.2525) (width 0.17) (layer "F.Cu") (net 110))
  (segment (start 143.540053 96.137861) (end 143.564179 96.176256) (width 0.17) (layer "F.Cu") (net 110))
  (segment (start 134.260567 93.785874) (end 134.294866 93.769358) (width 0.17) (layer "F.Cu") (net 110))
  (segment (start 142.460853 96.998574) (end 142.48783 96.971597) (width 0.17) (layer "F.Cu") (net 110))
  (segment (start 134.435131 94.326533) (end 136.361098 96.2525) (width 0.17) (layer "F.Cu") (net 110))
  (segment (start 134.230804 93.809609) (end 134.260567 93.785874) (width 0.17) (layer "F.Cu") (net 110))
  (segment (start 142.48783 96.971597) (end 142.508127 96.939294) (width 0.17) (layer "F.Cu") (net 110))
  (segment (start 140.733705 96.500731) (end 140.766135 96.59341) (width 0.17) (layer "F.Cu") (net 110))
  (segment (start 134.394878 94.262471) (end 134.411396 94.29677) (width 0.17) (layer "F.Cu") (net 110))
  (segment (start 142.12 96.865372) (end 142.124271 96.903284) (width 0.17) (layer "F.Cu") (net 110))
  (segment (start 140.909588 97.031472) (end 140.9475 97.035743) (width 0.17) (layer "F.Cu") (net 110))
  (segment (start 142.216449 97.018871) (end 142.252459 97.031472) (width 0.17) (layer "F.Cu") (net 110))
  (segment (start 140.528898 96.295924) (end 140.612036 96.348163) (width 0.17) (layer "F.Cu") (net 110))
  (segment (start 134.519944 93.948852) (end 134.511473 93.985964) (width 0.17) (layer "F.Cu") (net 110))
  (segment (start 141.011758 97.035743) (end 141.049669 97.031472) (width 0.17) (layer "F.Cu") (net 110))
  (segment (start 142.627267 95.045747) (end 142.70149 94.971524) (width 0.17) (layer "F.Cu") (net 110))
  (segment (start 134.294866 93.769358) (end 134.331979 93.760887) (width 0.17) (layer "F.Cu") (net 110))
  (segment (start 143.343509 94.971524) (end 143.417732 95.045747) (width 0.17) (layer "F.Cu") (net 110))
  (segment (start 141.182129 96.690981) (end 141.193122 96.59341) (width 0.17) (layer "F.Cu") (net 110))
  (segment (start 140.873578 97.018871) (end 140.909588 97.031472) (width 0.17) (layer "F.Cu") (net 110))
  (segment (start 142.354629 97.035743) (end 142.39254 97.031472) (width 0.17) (layer "F.Cu") (net 110))
  (segment (start 143.52 95.338009) (end 143.52 96.05) (width 0.17) (layer "F.Cu") (net 110))
  (segment (start 141.117982 96.998574) (end 141.144959 96.971597) (width 0.17) (layer "F.Cu") (net 110))
  (segment (start 140.777129 96.690981) (end 140.777129 96.865372) (width 0.17) (layer "F.Cu") (net 110))
  (segment (start 134.411396 94.29677) (end 134.435131 94.326533) (width 0.17) (layer "F.Cu") (net 110))
  (segment (start 143.473578 95.134625) (end 143.508247 95.233702) (width 0.17) (layer "F.Cu") (net 110))
  (segment (start 141.277791 96.417593) (end 141.347221 96.348163) (width 0.17) (layer "F.Cu") (net 110))
  (segment (start 140.338648 96.2525) (end 140.436219 96.263494) (width 0.17) (layer "F.Cu") (net 110))
  (segment (start 143.525077 96.09506) (end 143.540053 96.137861) (width 0.17) (layer "F.Cu") (net 110))
  (segment (start 140.7814 96.903284) (end 140.794001 96.939294) (width 0.17) (layer "F.Cu") (net 110))
  (segment (start 134.370047 93.760887) (end 134.40716 93.769357) (width 0.17) (layer "F.Cu") (net 110))
  (segment (start 142.109006 96.59341) (end 142.12 96.690981) (width 0.17) (layer "F.Cu") (net 110))
  (segment (start 140.766135 96.59341) (end 140.777129 96.690981) (width 0.17) (layer "F.Cu") (net 110))
  (segment (start 142.290371 97.035743) (end 142.354629 97.035743) (width 0.17) (layer "F.Cu") (net 110))
  (segment (start 142.42855 97.018871) (end 142.460853 96.998574) (width 0.17) (layer "F.Cu") (net 110))
  (segment (start 142.39254 97.031472) (end 142.42855 97.018871) (width 0.17) (layer "F.Cu") (net 110))
  (segment (start 142.790368 94.915678) (end 142.889445 94.881009) (width 0.17) (layer "F.Cu") (net 110))
  (segment (start 134.386408 94.225358) (end 134.394878 94.262471) (width 0.17) (layer "F.Cu") (net 110))
  (segment (start 140.794001 96.939294) (end 140.814298 96.971597) (width 0.17) (layer "F.Cu") (net 110))
  (segment (start 140.9475 97.035743) (end 141.011758 97.035743) (width 0.17) (layer "F.Cu") (net 110))
  (segment (start 143.564179 96.176256) (end 143.596243 96.20832) (width 0.17) (layer "F.Cu") (net 110))
  (segment (start 141.681519 96.2525) (end 141.77909 96.263494) (width 0.17) (layer "F.Cu") (net 110))
  (segment (start 143.155554 94.881009) (end 143.254631 94.915678) (width 0.17) (layer "F.Cu") (net 110))
  (segment (start 142.993752 94.869257) (end 143.051247 94.869257) (width 0.17) (layer "F.Cu") (net 110))
  (segment (start 141.430359 96.295924) (end 141.523038 96.263494) (width 0.17) (layer "F.Cu") (net 110))
  (segment (start 134.494956 93.839372) (end 134.511474 93.87367) (width 0.17) (layer "F.Cu") (net 110))
  (segment (start 143.596243 96.20832) (end 143.634638 96.232446) (width 0.17) (layer "F.Cu") (net 110))
  (segment (start 142.024337 96.417593) (end 142.076576 96.500731) (width 0.17) (layer "F.Cu") (net 110))
  (segment (start 143.634638 96.232446) (end 143.677439 96.247422) (width 0.17) (layer "F.Cu") (net 110))
  (segment (start 143.417732 95.045747) (end 143.473578 95.134625) (width 0.17) (layer "F.Cu") (net 110))
  (segment (start 142.536752 95.233702) (end 142.571421 95.134625) (width 0.17) (layer "F.Cu") (net 110))
  (segment (start 141.871769 96.295924) (end 141.954907 96.348163) (width 0.17) (layer "F.Cu") (net 110))
  (segment (start 134.018359 93.885953) (end 134.055473 93.894423) (width 0.17) (layer "F.Cu") (net 110))
  (segment (start 141.347221 96.348163) (end 141.430359 96.295924) (width 0.17) (layer "F.Cu") (net 110))
  (segment (start 142.136872 96.939294) (end 142.157169 96.971597) (width 0.17) (layer "F.Cu") (net 110))
  (segment (start 133.984061 93.869435) (end 134.018359 93.885953) (width 0.17) (layer "F.Cu") (net 110))
  (segment (start 142.571421 95.134625) (end 142.627267 95.045747) (width 0.17) (layer "F.Cu") (net 110))
  (segment (start 147.1525 95.515) (end 147.1525 95.738902) (width 0.17) (layer "F.Cu") (net 111))
  (segment (start 146.0375 96.2525) (end 145.685 95.9) (width 0.17) (layer "F.Cu") (net 111))
  (segment (start 146.638902 96.2525) (end 146.0375 96.2525) (width 0.17) (layer "F.Cu") (net 111))
  (segment (start 146.9375 95.3) (end 147.1525 95.515) (width 0.17) (layer "F.Cu") (net 111))
  (segment (start 147.1525 95.738902) (end 146.638902 96.2525) (width 0.17) (layer "F.Cu") (net 111))
  (via (at 146.9375 95.3) (size 0.6) (drill 0.25) (layers "F.Cu" "B.Cu") (net 111))
  (segment (start 147.1525 97.161098) (end 147.1525 95.515) (width 0.17) (layer "B.Cu") (net 111))
  (segment (start 147.988902 97.9975) (end 147.1525 97.161098) (width 0.17) (layer "B.Cu") (net 111))
  (segment (start 147.1525 95.515) (end 146.9375 95.3) (width 0.17) (layer "B.Cu") (net 111))
  (segment (start 149.232489 98.1) (end 149.129989 97.9975) (width 0.17) (layer "B.Cu") (net 111))
  (segment (start 149.129989 97.9975) (end 147.988902 97.9975) (width 0.17) (layer "B.Cu") (net 111))
  (segment (start 150.39499 98.1) (end 149.232489 98.1) (width 0.17) (layer "B.Cu") (net 111))
  (segment (start 122.25 92.15) (end 121.9 92.5) (width 0.182) (layer "F.Cu") (net 112))
  (segment (start 122.25 89.55) (end 122.25 92.15) (width 0.182) (layer "F.Cu") (net 112))
  (segment (start 121.9 93.315) (end 121.9 92.7) (width 0.182) (layer "F.Cu") (net 112))
  (segment (start 121.9 92.5) (end 121.9 92.7) (width 0.182) (layer "F.Cu") (net 112))
  (via (at 121.9 92.7) (size 0.6) (drill 0.25) (layers "F.Cu" "B.Cu") (net 112))
  (segment (start 121.9 92.7) (end 121.9 93.315) (width 0.182) (layer "B.Cu") (net 112))
  (segment (start 120.75 89.55) (end 120.75 93.165) (width 0.182) (layer "F.Cu") (net 113))
  (segment (start 120.25 92.965) (end 119.9 93.315) (width 0.182) (layer "F.Cu") (net 114))
  (segment (start 120.25 89.55) (end 120.25 92.965) (width 0.182) (layer "F.Cu") (net 114))
  (segment (start 122.75 89.55) (end 122.75 93.165) (width 0.182) (layer "F.Cu") (net 115))
  (segment (start 123.25 89.55) (end 123.25 91.75) (width 0.182) (layer "F.Cu") (net 116))
  (segment (start 123.25 91.75) (end 123.3 91.8) (width 0.182) (layer "F.Cu") (net 116))
  (via (at 123.3 91.8) (size 0.6) (drill 0.25) (layers "F.Cu" "B.Cu") (net 116))
  (segment (start 120.799999 91.500001) (end 119.9 92.4) (width 0.182) (layer "B.Cu") (net 116))
  (segment (start 123.3 91.8) (end 123.000001 91.500001) (width 0.182) (layer "B.Cu") (net 116))
  (segment (start 123.000001 91.500001) (end 120.799999 91.500001) (width 0.182) (layer "B.Cu") (net 116))
  (segment (start 119.9 92.4) (end 119.9 93.315) (width 0.182) (layer "B.Cu") (net 116))
  (segment (start 121.3 90.8) (end 121.3 89.6) (width 0.182) (layer "F.Cu") (net 117))
  (via (at 121.3 90.8) (size 0.6) (drill 0.25) (layers "F.Cu" "B.Cu") (net 117))
  (segment (start 123.9 92.315) (end 122.9 93.315) (width 0.182) (layer "B.Cu") (net 117))
  (segment (start 123.3 90.8) (end 123.9 91.4) (width 0.182) (layer "B.Cu") (net 117))
  (segment (start 121.3 90.8) (end 123.3 90.8) (width 0.182) (layer "B.Cu") (net 117))
  (segment (start 123.9 91.4) (end 123.9 92.315) (width 0.182) (layer "B.Cu") (net 117))
  (segment (start 121.266 91.734) (end 121.816001 91.183999) (width 0.182) (layer "F.Cu") (net 118))
  (segment (start 121.816001 90.598001) (end 121.75 90.532) (width 0.182) (layer "F.Cu") (net 118))
  (segment (start 121.75 89.55) (end 121.75 90.532) (width 0.182) (layer "F.Cu") (net 118))
  (segment (start 121.816001 91.183999) (end 121.816001 90.598001) (width 0.182) (layer "F.Cu") (net 118))
  (segment (start 121.266 92.2) (end 121.266 91.734) (width 0.182) (layer "F.Cu") (net 118))
  (via (at 121.266 92.2) (size 0.6) (drill 0.25) (layers "F.Cu" "B.Cu") (net 118))
  (segment (start 120.9 93.315) (end 120.9 92.566) (width 0.182) (layer "B.Cu") (net 118))
  (segment (start 120.9 92.566) (end 121.266 92.2) (width 0.182) (layer "B.Cu") (net 118))
  (segment (start 140.825001 95.025001) (end 141.2 95.4) (width 0.2) (layer "F.Cu") (net 119))
  (segment (start 137.625001 95.025001) (end 140.825001 95.025001) (width 0.2) (layer "F.Cu") (net 119))
  (segment (start 133.75 89.55) (end 133.75 91.15) (width 0.2) (layer "F.Cu") (net 119))
  (segment (start 133.75 91.15) (end 137.625001 95.025001) (width 0.2) (layer "F.Cu") (net 119))
  (via (at 141.2 95.4) (size 0.6) (drill 0.25) (layers "F.Cu" "B.Cu") (net 119))
  (segment (start 141.45 96.35) (end 141.2 96.1) (width 0.21) (layer "B.Cu") (net 119))
  (segment (start 142.845 96.35) (end 141.45 96.35) (width 0.21) (layer "B.Cu") (net 119))
  (segment (start 141.2 96.1) (end 141.2 95.4) (width 0.21) (layer "B.Cu") (net 119))
  (segment (start 140.2 95.6) (end 137.5 95.6) (width 0.2) (layer "F.Cu") (net 120))
  (segment (start 133.25 91.35) (end 133.25 89.55) (width 0.2) (layer "F.Cu") (net 120))
  (segment (start 137.5 95.6) (end 133.25 91.35) (width 0.2) (layer "F.Cu") (net 120))
  (via (at 140.2 95.6) (size 0.6) (drill 0.25) (layers "F.Cu" "B.Cu") (net 120))
  (segment (start 140.2 95.6) (end 140.2 94.985) (width 0.21) (layer "B.Cu") (net 120))
  (segment (start 140.2 94.985) (end 140.7 94.485) (width 0.21) (layer "B.Cu") (net 120))
  (segment (start 140.2 95.6) (end 140.2 96.4) (width 0.21) (layer "B.Cu") (net 120))
  (segment (start 140.2 96.4) (end 140.65 96.85) (width 0.21) (layer "B.Cu") (net 120))
  (segment (start 140.65 96.85) (end 142.845 96.85) (width 0.21) (layer "B.Cu") (net 120))
  (segment (start 142.845 98.85) (end 140.7 98.85) (width 0.125) (layer "B.Cu") (net 121))
  (segment (start 142.032759 97.664843) (end 142.142308 97.6525) (width 0.17) (layer "F.Cu") (net 122))
  (segment (start 144.195 98.368503) (end 144.200703 98.419126) (width 0.17) (layer "F.Cu") (net 122))
  (segment (start 148.585 96.2025) (end 148.8 95.9875) (width 0.17) (layer "F.Cu") (net 122))
  (segment (start 130.6475 90.852656) (end 130.6475 92.538902) (width 0.17) (layer "F.Cu") (net 122))
  (segment (start 145.032759 97.664843) (end 145.142308 97.6525) (width 0.17) (layer "F.Cu") (net 122))
  (segment (start 142.823791 98.573473) (end 142.871876 98.590299) (width 0.17) (layer "F.Cu") (net 122))
  (segment (start 144.323791 98.573473) (end 144.371876 98.590299) (width 0.17) (layer "F.Cu") (net 122))
  (segment (start 144.00964 97.759906) (end 144.087593 97.837859) (width 0.17) (layer "F.Cu") (net 122))
  (segment (start 130.750001 89.550004) (end 130.750001 90.750155) (width 0.17) (layer "F.Cu") (net 122))
  (segment (start 133.307444 94.669074) (end 133.341741 94.68559) (width 0.17) (layer "F.Cu") (net 122))
  (segment (start 132.918359 94.785953) (end 132.955473 94.794423) (width 0.17) (layer "F.Cu") (net 122))
  (segment (start 142.700703 98.419126) (end 142.717529 98.467211) (width 0.17) (layer "F.Cu") (net 122))
  (segment (start 135.761098 97.6525) (end 140.702691 97.6525) (width 0.17) (layer "F.Cu") (net 122))
  (segment (start 133.335131 95.226533) (end 135.761098 97.6525) (width 0.17) (layer "F.Cu") (net 122))
  (segment (start 133.411757 94.885681) (end 133.395239 94.919979) (width 0.17) (layer "F.Cu") (net 122))
  (segment (start 141.644296 98.419126) (end 141.65 98.368503) (width 0.17) (layer "F.Cu") (net 122))
  (segment (start 132.884061 94.769435) (end 132.918359 94.785953) (width 0.17) (layer "F.Cu") (net 122))
  (segment (start 141.65 98.144808) (end 141.662343 98.035259) (width 0.17) (layer "F.Cu") (net 122))
  (segment (start 144.280656 98.546369) (end 144.323791 98.573473) (width 0.17) (layer "F.Cu") (net 122))
  (segment (start 144.835359 97.759906) (end 144.928703 97.701253) (width 0.17) (layer "F.Cu") (net 122))
  (segment (start 133.286406 95.087289) (end 133.286406 95.125357) (width 0.17) (layer "F.Cu") (net 122))
  (segment (start 140.702691 97.6525) (end 140.81224 97.664843) (width 0.17) (layer "F.Cu") (net 122))
  (segment (start 143.428703 97.701253) (end 143.532759 97.664843) (width 0.17) (layer "F.Cu") (net 122))
  (segment (start 130.750001 90.750155) (end 130.6475 90.852656) (width 0.17) (layer "F.Cu") (net 122))
  (segment (start 144.521208 98.573473) (end 144.564343 98.546369) (width 0.17) (layer "F.Cu") (net 122))
  (segment (start 143.15 98.144808) (end 143.162343 98.035259) (width 0.17) (layer "F.Cu") (net 122))
  (segment (start 141.146246 97.931203) (end 141.182656 98.035259) (width 0.17) (layer "F.Cu") (net 122))
  (segment (start 133.195148 94.669073) (end 133.232263 94.660603) (width 0.17) (layer "F.Cu") (net 122))
  (segment (start 140.916296 97.701253) (end 141.00964 97.759906) (width 0.17) (layer "F.Cu") (net 122))
  (segment (start 141.473123 98.590299) (end 141.521208 98.573473) (width 0.17) (layer "F.Cu") (net 122))
  (segment (start 141.087593 97.837859) (end 141.146246 97.931203) (width 0.17) (layer "F.Cu") (net 122))
  (segment (start 141.200703 98.419126) (end 141.217529 98.467211) (width 0.17) (layer "F.Cu") (net 122))
  (segment (start 144.757406 97.837859) (end 144.835359 97.759906) (width 0.17) (layer "F.Cu") (net 122))
  (segment (start 142.9225 98.596003) (end 142.973123 98.590299) (width 0.17) (layer "F.Cu") (net 122))
  (segment (start 144.200703 98.419126) (end 144.217529 98.467211) (width 0.17) (layer "F.Cu") (net 122))
  (segment (start 141.195 98.368503) (end 141.200703 98.419126) (width 0.17) (layer "F.Cu") (net 122))
  (segment (start 142.646246 97.931203) (end 142.682656 98.035259) (width 0.17) (layer "F.Cu") (net 122))
  (segment (start 141.757406 97.837859) (end 141.835359 97.759906) (width 0.17) (layer "F.Cu") (net 122))
  (segment (start 133.33513 94.986116) (end 133.311394 95.015877) (width 0.17) (layer "F.Cu") (net 122))
  (segment (start 133.420226 94.848567) (end 133.411757 94.885681) (width 0.17) (layer "F.Cu") (net 122))
  (segment (start 141.62747 98.467211) (end 141.644296 98.419126) (width 0.17) (layer "F.Cu") (net 122))
  (segment (start 141.65 98.368503) (end 141.65 98.144808) (width 0.17) (layer "F.Cu") (net 122))
  (segment (start 143.916296 97.701253) (end 144.00964 97.759906) (width 0.17) (layer "F.Cu") (net 122))
  (segment (start 144.698753 97.931203) (end 144.757406 97.837859) (width 0.17) (layer "F.Cu") (net 122))
  (segment (start 142.780656 98.546369) (end 142.823791 98.573473) (width 0.17) (layer "F.Cu") (net 122))
  (segment (start 143.198753 97.931203) (end 143.257406 97.837859) (width 0.17) (layer "F.Cu") (net 122))
  (segment (start 133.094715 94.745701) (end 133.131088 94.709325) (width 0.17) (layer "F.Cu") (net 122))
  (segment (start 141.4225 98.596003) (end 141.473123 98.590299) (width 0.17) (layer "F.Cu") (net 122))
  (segment (start 144.662343 98.035259) (end 144.698753 97.931203) (width 0.17) (layer "F.Cu") (net 122))
  (segment (start 133.131088 94.709325) (end 133.160851 94.685591) (width 0.17) (layer "F.Cu") (net 122))
  (segment (start 142.744633 98.510346) (end 142.780656 98.546369) (width 0.17) (layer "F.Cu") (net 122))
  (segment (start 142.142308 97.6525) (end 142.202691 97.6525) (width 0.17) (layer "F.Cu") (net 122))
  (segment (start 143.702691 97.6525) (end 143.81224 97.664843) (width 0.17) (layer "F.Cu") (net 122))
  (segment (start 141.244633 98.510346) (end 141.280656 98.546369) (width 0.17) (layer "F.Cu") (net 122))
  (segment (start 144.928703 97.701253) (end 145.032759 97.664843) (width 0.17) (layer "F.Cu") (net 122))
  (segment (start 144.62747 98.467211) (end 144.644296 98.419126) (width 0.17) (layer "F.Cu") (net 122))
  (segment (start 148.088902 96.2025) (end 148.585 96.2025) (width 0.17) (layer "F.Cu") (net 122))
  (segment (start 141.280656 98.546369) (end 141.323791 98.573473) (width 0.17) (layer "F.Cu") (net 122))
  (segment (start 143.064343 98.546369) (end 143.100366 98.510346) (width 0.17) (layer "F.Cu") (net 122))
  (segment (start 142.682656 98.035259) (end 142.695 98.144808) (width 0.17) (layer "F.Cu") (net 122))
  (segment (start 144.087593 97.837859) (end 144.146246 97.931203) (width 0.17) (layer "F.Cu") (net 122))
  (segment (start 141.371876 98.590299) (end 141.4225 98.596003) (width 0.17) (layer "F.Cu") (net 122))
  (segment (start 133.411756 94.773385) (end 133.420226 94.810499) (width 0.17) (layer "F.Cu") (net 122))
  (segment (start 142.871876 98.590299) (end 142.9225 98.596003) (width 0.17) (layer "F.Cu") (net 122))
  (segment (start 144.65 98.144808) (end 144.662343 98.035259) (width 0.17) (layer "F.Cu") (net 122))
  (segment (start 142.202691 97.6525) (end 142.31224 97.664843) (width 0.17) (layer "F.Cu") (net 122))
  (segment (start 133.294878 95.050176) (end 133.286406 95.087289) (width 0.17) (layer "F.Cu") (net 122))
  (segment (start 142.695 98.368503) (end 142.700703 98.419126) (width 0.17) (layer "F.Cu") (net 122))
  (segment (start 144.217529 98.467211) (end 144.244633 98.510346) (width 0.17) (layer "F.Cu") (net 122))
  (segment (start 133.232263 94.660603) (end 133.270331 94.660603) (width 0.17) (layer "F.Cu") (net 122))
  (segment (start 141.698753 97.931203) (end 141.757406 97.837859) (width 0.17) (layer "F.Cu") (net 122))
  (segment (start 144.182656 98.035259) (end 144.195 98.144808) (width 0.17) (layer "F.Cu") (net 122))
  (segment (start 133.294877 95.16247) (end 133.311395 95.196769) (width 0.17) (layer "F.Cu") (net 122))
  (segment (start 133.311395 95.196769) (end 133.335131 95.226533) (width 0.17) (layer "F.Cu") (net 122))
  (segment (start 144.195 98.144808) (end 144.195 98.368503) (width 0.17) (layer "F.Cu") (net 122))
  (segment (start 143.335359 97.759906) (end 143.428703 97.701253) (width 0.17) (layer "F.Cu") (net 122))
  (segment (start 141.217529 98.467211) (end 141.244633 98.510346) (width 0.17) (layer "F.Cu") (net 122))
  (segment (start 133.030653 94.785952) (end 133.064951 94.769434) (width 0.17) (layer "F.Cu") (net 122))
  (segment (start 144.644296 98.419126) (end 144.65 98.368503) (width 0.17) (layer "F.Cu") (net 122))
  (segment (start 133.270331 94.660603) (end 133.307444 94.669074) (width 0.17) (layer "F.Cu") (net 122))
  (segment (start 141.928703 97.701253) (end 142.032759 97.664843) (width 0.17) (layer "F.Cu") (net 122))
  (segment (start 141.564343 98.546369) (end 141.600366 98.510346) (width 0.17) (layer "F.Cu") (net 122))
  (segment (start 133.064951 94.769434) (end 133.094715 94.745701) (width 0.17) (layer "F.Cu") (net 122))
  (segment (start 130.6475 92.538902) (end 132.854299 94.745701) (width 0.17) (layer "F.Cu") (net 122))
  (segment (start 144.371876 98.590299) (end 144.4225 98.596003) (width 0.17) (layer "F.Cu") (net 122))
  (segment (start 142.31224 97.664843) (end 142.416296 97.701253) (width 0.17) (layer "F.Cu") (net 122))
  (segment (start 141.323791 98.573473) (end 141.371876 98.590299) (width 0.17) (layer "F.Cu") (net 122))
  (segment (start 141.662343 98.035259) (end 141.698753 97.931203) (width 0.17) (layer "F.Cu") (net 122))
  (segment (start 144.4225 98.596003) (end 144.473123 98.590299) (width 0.17) (layer "F.Cu") (net 122))
  (segment (start 141.600366 98.510346) (end 141.62747 98.467211) (width 0.17) (layer "F.Cu") (net 122))
  (segment (start 143.021208 98.573473) (end 143.064343 98.546369) (width 0.17) (layer "F.Cu") (net 122))
  (segment (start 141.835359 97.759906) (end 141.928703 97.701253) (width 0.17) (layer "F.Cu") (net 122))
  (segment (start 144.244633 98.510346) (end 144.280656 98.546369) (width 0.17) (layer "F.Cu") (net 122))
  (segment (start 133.395239 94.919979) (end 133.371504 94.949741) (width 0.17) (layer "F.Cu") (net 122))
  (segment (start 143.15 98.368503) (end 143.15 98.144808) (width 0.17) (layer "F.Cu") (net 122))
  (segment (start 145.142308 97.6525) (end 146.638902 97.6525) (width 0.17) (layer "F.Cu") (net 122))
  (segment (start 133.420226 94.810499) (end 133.420226 94.848567) (width 0.17) (layer "F.Cu") (net 122))
  (segment (start 133.160851 94.685591) (end 133.195148 94.669073) (width 0.17) (layer "F.Cu") (net 122))
  (segment (start 142.973123 98.590299) (end 143.021208 98.573473) (width 0.17) (layer "F.Cu") (net 122))
  (segment (start 133.311394 95.015877) (end 133.294878 95.050176) (width 0.17) (layer "F.Cu") (net 122))
  (segment (start 143.532759 97.664843) (end 143.642308 97.6525) (width 0.17) (layer "F.Cu") (net 122))
  (segment (start 144.146246 97.931203) (end 144.182656 98.035259) (width 0.17) (layer "F.Cu") (net 122))
  (segment (start 141.521208 98.573473) (end 141.564343 98.546369) (width 0.17) (layer "F.Cu") (net 122))
  (segment (start 143.144296 98.419126) (end 143.15 98.368503) (width 0.17) (layer "F.Cu") (net 122))
  (segment (start 142.717529 98.467211) (end 142.744633 98.510346) (width 0.17) (layer "F.Cu") (net 122))
  (segment (start 132.993541 94.794423) (end 133.030653 94.785952) (width 0.17) (layer "F.Cu") (net 122))
  (segment (start 143.12747 98.467211) (end 143.144296 98.419126) (width 0.17) (layer "F.Cu") (net 122))
  (segment (start 133.371504 94.949741) (end 133.33513 94.986116) (width 0.17) (layer "F.Cu") (net 122))
  (segment (start 132.854299 94.745701) (end 132.884061 94.769435) (width 0.17) (layer "F.Cu") (net 122))
  (segment (start 143.257406 97.837859) (end 143.335359 97.759906) (width 0.17) (layer "F.Cu") (net 122))
  (segment (start 133.341741 94.68559) (end 133.371504 94.709325) (width 0.17) (layer "F.Cu") (net 122))
  (segment (start 143.642308 97.6525) (end 143.702691 97.6525) (width 0.17) (layer "F.Cu") (net 122))
  (segment (start 133.286406 95.125357) (end 133.294877 95.16247) (width 0.17) (layer "F.Cu") (net 122))
  (segment (start 142.695 98.144808) (end 142.695 98.368503) (width 0.17) (layer "F.Cu") (net 122))
  (segment (start 133.371504 94.709325) (end 133.395238 94.739087) (width 0.17) (layer "F.Cu") (net 122))
  (segment (start 144.65 98.368503) (end 144.65 98.144808) (width 0.17) (layer "F.Cu") (net 122))
  (segment (start 143.162343 98.035259) (end 143.198753 97.931203) (width 0.17) (layer "F.Cu") (net 122))
  (segment (start 141.182656 98.035259) (end 141.195 98.144808) (width 0.17) (layer "F.Cu") (net 122))
  (segment (start 141.00964 97.759906) (end 141.087593 97.837859) (width 0.17) (layer "F.Cu") (net 122))
  (segment (start 144.600366 98.510346) (end 144.62747 98.467211) (width 0.17) (layer "F.Cu") (net 122))
  (segment (start 144.473123 98.590299) (end 144.521208 98.573473) (width 0.17) (layer "F.Cu") (net 122))
  (segment (start 143.81224 97.664843) (end 143.916296 97.701253) (width 0.17) (layer "F.Cu") (net 122))
  (segment (start 142.416296 97.701253) (end 142.50964 97.759906) (width 0.17) (layer "F.Cu") (net 122))
  (segment (start 146.638902 97.6525) (end 148.088902 96.2025) (width 0.17) (layer "F.Cu") (net 122))
  (segment (start 144.564343 98.546369) (end 144.600366 98.510346) (width 0.17) (layer "F.Cu") (net 122))
  (segment (start 142.587593 97.837859) (end 142.646246 97.931203) (width 0.17) (layer "F.Cu") (net 122))
  (segment (start 140.81224 97.664843) (end 140.916296 97.701253) (width 0.17) (layer "F.Cu") (net 122))
  (segment (start 141.195 98.144808) (end 141.195 98.368503) (width 0.17) (layer "F.Cu") (net 122))
  (segment (start 133.395238 94.739087) (end 133.411756 94.773385) (width 0.17) (layer "F.Cu") (net 122))
  (segment (start 142.50964 97.759906) (end 142.587593 97.837859) (width 0.17) (layer "F.Cu") (net 122))
  (segment (start 132.955473 94.794423) (end 132.993541 94.794423) (width 0.17) (layer "F.Cu") (net 122))
  (segment (start 143.100366 98.510346) (end 143.12747 98.467211) (width 0.17) (layer "F.Cu") (net 122))
  (via (at 148.8 95.9875) (size 0.6) (drill 0.25) (layers "F.Cu" "B.Cu") (net 122))
  (segment (start 149.129989 96.2025) (end 149.015 96.2025) (width 0.17) (layer "B.Cu") (net 122))
  (segment (start 149.232489 96.1) (end 149.129989 96.2025) (width 0.17) (layer "B.Cu") (net 122))
  (segment (start 149.015 96.2025) (end 148.8 95.9875) (width 0.17) (layer "B.Cu") (net 122))
  (segment (start 150.39499 96.1) (end 149.232489 96.1) (width 0.17) (layer "B.Cu") (net 122))
  (segment (start 132.561757 95.935681) (end 132.545239 95.969979) (width 0.17) (layer "F.Cu") (net 123))
  (segment (start 141.482449 99.396722) (end 141.543908 99.494533) (width 0.17) (layer "F.Cu") (net 123))
  (segment (start 132.004299 95.795701) (end 132.034061 95.819435) (width 0.17) (layer "F.Cu") (net 123))
  (segment (start 132.521504 95.999741) (end 132.48513 96.036116) (width 0.17) (layer "F.Cu") (net 123))
  (segment (start 132.281088 95.759325) (end 132.310851 95.735591) (width 0.17) (layer "F.Cu") (net 123))
  (segment (start 141.594995 100.290992) (end 141.601325 100.347178) (width 0.17) (layer "F.Cu") (net 123))
  (segment (start 141.903681 100.537161) (end 141.95705 100.518486) (width 0.17) (layer "F.Cu") (net 123))
  (segment (start 141.62 100.400547) (end 141.650082 100.448423) (width 0.17) (layer "F.Cu") (net 123))
  (segment (start 142.615858 99.202495) (end 147.785 99.202495) (width 0.17) (layer "F.Cu") (net 123))
  (segment (start 142.21254 99.396722) (end 142.294222 99.31504) (width 0.17) (layer "F.Cu") (net 123))
  (segment (start 141.079131 99.202495) (end 141.193921 99.215428) (width 0.17) (layer "F.Cu") (net 123))
  (segment (start 132.457444 95.719074) (end 132.491741 95.73559) (width 0.17) (layer "F.Cu") (net 123))
  (segment (start 141.594995 99.718358) (end 141.594995 100.290992) (width 0.17) (layer "F.Cu") (net 123))
  (segment (start 141.302956 99.253581) (end 141.400767 99.31504) (width 0.17) (layer "F.Cu") (net 123))
  (segment (start 141.193921 99.215428) (end 141.302956 99.253581) (width 0.17) (layer "F.Cu") (net 123))
  (segment (start 142.099995 100.290992) (end 142.099995 99.718358) (width 0.17) (layer "F.Cu") (net 123))
  (segment (start 132.444878 96.100176) (end 132.436406 96.137289) (width 0.17) (layer "F.Cu") (net 123))
  (segment (start 142.501068 99.215428) (end 142.615858 99.202495) (width 0.17) (layer "F.Cu") (net 123))
  (segment (start 132.345148 95.719073) (end 132.382263 95.710603) (width 0.17) (layer "F.Cu") (net 123))
  (segment (start 141.650082 100.448423) (end 141.690063 100.488404) (width 0.17) (layer "F.Cu") (net 123))
  (segment (start 132.545239 95.969979) (end 132.521504 95.999741) (width 0.17) (layer "F.Cu") (net 123))
  (segment (start 132.310851 95.735591) (end 132.345148 95.719073) (width 0.17) (layer "F.Cu") (net 123))
  (segment (start 129.147499 92.938901) (end 132.004299 95.795701) (width 0.17) (layer "F.Cu") (net 123))
  (segment (start 141.847495 100.543492) (end 141.903681 100.537161) (width 0.17) (layer "F.Cu") (net 123))
  (segment (start 132.068359 95.835953) (end 132.105473 95.844423) (width 0.17) (layer "F.Cu") (net 123))
  (segment (start 141.601325 100.347178) (end 141.62 100.400547) (width 0.17) (layer "F.Cu") (net 123))
  (segment (start 129.249999 90.750155) (end 129.147499 90.852655) (width 0.17) (layer "F.Cu") (net 123))
  (segment (start 132.545238 95.789087) (end 132.561756 95.823385) (width 0.17) (layer "F.Cu") (net 123))
  (segment (start 132.214951 95.819434) (end 132.244715 95.795701) (width 0.17) (layer "F.Cu") (net 123))
  (segment (start 132.180653 95.835952) (end 132.214951 95.819434) (width 0.17) (layer "F.Cu") (net 123))
  (segment (start 132.485131 96.276533) (end 135.411093 99.202495) (width 0.17) (layer "F.Cu") (net 123))
  (segment (start 142.112928 99.603568) (end 142.151081 99.494533) (width 0.17) (layer "F.Cu") (net 123))
  (segment (start 132.143541 95.844423) (end 132.180653 95.835952) (width 0.17) (layer "F.Cu") (net 123))
  (segment (start 132.570226 95.898567) (end 132.561757 95.935681) (width 0.17) (layer "F.Cu") (net 123))
  (segment (start 141.737939 100.518486) (end 141.791308 100.537161) (width 0.17) (layer "F.Cu") (net 123))
  (segment (start 141.400767 99.31504) (end 141.482449 99.396722) (width 0.17) (layer "F.Cu") (net 123))
  (segment (start 142.151081 99.494533) (end 142.21254 99.396722) (width 0.17) (layer "F.Cu") (net 123))
  (segment (start 142.074989 100.400547) (end 142.093664 100.347178) (width 0.17) (layer "F.Cu") (net 123))
  (segment (start 141.582061 99.603568) (end 141.594995 99.718358) (width 0.17) (layer "F.Cu") (net 123))
  (segment (start 141.791308 100.537161) (end 141.847495 100.543492) (width 0.17) (layer "F.Cu") (net 123))
  (segment (start 142.392033 99.253581) (end 142.501068 99.215428) (width 0.17) (layer "F.Cu") (net 123))
  (segment (start 142.294222 99.31504) (end 142.392033 99.253581) (width 0.17) (layer "F.Cu") (net 123))
  (segment (start 141.543908 99.494533) (end 141.582061 99.603568) (width 0.17) (layer "F.Cu") (net 123))
  (segment (start 142.004926 100.488404) (end 142.044907 100.448423) (width 0.17) (layer "F.Cu") (net 123))
  (segment (start 132.436406 96.137289) (end 132.436406 96.175357) (width 0.17) (layer "F.Cu") (net 123))
  (segment (start 129.249999 89.550004) (end 129.249999 90.750155) (width 0.17) (layer "F.Cu") (net 123))
  (segment (start 147.785 99.202495) (end 148 98.987495) (width 0.17) (layer "F.Cu") (net 123))
  (segment (start 132.436406 96.175357) (end 132.444877 96.21247) (width 0.17) (layer "F.Cu") (net 123))
  (segment (start 132.48513 96.036116) (end 132.461394 96.065877) (width 0.17) (layer "F.Cu") (net 123))
  (segment (start 129.147499 90.852655) (end 129.147499 92.938901) (width 0.17) (layer "F.Cu") (net 123))
  (segment (start 132.034061 95.819435) (end 132.068359 95.835953) (width 0.17) (layer "F.Cu") (net 123))
  (segment (start 132.420331 95.710603) (end 132.457444 95.719074) (width 0.17) (layer "F.Cu") (net 123))
  (segment (start 132.491741 95.73559) (end 132.521504 95.759325) (width 0.17) (layer "F.Cu") (net 123))
  (segment (start 132.461394 96.065877) (end 132.444878 96.100176) (width 0.17) (layer "F.Cu") (net 123))
  (segment (start 132.382263 95.710603) (end 132.420331 95.710603) (width 0.17) (layer "F.Cu") (net 123))
  (segment (start 141.690063 100.488404) (end 141.737939 100.518486) (width 0.17) (layer "F.Cu") (net 123))
  (segment (start 132.244715 95.795701) (end 132.281088 95.759325) (width 0.17) (layer "F.Cu") (net 123))
  (segment (start 132.444877 96.21247) (end 132.461395 96.246769) (width 0.17) (layer "F.Cu") (net 123))
  (segment (start 132.461395 96.246769) (end 132.485131 96.276533) (width 0.17) (layer "F.Cu") (net 123))
  (segment (start 135.411093 99.202495) (end 141.079131 99.202495) (width 0.17) (layer "F.Cu") (net 123))
  (segment (start 141.95705 100.518486) (end 142.004926 100.488404) (width 0.17) (layer "F.Cu") (net 123))
  (segment (start 132.561756 95.823385) (end 132.570226 95.860499) (width 0.17) (layer "F.Cu") (net 123))
  (segment (start 132.521504 95.759325) (end 132.545238 95.789087) (width 0.17) (layer "F.Cu") (net 123))
  (segment (start 142.099995 99.718358) (end 142.112928 99.603568) (width 0.17) (layer "F.Cu") (net 123))
  (segment (start 132.570226 95.860499) (end 132.570226 95.898567) (width 0.17) (layer "F.Cu") (net 123))
  (segment (start 142.093664 100.347178) (end 142.099995 100.290992) (width 0.17) (layer "F.Cu") (net 123))
  (segment (start 142.044907 100.448423) (end 142.074989 100.400547) (width 0.17) (layer "F.Cu") (net 123))
  (segment (start 132.105473 95.844423) (end 132.143541 95.844423) (width 0.17) (layer "F.Cu") (net 123))
  (via (at 148 98.987495) (size 0.6) (drill 0.25) (layers "F.Cu" "B.Cu") (net 123))
  (segment (start 148.215 99.202495) (end 148 98.987495) (width 0.17) (layer "B.Cu") (net 123))
  (segment (start 149.232489 99.1) (end 149.129994 99.202495) (width 0.17) (layer "B.Cu") (net 123))
  (segment (start 150.39499 99.1) (end 149.232489 99.1) (width 0.17) (layer "B.Cu") (net 123))
  (segment (start 149.129994 99.202495) (end 148.215 99.202495) (width 0.17) (layer "B.Cu") (net 123))
  (segment (start 134.25 90.95) (end 134.25 89.55) (width 0.2) (layer "F.Cu") (net 124))
  (segment (start 138.9 94.4) (end 137.7 94.4) (width 0.2) (layer "F.Cu") (net 124))
  (segment (start 137.7 94.4) (end 134.25 90.95) (width 0.2) (layer "F.Cu") (net 124))
  (via (at 138.9 94.4) (size 0.6) (drill 0.25) (layers "F.Cu" "B.Cu") (net 124))
  (segment (start 138.9 96.4) (end 139.35 96.85) (width 0.2) (layer "B.Cu") (net 124))
  (segment (start 138.9 94.4) (end 139.615 94.4) (width 0.2) (layer "B.Cu") (net 124))
  (segment (start 139.35 96.85) (end 139.85 97.35) (width 0.21) (layer "B.Cu") (net 124))
  (segment (start 138.9 94.4) (end 138.9 96.4) (width 0.2) (layer "B.Cu") (net 124))
  (segment (start 139.85 97.35) (end 142.845 97.35) (width 0.21) (layer "B.Cu") (net 124))
  (segment (start 141.299995 100.322628) (end 141.312928 100.437418) (width 0.17) (layer "F.Cu") (net 125))
  (segment (start 142.591308 99.503825) (end 142.647495 99.497495) (width 0.17) (layer "F.Cu") (net 125))
  (segment (start 128.8525 90.852655) (end 128.8525 93.061098) (width 0.17) (layer "F.Cu") (net 125))
  (segment (start 141.879131 100.838492) (end 141.993921 100.825558) (width 0.17) (layer "F.Cu") (net 125))
  (segment (start 142.102956 100.787405) (end 142.200767 100.725946) (width 0.17) (layer "F.Cu") (net 125))
  (segment (start 142.450082 99.592563) (end 142.490063 99.552582) (width 0.17) (layer "F.Cu") (net 125))
  (segment (start 141.244907 99.592563) (end 141.274989 99.640439) (width 0.17) (layer "F.Cu") (net 125))
  (segment (start 141.993921 100.825558) (end 142.102956 100.787405) (width 0.17) (layer "F.Cu") (net 125))
  (segment (start 141.15705 99.5225) (end 141.204926 99.552582) (width 0.17) (layer "F.Cu") (net 125))
  (segment (start 141.41254 100.644264) (end 141.494222 100.725946) (width 0.17) (layer "F.Cu") (net 125))
  (segment (start 142.647495 99.497495) (end 147.785 99.497495) (width 0.17) (layer "F.Cu") (net 125))
  (segment (start 141.494222 100.725946) (end 141.592033 100.787405) (width 0.17) (layer "F.Cu") (net 125))
  (segment (start 142.282449 100.644264) (end 142.343908 100.546453) (width 0.17) (layer "F.Cu") (net 125))
  (segment (start 147.785 99.497495) (end 148 99.712495) (width 0.17) (layer "F.Cu") (net 125))
  (segment (start 142.394995 99.749995) (end 142.401325 99.693808) (width 0.17) (layer "F.Cu") (net 125))
  (segment (start 141.701068 100.825558) (end 141.815858 100.838492) (width 0.17) (layer "F.Cu") (net 125))
  (segment (start 142.343908 100.546453) (end 142.382061 100.437418) (width 0.17) (layer "F.Cu") (net 125))
  (segment (start 128.75 90.750155) (end 128.8525 90.852655) (width 0.17) (layer "F.Cu") (net 125))
  (segment (start 142.537939 99.5225) (end 142.591308 99.503825) (width 0.17) (layer "F.Cu") (net 125))
  (segment (start 128.8525 93.061098) (end 135.288897 99.497495) (width 0.17) (layer "F.Cu") (net 125))
  (segment (start 141.293664 99.693808) (end 141.299995 99.749995) (width 0.17) (layer "F.Cu") (net 125))
  (segment (start 141.299995 99.749995) (end 141.299995 100.322628) (width 0.17) (layer "F.Cu") (net 125))
  (segment (start 141.047495 99.497495) (end 141.103681 99.503825) (width 0.17) (layer "F.Cu") (net 125))
  (segment (start 141.592033 100.787405) (end 141.701068 100.825558) (width 0.17) (layer "F.Cu") (net 125))
  (segment (start 141.274989 99.640439) (end 141.293664 99.693808) (width 0.17) (layer "F.Cu") (net 125))
  (segment (start 142.394995 100.322628) (end 142.394995 99.749995) (width 0.17) (layer "F.Cu") (net 125))
  (segment (start 141.312928 100.437418) (end 141.351081 100.546453) (width 0.17) (layer "F.Cu") (net 125))
  (segment (start 142.490063 99.552582) (end 142.537939 99.5225) (width 0.17) (layer "F.Cu") (net 125))
  (segment (start 142.42 99.640439) (end 142.450082 99.592563) (width 0.17) (layer "F.Cu") (net 125))
  (segment (start 142.382061 100.437418) (end 142.394995 100.322628) (width 0.17) (layer "F.Cu") (net 125))
  (segment (start 128.75 89.550004) (end 128.75 90.750155) (width 0.17) (layer "F.Cu") (net 125))
  (segment (start 142.200767 100.725946) (end 142.282449 100.644264) (width 0.17) (layer "F.Cu") (net 125))
  (segment (start 141.351081 100.546453) (end 141.41254 100.644264) (width 0.17) (layer "F.Cu") (net 125))
  (segment (start 141.815858 100.838492) (end 141.879131 100.838492) (width 0.17) (layer "F.Cu") (net 125))
  (segment (start 141.204926 99.552582) (end 141.244907 99.592563) (width 0.17) (layer "F.Cu") (net 125))
  (segment (start 142.401325 99.693808) (end 142.42 99.640439) (width 0.17) (layer "F.Cu") (net 125))
  (segment (start 135.288897 99.497495) (end 141.047495 99.497495) (width 0.17) (layer "F.Cu") (net 125))
  (segment (start 141.103681 99.503825) (end 141.15705 99.5225) (width 0.17) (layer "F.Cu") (net 125))
  (via (at 148 99.712495) (size 0.6) (drill 0.25) (layers "F.Cu" "B.Cu") (net 125))
  (segment (start 149.129994 99.497495) (end 148.215 99.497495) (width 0.17) (layer "B.Cu") (net 125))
  (segment (start 149.232489 99.59999) (end 149.129994 99.497495) (width 0.17) (layer "B.Cu") (net 125))
  (segment (start 148.215 99.497495) (end 148 99.712495) (width 0.17) (layer "B.Cu") (net 125))
  (segment (start 150.39499 99.59999) (end 149.232489 99.59999) (width 0.17) (layer "B.Cu") (net 125))
  (segment (start 143.445 98.175) (end 143.450703 98.124376) (width 0.17) (layer "F.Cu") (net 126))
  (segment (start 144.994633 98.033156) (end 145.030656 97.997133) (width 0.17) (layer "F.Cu") (net 126))
  (segment (start 144.896246 98.612299) (end 144.932656 98.508243) (width 0.17) (layer "F.Cu") (net 126))
  (segment (start 141.945 98.175) (end 141.950703 98.124376) (width 0.17) (layer "F.Cu") (net 126))
  (segment (start 143.450703 98.124376) (end 143.467529 98.076291) (width 0.17) (layer "F.Cu") (net 126))
  (segment (start 142.37747 98.076291) (end 142.394296 98.124376) (width 0.17) (layer "F.Cu") (net 126))
  (segment (start 141.837593 98.705643) (end 141.896246 98.612299) (width 0.17) (layer "F.Cu") (net 126))
  (segment (start 143.166296 98.842249) (end 143.25964 98.783596) (width 0.17) (layer "F.Cu") (net 126))
  (segment (start 140.87747 98.076291) (end 140.894296 98.124376) (width 0.17) (layer "F.Cu") (net 126))
  (segment (start 130.25 89.550004) (end 130.25 90.750155) (width 0.17) (layer "F.Cu") (net 126))
  (segment (start 142.585359 98.783596) (end 142.678703 98.842249) (width 0.17) (layer "F.Cu") (net 126))
  (segment (start 141.666296 98.842249) (end 141.75964 98.783596) (width 0.17) (layer "F.Cu") (net 126))
  (segment (start 140.771208 97.970029) (end 140.814343 97.997133) (width 0.17) (layer "F.Cu") (net 126))
  (segment (start 143.337593 98.705643) (end 143.396246 98.612299) (width 0.17) (layer "F.Cu") (net 126))
  (segment (start 142.782759 98.878659) (end 142.892308 98.891003) (width 0.17) (layer "F.Cu") (net 126))
  (segment (start 144.56224 98.878659) (end 144.666296 98.842249) (width 0.17) (layer "F.Cu") (net 126))
  (segment (start 144.178703 98.842249) (end 144.282759 98.878659) (width 0.17) (layer "F.Cu") (net 126))
  (segment (start 145.030656 97.997133) (end 145.073791 97.970029) (width 0.17) (layer "F.Cu") (net 126))
  (segment (start 143.948753 98.612299) (end 144.007406 98.705643) (width 0.17) (layer "F.Cu") (net 126))
  (segment (start 144.950703 98.124376) (end 144.967529 98.076291) (width 0.17) (layer "F.Cu") (net 126))
  (segment (start 140.850366 98.033156) (end 140.87747 98.076291) (width 0.17) (layer "F.Cu") (net 126))
  (segment (start 146.761098 97.9475) (end 148.211098 96.4975) (width 0.17) (layer "F.Cu") (net 126))
  (segment (start 142.412343 98.508243) (end 142.448753 98.612299) (width 0.17) (layer "F.Cu") (net 126))
  (segment (start 148.585 96.4975) (end 148.8 96.7125) (width 0.17) (layer "F.Cu") (net 126))
  (segment (start 142.350366 98.033156) (end 142.37747 98.076291) (width 0.17) (layer "F.Cu") (net 126))
  (segment (start 144.666296 98.842249) (end 144.75964 98.783596) (width 0.17) (layer "F.Cu") (net 126))
  (segment (start 140.9 98.398694) (end 140.912343 98.508243) (width 0.17) (layer "F.Cu") (net 126))
  (segment (start 144.945 98.398694) (end 144.945 98.175) (width 0.17) (layer "F.Cu") (net 126))
  (segment (start 144.452691 98.891003) (end 144.56224 98.878659) (width 0.17) (layer "F.Cu") (net 126))
  (segment (start 143.814343 97.997133) (end 143.850366 98.033156) (width 0.17) (layer "F.Cu") (net 126))
  (segment (start 144.085359 98.783596) (end 144.178703 98.842249) (width 0.17) (layer "F.Cu") (net 126))
  (segment (start 141.085359 98.783596) (end 141.178703 98.842249) (width 0.17) (layer "F.Cu") (net 126))
  (segment (start 140.894296 98.124376) (end 140.9 98.175) (width 0.17) (layer "F.Cu") (net 126))
  (segment (start 143.850366 98.033156) (end 143.87747 98.076291) (width 0.17) (layer "F.Cu") (net 126))
  (segment (start 130.352501 92.661099) (end 135.638902 97.9475) (width 0.17) (layer "F.Cu") (net 126))
  (segment (start 143.494633 98.033156) (end 143.530656 97.997133) (width 0.17) (layer "F.Cu") (net 126))
  (segment (start 143.621876 97.953203) (end 143.6725 97.9475) (width 0.17) (layer "F.Cu") (net 126))
  (segment (start 141.178703 98.842249) (end 141.282759 98.878659) (width 0.17) (layer "F.Cu") (net 126))
  (segment (start 145.1725 97.9475) (end 146.761098 97.9475) (width 0.17) (layer "F.Cu") (net 126))
  (segment (start 141.932656 98.508243) (end 141.945 98.398694) (width 0.17) (layer "F.Cu") (net 126))
  (segment (start 143.06224 98.878659) (end 143.166296 98.842249) (width 0.17) (layer "F.Cu") (net 126))
  (segment (start 145.073791 97.970029) (end 145.121876 97.953203) (width 0.17) (layer "F.Cu") (net 126))
  (segment (start 144.967529 98.076291) (end 144.994633 98.033156) (width 0.17) (layer "F.Cu") (net 126))
  (segment (start 143.573791 97.970029) (end 143.621876 97.953203) (width 0.17) (layer "F.Cu") (net 126))
  (segment (start 140.814343 97.997133) (end 140.850366 98.033156) (width 0.17) (layer "F.Cu") (net 126))
  (segment (start 144.282759 98.878659) (end 144.392308 98.891003) (width 0.17) (layer "F.Cu") (net 126))
  (segment (start 141.945 98.398694) (end 141.945 98.175) (width 0.17) (layer "F.Cu") (net 126))
  (segment (start 145.121876 97.953203) (end 145.1725 97.9475) (width 0.17) (layer "F.Cu") (net 126))
  (segment (start 148.211098 96.4975) (end 148.585 96.4975) (width 0.17) (layer "F.Cu") (net 126))
  (segment (start 142.223123 97.953203) (end 142.271208 97.970029) (width 0.17) (layer "F.Cu") (net 126))
  (segment (start 142.271208 97.970029) (end 142.314343 97.997133) (width 0.17) (layer "F.Cu") (net 126))
  (segment (start 142.507406 98.705643) (end 142.585359 98.783596) (width 0.17) (layer "F.Cu") (net 126))
  (segment (start 141.282759 98.878659) (end 141.392308 98.891003) (width 0.17) (layer "F.Cu") (net 126))
  (segment (start 142.678703 98.842249) (end 142.782759 98.878659) (width 0.17) (layer "F.Cu") (net 126))
  (segment (start 142.314343 97.997133) (end 142.350366 98.033156) (width 0.17) (layer "F.Cu") (net 126))
  (segment (start 144.007406 98.705643) (end 144.085359 98.783596) (width 0.17) (layer "F.Cu") (net 126))
  (segment (start 142.952691 98.891003) (end 143.06224 98.878659) (width 0.17) (layer "F.Cu") (net 126))
  (segment (start 141.392308 98.891003) (end 141.452691 98.891003) (width 0.17) (layer "F.Cu") (net 126))
  (segment (start 143.9 98.175) (end 143.9 98.398694) (width 0.17) (layer "F.Cu") (net 126))
  (segment (start 143.912343 98.508243) (end 143.948753 98.612299) (width 0.17) (layer "F.Cu") (net 126))
  (segment (start 143.25964 98.783596) (end 143.337593 98.705643) (width 0.17) (layer "F.Cu") (net 126))
  (segment (start 140.912343 98.508243) (end 140.948753 98.612299) (width 0.17) (layer "F.Cu") (net 126))
  (segment (start 142.394296 98.124376) (end 142.4 98.175) (width 0.17) (layer "F.Cu") (net 126))
  (segment (start 144.75964 98.783596) (end 144.837593 98.705643) (width 0.17) (layer "F.Cu") (net 126))
  (segment (start 135.638902 97.9475) (end 140.6725 97.9475) (width 0.17) (layer "F.Cu") (net 126))
  (segment (start 140.723123 97.953203) (end 140.771208 97.970029) (width 0.17) (layer "F.Cu") (net 126))
  (segment (start 142.4 98.175) (end 142.4 98.398694) (width 0.17) (layer "F.Cu") (net 126))
  (segment (start 142.030656 97.997133) (end 142.073791 97.970029) (width 0.17) (layer "F.Cu") (net 126))
  (segment (start 141.452691 98.891003) (end 141.56224 98.878659) (width 0.17) (layer "F.Cu") (net 126))
  (segment (start 140.9 98.175) (end 140.9 98.398694) (width 0.17) (layer "F.Cu") (net 126))
  (segment (start 142.121876 97.953203) (end 142.1725 97.9475) (width 0.17) (layer "F.Cu") (net 126))
  (segment (start 144.392308 98.891003) (end 144.452691 98.891003) (width 0.17) (layer "F.Cu") (net 126))
  (segment (start 141.75964 98.783596) (end 141.837593 98.705643) (width 0.17) (layer "F.Cu") (net 126))
  (segment (start 144.945 98.175) (end 144.950703 98.124376) (width 0.17) (layer "F.Cu") (net 126))
  (segment (start 142.073791 97.970029) (end 142.121876 97.953203) (width 0.17) (layer "F.Cu") (net 126))
  (segment (start 142.1725 97.9475) (end 142.223123 97.953203) (width 0.17) (layer "F.Cu") (net 126))
  (segment (start 143.894296 98.124376) (end 143.9 98.175) (width 0.17) (layer "F.Cu") (net 126))
  (segment (start 143.396246 98.612299) (end 143.432656 98.508243) (width 0.17) (layer "F.Cu") (net 126))
  (segment (start 143.530656 97.997133) (end 143.573791 97.970029) (width 0.17) (layer "F.Cu") (net 126))
  (segment (start 141.967529 98.076291) (end 141.994633 98.033156) (width 0.17) (layer "F.Cu") (net 126))
  (segment (start 140.948753 98.612299) (end 141.007406 98.705643) (width 0.17) (layer "F.Cu") (net 126))
  (segment (start 141.950703 98.124376) (end 141.967529 98.076291) (width 0.17) (layer "F.Cu") (net 126))
  (segment (start 142.4 98.398694) (end 142.412343 98.508243) (width 0.17) (layer "F.Cu") (net 126))
  (segment (start 141.896246 98.612299) (end 141.932656 98.508243) (width 0.17) (layer "F.Cu") (net 126))
  (segment (start 142.892308 98.891003) (end 142.952691 98.891003) (width 0.17) (layer "F.Cu") (net 126))
  (segment (start 143.445 98.398694) (end 143.445 98.175) (width 0.17) (layer "F.Cu") (net 126))
  (segment (start 130.25 90.750155) (end 130.352501 90.852656) (width 0.17) (layer "F.Cu") (net 126))
  (segment (start 143.723123 97.953203) (end 143.771208 97.970029) (width 0.17) (layer "F.Cu") (net 126))
  (segment (start 143.87747 98.076291) (end 143.894296 98.124376) (width 0.17) (layer "F.Cu") (net 126))
  (segment (start 130.352501 90.852656) (end 130.352501 92.661099) (width 0.17) (layer "F.Cu") (net 126))
  (segment (start 141.994633 98.033156) (end 142.030656 97.997133) (width 0.17) (layer "F.Cu") (net 126))
  (segment (start 143.432656 98.508243) (end 143.445 98.398694) (width 0.17) (layer "F.Cu") (net 126))
  (segment (start 143.9 98.398694) (end 143.912343 98.508243) (width 0.17) (layer "F.Cu") (net 126))
  (segment (start 141.56224 98.878659) (end 141.666296 98.842249) (width 0.17) (layer "F.Cu") (net 126))
  (segment (start 140.6725 97.9475) (end 140.723123 97.953203) (width 0.17) (layer "F.Cu") (net 126))
  (segment (start 142.448753 98.612299) (end 142.507406 98.705643) (width 0.17) (layer "F.Cu") (net 126))
  (segment (start 144.932656 98.508243) (end 144.945 98.398694) (width 0.17) (layer "F.Cu") (net 126))
  (segment (start 144.837593 98.705643) (end 144.896246 98.612299) (width 0.17) (layer "F.Cu") (net 126))
  (segment (start 143.771208 97.970029) (end 143.814343 97.997133) (width 0.17) (layer "F.Cu") (net 126))
  (segment (start 143.467529 98.076291) (end 143.494633 98.033156) (width 0.17) (layer "F.Cu") (net 126))
  (segment (start 141.007406 98.705643) (end 141.085359 98.783596) (width 0.17) (layer "F.Cu") (net 126))
  (segment (start 143.6725 97.9475) (end 143.723123 97.953203) (width 0.17) (layer "F.Cu") (net 126))
  (via (at 148.8 96.7125) (size 0.6) (drill 0.25) (layers "F.Cu" "B.Cu") (net 126))
  (segment (start 149.129989 96.4975) (end 149.015 96.4975) (width 0.17) (layer "B.Cu") (net 126))
  (segment (start 150.39499 96.6) (end 149.232489 96.6) (width 0.17) (layer "B.Cu") (net 126))
  (segment (start 149.232489 96.6) (end 149.129989 96.4975) (width 0.17) (layer "B.Cu") (net 126))
  (segment (start 149.015 96.4975) (end 148.8 96.7125) (width 0.17) (layer "B.Cu") (net 126))
  (segment (start 126.275 134.675) (end 126.275 134.225) (width 0.25) (layer "F.Cu") (net 127))
  (segment (start 126.275 134.225) (end 126.3 134.2) (width 0.25) (layer "F.Cu") (net 127))
  (via (at 126.3 134.2) (size 0.6) (drill 0.25) (layers "F.Cu" "B.Cu") (net 127))
  (segment (start 126.3 134.2) (end 126.3 132.8492) (width 0.15) (layer "B.Cu") (net 127))
  (segment (start 79.415 123.9) (end 78.465 123.9) (width 0.15) (layer "F.Cu") (net 128))
  (segment (start 77.202399 124.15) (end 78.215 124.15) (width 0.15) (layer "F.Cu") (net 128))
  (segment (start 78.215 124.15) (end 78.45 123.915) (width 0.15) (layer "F.Cu") (net 128))
  (segment (start 125.59996 127.011038) (end 125.088962 126.50004) (width 0.15) (layer "F.Cu") (net 129))
  (segment (start 125.9 130.6) (end 125.6 130.6) (width 0.15) (layer "F.Cu") (net 129))
  (segment (start 127.7125 133.0875) (end 128 133.375) (width 0.15) (layer "F.Cu") (net 129))
  (segment (start 128 133.375) (end 128 133.95) (width 0.15) (layer "F.Cu") (net 129))
  (segment (start 110.147328 120.346966) (end 109.697343 119.896981) (width 0.15) (layer "F.Cu") (net 129))
  (segment (start 117.99996 123.611038) (end 117.588962 123.20004) (width 0.15) (layer "F.Cu") (net 129))
  (segment (start 117.99996 125.555648) (end 117.99996 123.611038) (width 0.15) (layer "F.Cu") (net 129))
  (segment (start 125.59996 130.59996) (end 125.59996 127.011038) (width 0.15) (layer "F.Cu") (net 129))
  (segment (start 125.59996 130.59996) (end 125.59996 132.64994) (width 0.15) (layer "F.Cu") (net 129))
  (segment (start 125.59996 132.64994) (end 126.03752 133.0875) (width 0.15) (layer "F.Cu") (net 129))
  (segment (start 118.944352 126.50004) (end 117.99996 125.555648) (width 0.15) (layer "F.Cu") (net 129))
  (segment (start 98.75 119.55) (end 99 119.8) (width 0.15) (layer "F.Cu") (net 129))
  (segment (start 125.6 130.6) (end 125.59996 130.59996) (width 0.15) (layer "F.Cu") (net 129))
  (segment (start 113.344352 123.20004) (end 110.491278 120.346966) (width 0.15) (layer "F.Cu") (net 129))
  (segment (start 126.03752 133.0875) (end 127.7125 133.0875) (width 0.15) (layer "F.Cu") (net 129))
  (segment (start 117.588962 123.20004) (end 113.344352 123.20004) (width 0.15) (layer "F.Cu") (net 129))
  (segment (start 98.75 118.55) (end 98.75 119.55) (width 0.15) (layer "F.Cu") (net 129))
  (segment (start 125.088962 126.50004) (end 118.944352 126.50004) (width 0.15) (layer "F.Cu") (net 129))
  (segment (start 110.491278 120.346966) (end 110.147328 120.346966) (width 0.15) (layer "F.Cu") (net 129))
  (via (at 125.9 130.6) (size 0.6) (drill 0.25) (layers "F.Cu" "B.Cu") (net 129))
  (via (at 109.697343 119.896981) (size 0.6) (drill 0.25) (layers "F.Cu" "B.Cu") (net 129))
  (via (at 99 119.8) (size 0.6) (drill 0.25) (layers "F.Cu" "B.Cu") (net 129))
  (segment (start 108.8 119.5) (end 108.6 119.5) (width 0.15) (layer "In2.Cu") (net 129))
  (segment (start 100.4 119.5) (end 99.7 119.5) (width 0.15) (layer "In2.Cu") (net 129))
  (segment (start 100.3 119.5) (end 100.211078 119.5) (width 0.15) (layer "In2.Cu") (net 129))
  (segment (start 99.4 119.8) (end 99 119.8) (width 0.15) (layer "In2.Cu") (net 129))
  (segment (start 100.4 119.5) (end 100.2 119.5) (width 0.15) (layer "In2.Cu") (net 129))
  (segment (start 109.697343 119.896981) (end 109.196981 119.896981) (width 0.15) (layer "In2.Cu") (net 129))
  (segment (start 100.2 119.5) (end 100.3 119.5) (width 0.15) (layer "In2.Cu") (net 129))
  (segment (start 108.6 119.5) (end 100.4 119.5) (width 0.15) (layer "In2.Cu") (net 129))
  (segment (start 109.196981 119.896981) (end 108.8 119.5) (width 0.15) (layer "In2.Cu") (net 129))
  (segment (start 99.7 119.5) (end 99.4 119.8) (width 0.15) (layer "In2.Cu") (net 129))
  (segment (start 100.4 119.5) (end 100.3 119.5) (width 0.15) (layer "In2.Cu") (net 129))
  (segment (start 126.5 130.5492) (end 125.9508 130.5492) (width 0.15) (layer "B.Cu") (net 129))
  (segment (start 125.9508 130.5492) (end 125.9 130.6) (width 0.15) (layer "B.Cu") (net 129))
  (segment (start 110.377366 120.621976) (end 110.527695 120.772305) (width 0.15) (layer "F.Cu") (net 130))
  (segment (start 125.7 135.175) (end 125.45 134.925) (width 0.15) (layer "F.Cu") (net 130))
  (segment (start 125.45 133.05) (end 125.32495 132.92495) (width 0.15) (layer "F.Cu") (net 130))
  (segment (start 113.230438 123.475048) (end 110.527695 120.772305) (width 0.15) (layer "F.Cu") (net 130))
  (segment (start 117.47505 123.47505) (end 113.23044 123.47505) (width 0.15) (layer "F.Cu") (net 130))
  (segment (start 125.32495 132.92495) (end 125.32495 130.62495) (width 0.15) (layer "F.Cu") (net 130))
  (segment (start 125.32495 130.62495) (end 125.02495 130.62495) (width 0.15) (layer "F.Cu") (net 130))
  (segment (start 125.32495 130.62495) (end 125.32495 127.12495) (width 0.15) (layer "F.Cu") (net 130))
  (segment (start 98.25 118.55) (end 98.25 120.03823) (width 0.15) (layer "F.Cu") (net 130))
  (segment (start 117.72495 125.66956) (end 117.72495 123.72495) (width 0.15) (layer "F.Cu") (net 130))
  (segment (start 125.02495 130.62495) (end 125 130.6) (width 0.15) (layer "F.Cu") (net 130))
  (segment (start 125.45 134.925) (end 125.45 133.05) (width 0.15) (layer "F.Cu") (net 130))
  (segment (start 117.72495 123.72495) (end 117.47505 123.47505) (width 0.15) (layer "F.Cu") (net 130))
  (segment (start 125.32495 127.12495) (end 124.97505 126.77505) (width 0.15) (layer "F.Cu") (net 130))
  (segment (start 126.275 135.175) (end 125.7 135.175) (width 0.15) (layer "F.Cu") (net 130))
  (segment (start 118.83044 126.77505) (end 117.72495 125.66956) (width 0.15) (layer "F.Cu") (net 130))
  (segment (start 113.23044 123.47505) (end 113.230438 123.475048) (width 0.15) (layer "F.Cu") (net 130))
  (segment (start 98.25 120.03823) (end 98.6425 120.43073) (width 0.15) (layer "F.Cu") (net 130))
  (segment (start 124.97505 126.77505) (end 118.83044 126.77505) (width 0.15) (layer "F.Cu") (net 130))
  (segment (start 109.700537 120.621976) (end 110.377366 120.621976) (width 0.15) (layer "F.Cu") (net 130))
  (via (at 98.6425 120.43073) (size 0.6) (drill 0.25) (layers "F.Cu" "B.Cu") (net 130))
  (via (at 109.700537 120.621976) (size 0.6) (drill 0.25) (layers "F.Cu" "B.Cu") (net 130))
  (via (at 125 130.6) (size 0.6) (drill 0.25) (layers "F.Cu" "B.Cu") (net 130))
  (segment (start 99.16927 120.43073) (end 98.6425 120.43073) (width 0.15) (layer "In2.Cu") (net 130))
  (segment (start 99.8 119.8) (end 99.16927 120.43073) (width 0.15) (layer "In2.Cu") (net 130))
  (segment (start 108.7 119.8) (end 99.8 119.8) (width 0.15) (layer "In2.Cu") (net 130))
  (segment (start 109.700537 120.621976) (end 109.521976 120.621976) (width 0.15) (layer "In2.Cu") (net 130))
  (segment (start 109.521976 120.621976) (end 108.7 119.8) (width 0.15) (layer "In2.Cu") (net 130))
  (segment (start 124.4 130.5508) (end 124.9508 130.5508) (width 0.15) (layer "B.Cu") (net 130))
  (segment (start 124.9508 130.5508) (end 125 130.6) (width 0.15) (layer "B.Cu") (net 130))
  (segment (start 134.538164 126.147952) (end 133.903164 125.512952) (width 0.125) (layer "F.Cu") (net 131))
  (segment (start 134.538164 126.512953) (end 134.987047 126.512953) (width 0.125) (layer "F.Cu") (net 131))
  (segment (start 134.538164 126.512953) (end 134.538164 126.147952) (width 0.125) (layer "F.Cu") (net 131))
  (segment (start 133.903164 123.491425) (end 133.903164 122.491424) (width 0.125) (layer "F.Cu") (net 131))
  (segment (start 133.903164 122.491424) (end 133.903164 121.491425) (width 0.125) (layer "F.Cu") (net 131))
  (segment (start 134.987047 126.512953) (end 135.2 126.3) (width 0.125) (layer "F.Cu") (net 131))
  (segment (start 116.685 107.2) (end 116.685 108.885) (width 0.2) (layer "F.Cu") (net 131))
  (segment (start 144.875 85.4) (end 146 85.4) (width 0.2) (layer "F.Cu") (net 131))
  (segment (start 133.308576 122.491424) (end 133 122.8) (width 0.18) (layer "F.Cu") (net 131))
  (segment (start 133.903164 121.491425) (end 133.903164 123.491425) (width 0.18) (layer "F.Cu") (net 131))
  (segment (start 133.903164 122.491424) (end 133.308576 122.491424) (width 0.18) (layer "F.Cu") (net 131))
  (segment (start 95.8 138.7) (end 95.8 139.015) (width 0.2) (layer "F.Cu") (net 131))
  (segment (start 144.465 94.5) (end 144.465 93.735) (width 0.125) (layer "F.Cu") (net 131))
  (segment (start 121.865 108.35) (end 122.315 108.8) (width 0.2) (layer "F.Cu") (net 131))
  (segment (start 102.749174 102.257733) (end 102.291 101.799559) (width 0.25) (layer "F.Cu") (net 131))
  (segment (start 132.372 131.375) (end 132.372 132.372) (width 0.25) (layer "F.Cu") (net 131))
  (segment (start 114.265 109.4) (end 114.265 108.815) (width 0.2) (layer "F.Cu") (net 131))
  (segment (start 123.285 107.8) (end 123.95 107.8) (width 0.2) (layer "F.Cu") (net 131))
  (segment (start 95.585 145.315) (end 95.6 145.3) (width 0.2) (layer "F.Cu") (net 131))
  (segment (start 94.7 145.315) (end 95.585 145.315) (width 0.2) (layer "F.Cu") (net 131))
  (segment (start 114.265 108.815) (end 114.15 108.7) (width 0.2) (layer "F.Cu") (net 131))
  (segment (start 114.05 108.6) (end 114.15 108.7) (width 0.2) (layer "F.Cu") (net 131))
  (segment (start 144.465 93.735) (end 144.6 93.6) (width 0.15) (layer "F.Cu") (net 131))
  (segment (start 95.8 139.015) (end 96.1 139.315) (width 0.2) (layer "F.Cu") (net 131))
  (segment (start 132.372 132.372) (end 132.4 132.4) (width 0.25) (layer "F.Cu") (net 131))
  (segment (start 94.8 144.375) (end 94.7 144.475) (width 0.2) (layer "F.Cu") (net 131))
  (segment (start 147.528 121) (end 147.528 122.972) (width 0.25) (layer "F.Cu") (net 131))
  (segment (start 72.05 109.35) (end 72.2 109.2) (width 0.2) (layer "F.Cu") (net 131))
  (segment (start 116.685 108.2) (end 116.685 108.885) (width 0.15) (layer "F.Cu") (net 131))
  (segment (start 147.528 122.972) (end 147 123.5) (width 0.25) (layer "F.Cu") (net 131))
  (segment (start 123.285 107.83) (end 122.315 108.8) (width 0.2) (layer "F.Cu") (net 131))
  (segment (start 121.19 108.35) (end 121.865 108.35) (width 0.2) (layer "F.Cu") (net 131))
  (segment (start 116.685 107.2) (end 116.685 108.2) (width 0.15) (layer "F.Cu") (net 131))
  (segment (start 114.05 107.995) (end 114.05 108.6) (width 0.2) (layer "F.Cu") (net 131))
  (segment (start 147 123.5) (end 146.25 123.5) (width 0.25) (layer "F.Cu") (net 131))
  (segment (start 72.05 109.865) (end 72.05 109.35) (width 0.2) (layer "F.Cu") (net 131))
  (segment (start 116.685 108.885) (end 116.7 108.9) (width 0.2) (layer "F.Cu") (net 131))
  (segment (start 144.465 94.4) (end 144.465 93.735) (width 0.15) (layer "F.Cu") (net 131))
  (segment (start 94.8 143.825) (end 94.8 144.375) (width 0.2) (layer "F.Cu") (net 131))
  (segment (start 123.285 107.8) (end 123.285 106.8) (width 0.2) (layer "F.Cu") (net 131))
  (segment (start 94.7 144.475) (end 94.7 145.315) (width 0.2) (layer "F.Cu") (net 131))
  (via (at 102.749174 102.257733) (size 0.6) (drill 0.25) (layers "F.Cu" "B.Cu") (net 131))
  (via (at 135.2 126.3) (size 0.6) (drill 0.25) (layers "F.Cu" "B.Cu") (net 131))
  (via (at 114.15 108.7) (size 0.6) (drill 0.25) (layers "F.Cu" "B.Cu") (net 131))
  (via (at 146 85.4) (size 0.6) (drill 0.25) (layers "F.Cu" "B.Cu") (net 131))
  (via (at 137.25 107.15) (size 0.6) (drill 0.25) (layers "F.Cu" "B.Cu") (net 131))
  (via (at 133.901055 106.581055) (size 0.6) (drill 0.25) (layers "F.Cu" "B.Cu") (net 131))
  (via (at 81.2 112) (size 0.6) (drill 0.25) (layers "F.Cu" "B.Cu") (net 131))
  (via (at 81.2 111.4) (size 0.6) (drill 0.25) (layers "F.Cu" "B.Cu") (net 131))
  (via (at 144.6 93.6) (size 0.6) (drill 0.25) (layers "F.Cu" "B.Cu") (net 131))
  (via (at 133 134.2) (size 0.6) (drill 0.25) (layers "F.Cu" "B.Cu") (net 131))
  (via (at 121.8 114.4) (size 0.6) (drill 0.25) (layers "F.Cu" "B.Cu") (net 131))
  (via (at 112.6 133.2) (size 0.6) (drill 0.25) (layers "F.Cu" "B.Cu") (net 131))
  (via (at 82.4 111.4) (size 0.6) (drill 0.25) (layers "F.Cu" "B.Cu") (net 131))
  (via (at 81.2 110.8) (size 0.6) (drill 0.25) (layers "F.Cu" "B.Cu") (net 131))
  (via (at 138.5 131.75) (size 0.6) (drill 0.25) (layers "F.Cu" "B.Cu") (net 131))
  (via (at 149.5 137.1) (size 0.6) (drill 0.25) (layers "F.Cu" "B.Cu") (net 131))
  (via (at 72.2 109.2) (size 0.6) (drill 0.25) (layers "F.Cu" "B.Cu") (net 131))
  (via (at 95.8 138.7) (size 0.6) (drill 0.25) (layers "F.Cu" "B.Cu") (net 131))
  (via (at 146.25 123.5) (size 0.6) (drill 0.25) (layers "F.Cu" "B.Cu") (net 131))
  (via (at 81.8 110.8) (size 0.6) (drill 0.25) (layers "F.Cu" "B.Cu") (net 131))
  (via (at 116.2 131) (size 0.6) (drill 0.25) (layers "F.Cu" "B.Cu") (net 131))
  (via (at 116.7 108.9) (size 0.6) (drill 0.25) (layers "F.Cu" "B.Cu") (net 131))
  (via (at 135.3 148.4) (size 0.6) (drill 0.25) (layers "F.Cu" "B.Cu") (net 131))
  (via (at 132.4 132.4) (size 0.6) (drill 0.25) (layers "F.Cu" "B.Cu") (net 131))
  (via (at 82.4 110.8) (size 0.6) (drill 0.25) (layers "F.Cu" "B.Cu") (net 131))
  (via (at 118.9 133.1) (size 0.6) (drill 0.25) (layers "F.Cu" "B.Cu") (net 131))
  (via (at 119.7 91.5) (size 0.6) (drill 0.25) (layers "F.Cu" "B.Cu") (net 131))
  (via (at 149.5 136.5) (size 0.6) (drill 0.25) (layers "F.Cu" "B.Cu") (net 131))
  (via (at 138.9 98.5) (size 0.6) (drill 0.25) (layers "F.Cu" "B.Cu") (net 131))
  (via (at 133 122.8) (size 0.6) (drill 0.25) (layers "F.Cu" "B.Cu") (net 131))
  (via (at 119.1 91.5) (size 0.6) (drill 0.25) (layers "F.Cu" "B.Cu") (net 131))
  (via (at 95.6 145.3) (size 0.6) (drill 0.25) (layers "F.Cu" "B.Cu") (net 131))
  (via (at 82.4 112) (size 0.6) (drill 0.25) (layers "F.Cu" "B.Cu") (net 131))
  (via (at 81.8 112) (size 0.6) (drill 0.25) (layers "F.Cu" "B.Cu") (net 131))
  (via (at 123.95 107.8) (size 0.6) (drill 0.25) (layers "F.Cu" "B.Cu") (net 131))
  (via (at 81.8 111.4) (size 0.6) (drill 0.25) (layers "F.Cu" "B.Cu") (net 131))
  (segment (start 102.034174 102.257734) (end 102.749174 102.257733) (width 0.2) (layer "B.Cu") (net 131))
  (segment (start 136.15 148.425) (end 135.325 148.425) (width 0.2) (layer "B.Cu") (net 131))
  (segment (start 135.3 146.385) (end 135.65 146.035) (width 0.15) (layer "B.Cu") (net 131))
  (segment (start 133.8 106.68211) (end 133.8 107.305) (width 0.15) (layer "B.Cu") (net 131))
  (segment (start 121.785 114.385) (end 121.8 114.4) (width 0.2) (layer "B.Cu") (net 131))
  (segment (start 113.5 133.25) (end 112.65 133.25) (width 0.2) (layer "B.Cu") (net 131))
  (segment (start 135.2 126.3) (end 134.690212 126.3) (width 0.25) (layer "B.Cu") (net 131))
  (segment (start 134.690212 126.3) (end 133.888164 125.497952) (width 0.25) (layer "B.Cu") (net 131))
  (segment (start 133.901055 106.581055) (end 133.8 106.68211) (width 0.15) (layer "B.Cu") (net 131))
  (segment (start 118 133.25) (end 118.75 133.25) (width 0.2) (layer "B.Cu") (net 131))
  (segment (start 138.5 131.75) (end 139.5125 130.65) (width 0.25) (layer "B.Cu") (net 131))
  (segment (start 134.015 106.46711) (end 134.015 105.95) (width 0.15) (layer "B.Cu") (net 131))
  (segment (start 102.749173 102.257734) (end 102.749174 102.257733) (width 0.25) (layer "B.Cu") (net 131))
  (segment (start 135.3 148.4) (end 135.3 146.385) (width 0.15) (layer "B.Cu") (net 131))
  (segment (start 120.8 114.385) (end 121.785 114.385) (width 0.2) (layer "B.Cu") (net 131))
  (segment (start 133.901055 106.581055) (end 134.015 106.46711) (width 0.15) (layer "B.Cu") (net 131))
  (segment (start 120.8 115.415) (end 121.8 115.415) (width 0.2) (layer "B.Cu") (net 131))
  (segment (start 139.25 98.85) (end 138.9 98.5) (width 0.15) (layer "B.Cu") (net 131))
  (segment (start 135.325 148.425) (end 135.3 148.4) (width 0.2) (layer "B.Cu") (net 131))
  (segment (start 136.585 107.15) (end 137.25 107.15) (width 0.2) (layer "B.Cu") (net 131))
  (segment (start 133 133.5) (end 133 134.2) (width 0.2) (layer "B.Cu") (net 131))
  (segment (start 116.2 131) (end 116.2 130.485) (width 0.2) (layer "B.Cu") (net 131))
  (segment (start 118.75 133.25) (end 118.9 133.1) (width 0.2) (layer "B.Cu") (net 131))
  (segment (start 140.7 93.515) (end 139.7 93.515) (width 0.15) (layer "B.Cu") (net 131))
  (segment (start 116 132.15) (end 116 131.2) (width 0.2) (layer "B.Cu") (net 131))
  (segment (start 116 131.2) (end 116.2 131) (width 0.2) (layer "B.Cu") (net 131))
  (segment (start 136.585 107.15) (end 136.585 108.15) (width 0.2) (layer "B.Cu") (net 131))
  (segment (start 102.034173 102.257734) (end 102.749173 102.257734) (width 0.25) (layer "B.Cu") (net 131))
  (segment (start 121.8 115.415) (end 121.8 114.4) (width 0.2) (layer "B.Cu") (net 131))
  (segment (start 112.65 133.25) (end 112.6 133.2) (width 0.2) (layer "B.Cu") (net 131))
  (segment (start 118.9 133.1) (end 119.515 133.1) (width 0.2) (layer "B.Cu") (net 131))
  (segment (start 141.335 92.88) (end 140.7 93.515) (width 0.15) (layer "B.Cu") (net 131))
  (segment (start 139.73 98.85) (end 139.25 98.85) (width 0.15) (layer "B.Cu") (net 131))
  (segment (start 141.335 91.9) (end 141.335 92.88) (width 0.15) (layer "B.Cu") (net 131))
  (segment (start 112.6 133.2) (end 111.985 133.2) (width 0.2) (layer "B.Cu") (net 131))
  (segment (start 113.55 107.995) (end 113.55 108.55) (width 0.15) (layer "F.Cu") (net 132))
  (segment (start 102.849174 108.325826) (end 102.475 108.7) (width 0.3) (layer "F.Cu") (net 132))
  (segment (start 130.685 122.785) (end 129.8 121.9) (width 0.3) (layer "F.Cu") (net 132))
  (segment (start 120.4 120.3) (end 116.2 120.3) (width 0.3) (layer "F.Cu") (net 132))
  (segment (start 126.2 102.8) (end 126.2 106.7) (width 0.3) (layer "F.Cu") (net 132))
  (segment (start 126.6 107.1) (end 129.9 107.1) (width 0.3) (layer "F.Cu") (net 132))
  (segment (start 133.1769 105.3231) (end 134.5 104) (width 0.15) (layer "F.Cu") (net 132))
  (segment (start 101.75 112.45) (end 101.75 113.45) (width 0.3) (layer "F.Cu") (net 132))
  (segment (start 102.849174 103.257734) (end 102.849174 108.324174) (width 0.3) (layer "F.Cu") (net 132))
  (segment (start 132.7 126.3) (end 132.7 125.686116) (width 0.2) (layer "F.Cu") (net 132))
  (segment (start 133.463164 126.337953) (end 133.463164 126.463164) (width 0.15) (layer "F.Cu") (net 132))
  (segment (start 133.888164 126.512953) (end 133.238164 126.512953) (width 0.2) (layer "F.Cu") (net 132))
  (segment (start 116.2 120.3) (end 115.485 120.3) (width 0.3) (layer "F.Cu") (net 132))
  (segment (start 113.335 109.4) (end 113.335 108.765) (width 0.2) (layer "F.Cu") (net 132))
  (segment (start 122.3 102.2) (end 125.6 102.2) (width 0.3) (layer "F.Cu") (net 132))
  (segment (start 103.25 108.7) (end 102.475 108.7) (width 0.3) (layer "F.Cu") (net 132))
  (segment (start 102.849174 108.324174) (end 102.849174 108.325826) (width 0.3) (layer "F.Cu") (net 132))
  (segment (start 132.888164 125.497952) (end 132.202048 125.497952) (width 0.3) (layer "F.Cu") (net 132))
  (segment (start 101.75 113.45) (end 101.6 113.6) (width 0.3) (layer "F.Cu") (net 132))
  (segment (start 133.238164 126.512953) (end 132.912953 126.512953) (width 0.2) (layer "F.Cu") (net 132))
  (segment (start 102.849174 108.324174) (end 102.849174 108.674174) (width 0.3) (layer "F.Cu") (net 132))
  (segment (start 131.1 122.785) (end 131.1 124.395904) (width 0.3) (layer "F.Cu") (net 132))
  (segment (start 92.365 129) (end 92.365 125.315) (width 0.3) (layer "F.Cu") (net 132))
  (segment (start 115.485 120.3) (end 115.485 121.3) (width 0.15) (layer "F.Cu") (net 132))
  (segment (start 92.365 125.315) (end 92.35 125.3) (width 0.3) (layer "F.Cu") (net 132))
  (segment (start 125.6 102.2) (end 126.2 102.8) (width 0.3) (layer "F.Cu") (net 132))
  (segment (start 134.5 104) (end 136.715 104) (width 0.15) (layer "F.Cu") (net 132))
  (segment (start 113.55 108.55) (end 113.4 108.7) (width 0.2) (layer "F.Cu") (net 132))
  (segment (start 131.1 124.395904) (end 132.202048 125.497952) (width 0.3) (layer "F.Cu") (net 132))
  (segment (start 132.912953 126.512953) (end 132.7 126.3) (width 0.2) (layer "F.Cu") (net 132))
  (segment (start 102.1 108.7) (end 102.475 108.7) (width 0.3) (layer "F.Cu") (net 132))
  (segment (start 126.2 106.7) (end 126.6 107.1) (width 0.3) (layer "F.Cu") (net 132))
  (segment (start 92.365 126) (end 92.365 125.315) (width 0.2) (layer "F.Cu") (net 132))
  (segment (start 103.25 108.7) (end 113.4 108.7) (width 0.3) (layer "F.Cu") (net 132))
  (segment (start 129.8 121.9) (end 122 121.9) (width 0.3) (layer "F.Cu") (net 132))
  (segment (start 101.25 112.45) (end 101.25 109.55) (width 0.3) (layer "F.Cu") (net 132))
  (segment (start 122 121.9) (end 120.4 120.3) (width 0.3) (layer "F.Cu") (net 132))
  (segment (start 100.75 112.45) (end 100.75 113.55) (width 0.3) (layer "F.Cu") (net 132))
  (segment (start 100.75 113.55) (end 100.8 113.6) (width 0.3) (layer "F.Cu") (net 132))
  (segment (start 92.365 129) (end 92.365 126) (width 0.2) (layer "F.Cu") (net 132))
  (segment (start 101.25 109.55) (end 102.1 108.7) (width 0.3) (layer "F.Cu") (net 132))
  (segment (start 131.1 122.785) (end 130.685 122.785) (width 0.3) (layer "F.Cu") (net 132))
  (segment (start 113.55 107.405) (end 113.55 108.55) (width 0.2) (layer "F.Cu") (net 132))
  (segment (start 133.1769 106.603507) (end 133.1769 105.3231) (width 0.15) (layer "F.Cu") (net 132))
  (segment (start 103.225 108.7) (end 102.849174 108.324174) (width 0.3) (layer "F.Cu") (net 132))
  (segment (start 113.335 108.765) (end 113.4 108.7) (width 0.2) (layer "F.Cu") (net 132))
  (via (at 102.849174 103.257734) (size 0.6) (drill 0.25) (layers "F.Cu" "B.Cu") (net 132))
  (via (at 113.4 108.7) (size 0.6) (drill 0.25) (layers "F.Cu" "B.Cu") (net 132))
  (via (at 133.1769 106.603507) (size 0.6) (drill 0.25) (layers "F.Cu" "B.Cu") (net 132))
  (via (at 116.2 116.7) (size 0.6) (drill 0.25) (layers "F.Cu" "B.Cu") (net 132))
  (via (at 100.8 113.6) (size 0.6) (drill 0.25) (layers "F.Cu" "B.Cu") (net 132))
  (via (at 122.3 102.2) (size 0.6) (drill 0.25) (layers "F.Cu" "B.Cu") (net 132))
  (via (at 116.9 114.75) (size 0.6) (drill 0.25) (layers "F.Cu" "B.Cu") (net 132))
  (via (at 116.2 120.3) (size 0.6) (drill 0.25) (layers "F.Cu" "B.Cu") (net 132))
  (via (at 101.6 113.6) (size 0.6) (drill 0.25) (layers "F.Cu" "B.Cu") (net 132))
  (via (at 92.35 125.3) (size 0.6) (drill 0.25) (layers "F.Cu" "B.Cu") (net 132))
  (via (at 150.5 143.2) (size 0.6) (drill 0.25) (layers "F.Cu" "B.Cu") (net 132))
  (via (at 96 97.5) (size 0.6) (drill 0.25) (layers "F.Cu" "B.Cu") (net 132))
  (via (at 129.9 107.1) (size 0.6) (drill 0.25) (layers "F.Cu" "B.Cu") (net 132))
  (via (at 132.202048 125.497952) (size 0.6) (drill 0.25) (layers "F.Cu" "B.Cu") (net 132))
  (segment (start 135.2 139.8) (end 134.8 139.4) (width 0.15) (layer "In2.Cu") (net 132))
  (segment (start 147.2 139.8) (end 135.2 139.8) (width 0.15) (layer "In2.Cu") (net 132))
  (segment (start 134.6 133.8) (end 133.6 133.8) (width 0.15) (layer "In2.Cu") (net 132))
  (segment (start 133.297952 125.497952) (end 132.202048 125.497952) (width 0.15) (layer "In2.Cu") (net 132))
  (segment (start 95.8 113.2) (end 95.4 113.6) (width 0.25) (layer "In2.Cu") (net 132))
  (segment (start 92.9 121) (end 95 121) (width 0.25) (layer "In2.Cu") (net 132))
  (segment (start 92.35 121.55) (end 92.9 121) (width 0.25) (layer "In2.Cu") (net 132))
  (segment (start 99.7 113.2) (end 95.8 113.2) (width 0.25) (layer "In2.Cu") (net 132))
  (segment (start 92.35 125.3) (end 92.35 121.55) (width 0.25) (layer "In2.Cu") (net 132))
  (segment (start 133.4 133.6) (end 133.4 125.6) (width 0.15) (layer "In2.Cu") (net 132))
  (segment (start 95.4 113.6) (end 95.4 120.6) (width 0.25) (layer "In2.Cu") (net 132))
  (segment (start 134.8 134) (end 134.6 133.8) (width 0.15) (layer "In2.Cu") (net 132))
  (segment (start 133.4 125.6) (end 133.297952 125.497952) (width 0.15) (layer "In2.Cu") (net 132))
  (segment (start 100.1 113.6) (end 99.7 113.2) (width 0.25) (layer "In2.Cu") (net 132))
  (segment (start 147.6 142.8) (end 147.6 140.2) (width 0.15) (layer "In2.Cu") (net 132))
  (segment (start 134.8 139.4) (end 134.8 134) (width 0.15) (layer "In2.Cu") (net 132))
  (segment (start 147.6 140.2) (end 147.2 139.8) (width 0.15) (layer "In2.Cu") (net 132))
  (segment (start 95 121) (end 95.4 120.6) (width 0.25) (layer "In2.Cu") (net 132))
  (segment (start 133.6 133.8) (end 133.4 133.6) (width 0.15) (layer "In2.Cu") (net 132))
  (segment (start 150.5 143.2) (end 148 143.2) (width 0.15) (layer "In2.Cu") (net 132))
  (segment (start 100.8 113.6) (end 100.1 113.6) (width 0.25) (layer "In2.Cu") (net 132))
  (segment (start 148 143.2) (end 147.6 142.8) (width 0.15) (layer "In2.Cu") (net 132))
  (segment (start 101.6 115) (end 101.6 113.6) (width 0.3) (layer "In3.Cu") (net 132))
  (segment (start 116.9 114.75) (end 116.9 116) (width 0.3) (layer "In3.Cu") (net 132))
  (segment (start 113.550737 109.275001) (end 115.173997 109.275001) (width 0.3) (layer "In3.Cu") (net 132))
  (segment (start 98.1 101.5) (end 97.7 101.1) (width 0.2) (layer "In3.Cu") (net 132))
  (segment (start 97.7 101.1) (end 97.7 98.5) (width 0.2) (layer "In3.Cu") (net 132))
  (segment (start 102.4 115.8) (end 101.6 115) (width 0.3) (layer "In3.Cu") (net 132))
  (segment (start 101.657734 103.257734) (end 101.3 102.9) (width 0.2) (layer "In3.Cu") (net 132))
  (segment (start 96.7 97.5) (end 96 97.5) (width 0.2) (layer "In3.Cu") (net 132))
  (segment (start 113.4 108.7) (end 113.4 109.124264) (width 0.3) (layer "In3.Cu") (net 132))
  (segment (start 116.9 116) (end 116.2 116.7) (width 0.3) (layer "In3.Cu") (net 132))
  (segment (start 115.173997 109.275001) (end 117.923999 106.524999) (width 0.3) (layer "In3.Cu") (net 132))
  (segment (start 126.302001 106.524999) (end 126.877002 107.1) (width 0.3) (layer "In3.Cu") (net 132))
  (segment (start 116.2 116.7) (end 114.3 116.7) (width 0.3) (layer "In3.Cu") (net 132))
  (segment (start 116.2 116.7) (end 116.2 120.3) (width 0.3) (layer "In3.Cu") (net 132))
  (segment (start 101.3 101.9) (end 100.9 101.5) (width 0.2) (layer "In3.Cu") (net 132))
  (segment (start 117.923999 106.524999) (end 126.302001 106.524999) (width 0.3) (layer "In3.Cu") (net 132))
  (segment (start 100.9 101.5) (end 98.1 101.5) (width 0.2) (layer "In3.Cu") (net 132))
  (segment (start 114.3 116.7) (end 113.4 115.8) (width 0.3) (layer "In3.Cu") (net 132))
  (segment (start 113.4 109.124264) (end 113.550737 109.275001) (width 0.3) (layer "In3.Cu") (net 132))
  (segment (start 102.849174 103.257734) (end 101.657734 103.257734) (width 0.2) (layer "In3.Cu") (net 132))
  (segment (start 113.4 115.8) (end 102.4 115.8) (width 0.3) (layer "In3.Cu") (net 132))
  (segment (start 129.9 107.1) (end 126.877002 107.1) (width 0.3) (layer "In3.Cu") (net 132))
  (segment (start 101.3 102.9) (end 101.3 101.9) (width 0.2) (layer "In3.Cu") (net 132))
  (segment (start 97.7 98.5) (end 96.7 97.5) (width 0.2) (layer "In3.Cu") (net 132))
  (segment (start 102.034174 103.257734) (end 102.849174 103.257734) (width 0.2) (layer "B.Cu") (net 132))
  (segment (start 103.049173 101.257734) (end 102.034174 101.257734) (width 0.2) (layer "B.Cu") (net 132))
  (segment (start 103.349173 101.557734) (end 103.049173 101.257734) (width 0.2) (layer "B.Cu") (net 132))
  (segment (start 103.349174 103.057734) (end 103.349173 101.557734) (width 0.2) (layer "B.Cu") (net 132))
  (segment (start 103.149174 103.257734) (end 103.349174 103.057734) (width 0.2) (layer "B.Cu") (net 132))
  (segment (start 102.849174 103.257734) (end 103.149174 103.257734) (width 0.2) (layer "B.Cu") (net 132))
  (segment (start 96.015 97.515) (end 96 97.5) (width 0.125) (layer "B.Cu") (net 132))
  (segment (start 131 109.6) (end 132.8 109.6) (width 0.25) (layer "B.Cu") (net 132))
  (segment (start 96.8 97.515) (end 96.015 97.515) (width 0.125) (layer "B.Cu") (net 132))
  (segment (start 133.1769 106.603507) (end 133.1769 106.0419) (width 0.2) (layer "B.Cu") (net 132))
  (segment (start 116.9 116.685) (end 116.215 116.685) (width 0.2) (layer "B.Cu") (net 132))
  (segment (start 117.85 116.85) (end 117.065 116.85) (width 0.2) (layer "B.Cu") (net 132))
  (segment (start 130.515 108.1) (end 130.515 109.115) (width 0.25) (layer "B.Cu") (net 132))
  (segment (start 133.1769 106.603507) (end 133.3 106.726607) (width 0.3) (layer "B.Cu") (net 132))
  (segment (start 121.9 94.285) (end 121.9 101.8) (width 0.15) (layer "B.Cu") (net 132))
  (segment (start 130.515 107.1) (end 129.9 107.1) (width 0.2) (layer "B.Cu") (net 132))
  (segment (start 121.9 101.8) (end 122.3 102.2) (width 0.15) (layer "B.Cu") (net 132))
  (segment (start 133.249999 109.150001) (end 133.249999 107.945001) (width 0.25) (layer "B.Cu") (net 132))
  (segment (start 130.515 109.115) (end 131 109.6) (width 0.25) (layer "B.Cu") (net 132))
  (segment (start 116.9 114.085) (end 116.9 114.75) (width 0.2) (layer "B.Cu") (net 132))
  (segment (start 132.8 109.6) (end 133.249999 109.150001) (width 0.25) (layer "B.Cu") (net 132))
  (segment (start 133.249999 107.945001) (end 133.3 107.895) (width 0.25) (layer "B.Cu") (net 132))
  (segment (start 130.515 108.1) (end 130.515 107.1) (width 0.2) (layer "B.Cu") (net 132))
  (segment (start 116.215 116.685) (end 116.2 116.7) (width 0.2) (layer "B.Cu") (net 132))
  (segment (start 117.065 114.25) (end 116.9 114.085) (width 0.2) (layer "B.Cu") (net 132))
  (segment (start 117.795 114.25) (end 117.01 114.25) (width 0.2) (layer "B.Cu") (net 132))
  (segment (start 133.3 106.726607) (end 133.3 107.895) (width 0.3) (layer "B.Cu") (net 132))
  (segment (start 151 143.7) (end 150.5 143.2) (width 0.15) (layer "B.Cu") (net 132))
  (segment (start 139.515 141.5) (end 139.1 141.5) (width 0.2) (layer "F.Cu") (net 133))
  (segment (start 71.115 117.885) (end 71.115 117.985) (width 0.155) (layer "F.Cu") (net 133))
  (segment (start 138.9 142.3) (end 138.9 142) (width 0.2) (layer "F.Cu") (net 133))
  (segment (start 137.1 143.9) (end 137.75 143.25) (width 0.3) (layer "F.Cu") (net 133))
  (segment (start 153.95 141.15) (end 153.95 142) (width 0.2) (layer "F.Cu") (net 133))
  (segment (start 139.1 142.5) (end 138.9 142.3) (width 0.2) (layer "F.Cu") (net 133))
  (segment (start 153.95 141.25) (end 153.95 141.15) (width 0.2) (layer "F.Cu") (net 133))
  (segment (start 153.95 137.35) (end 153.95 138.2) (width 0.2) (layer "F.Cu") (net 133))
  (segment (start 139.515 142.5) (end 139.1 142.5) (width 0.2) (layer "F.Cu") (net 133))
  (segment (start 90.265 131.6) (end 89.6 131.6) (width 0.15) (layer "F.Cu") (net 133))
  (segment (start 111.9 138.5) (end 111.9 137.7) (width 0.2) (layer "F.Cu") (net 133))
  (segment (start 138.9 141.7) (end 138.9 142) (width 0.2) (layer "F.Cu") (net 133))
  (segment (start 111.1 138.75) (end 111.65 138.75) (width 0.2) (layer "F.Cu") (net 133))
  (segment (start 153.95 137.45) (end 153.95 137.35) (width 0.2) (layer "F.Cu") (net 133))
  (segment (start 153.95 133.65) (end 153.95 133.55) (width 0.2) (layer "F.Cu") (net 133))
  (segment (start 111.65 138.75) (end 111.9 138.5) (width 0.2) (layer "F.Cu") (net 133))
  (segment (start 90.265 132.65) (end 89.6 132.65) (width 0.15) (layer "F.Cu") (net 133))
  (segment (start 71.115 117.985) (end 71.115 117.3) (width 0.155) (layer "F.Cu") (net 133))
  (segment (start 139.1 141.5) (end 138.9 141.7) (width 0.2) (layer "F.Cu") (net 133))
  (segment (start 153.95 133.55) (end 153.95 134.4) (width 0.2) (layer "F.Cu") (net 133))
  (via (at 108.8 142) (size 0.6) (drill 0.25) (layers "F.Cu" "B.Cu") (net 133))
  (via (at 108.05 142) (size 0.6) (drill 0.25) (layers "F.Cu" "B.Cu") (net 133))
  (via (at 108.05 141.25) (size 0.6) (drill 0.25) (layers "F.Cu" "B.Cu") (net 133))
  (via (at 108.8 141.25) (size 0.6) (drill 0.25) (layers "F.Cu" "B.Cu") (net 133))
  (via (at 124.6 132.6) (size 0.6) (drill 0.25) (layers "F.Cu" "B.Cu") (net 133))
  (via (at 123.9 132.6) (size 0.6) (drill 0.25) (layers "F.Cu" "B.Cu") (net 133))
  (via (at 81.2 118) (size 0.6) (drill 0.25) (layers "F.Cu" "B.Cu") (net 133))
  (via (at 81.8 118) (size 0.6) (drill 0.25) (layers "F.Cu" "B.Cu") (net 133))
  (via (at 83 118.6) (size 0.6) (drill 0.25) (layers "F.Cu" "B.Cu") (net 133))
  (via (at 153.95 133.65) (size 0.6) (drill 0.25) (layers "F.Cu" "B.Cu") (net 133))
  (via (at 120.65 105.6) (size 0.6) (drill 0.25) (layers "F.Cu" "B.Cu") (net 133))
  (via (at 88.94795 116.617803) (size 0.6) (drill 0.25) (layers "F.Cu" "B.Cu") (net 133))
  (via (at 125.8 123.8) (size 0.6) (drill 0.25) (layers "F.Cu" "B.Cu") (free) (net 133))
  (via (at 121.25 105) (size 0.6) (drill 0.25) (layers "F.Cu" "B.Cu") (net 133))
  (via (at 81.2 118.6) (size 0.6) (drill 0.25) (layers "F.Cu" "B.Cu") (net 133))
  (via (at 81.2 117.4) (size 0.6) (drill 0.25) (layers "F.Cu" "B.Cu") (net 133))
  (via (at 122.7 129.3) (size 0.6) (drill 0.25) (layers "F.Cu" "B.Cu") (net 133))
  (via (at 153.95 141.25) (size 0.6) (drill 0.25) (layers "F.Cu" "B.Cu") (net 133))
  (via (at 81.2 116.8) (size 0.6) (drill 0.25) (layers "F.Cu" "B.Cu") (net 133))
  (via (at 117.35 88.2) (size 0.6) (drill 0.25) (layers "F.Cu" "B.Cu") (net 133))
  (via (at 81.8 117.4) (size 0.6) (drill 0.25) (layers "F.Cu" "B.Cu") (net 133))
  (via (at 126.4 123.8) (size 0.6) (drill 0.25) (layers "F.Cu" "B.Cu") (net 133))
  (via (at 81.8 118.6) (size 0.6) (drill 0.25) (layers "F.Cu" "B.Cu") (net 133))
  (via (at 120.05 105.6) (size 0.6) (drill 0.25) (layers "F.Cu" "B.Cu") (net 133))
  (via (at 71.115 117.885) (size 0.6) (drill 0.25) (layers "F.Cu" "B.Cu") (net 133))
  (via (at 89.6 132.65) (size 0.6) (drill 0.25) (layers "F.Cu" "B.Cu") (net 133))
  (via (at 138.9 142) (size 0.6) (drill 0.25) (layers "F.Cu" "B.Cu") (net 133))
  (via (at 121.25 105.6) (size 0.6) (drill 0.25) (layers "F.Cu" "B.Cu") (net 133))
  (via (at 125.2 124.2) (size 0.6) (drill 0.25) (layers "F.Cu" "B.Cu") (net 133))
  (via (at 120.65 105) (size 0.6) (drill 0.25) (layers "F.Cu" "B.Cu") (net 133))
  (via (at 125.2 124.8) (size 0.6) (drill 0.25) (layers "F.Cu" "B.Cu") (net 133))
  (via (at 120.05 105) (size 0.6) (drill 0.25) (layers "F.Cu" "B.Cu") (net 133))
  (via (at 82.4 118) (size 0.6) (drill 0.25) (layers "F.Cu" "B.Cu") (net 133))
  (via (at 153.95 137.45) (size 0.6) (drill 0.25) (layers "F.Cu" "B.Cu") (net 133))
  (via (at 116.75 88.2) (size 0.6) (drill 0.25) (layers "F.Cu" "B.Cu") (net 133))
  (via (at 137.75 143.25) (size 0.6) (drill 0.25) (layers "F.Cu" "B.Cu") (net 133))
  (via (at 82.4 118.6) (size 0.6) (drill 0.25) (layers "F.Cu" "B.Cu") (net 133))
  (via (at 89.6 131.6) (size 0.6) (drill 0.25) (layers "F.Cu" "B.Cu") (net 133))
  (via (at 111.9 137.7) (size 0.6) (drill 0.25) (layers "F.Cu" "B.Cu") (net 133))
  (segment (start 71.115 117.885) (end 81.085 117.885) (width 0.15) (layer "In2.Cu") (net 133))
  (segment (start 81.085 117.885) (end 81.2 118) (width 0.15) (layer "In2.Cu") (net 133))
  (segment (start 119.5 106.15) (end 120.05 105.6) (width 0.2) (layer "B.Cu") (net 133))
  (segment (start 123.4 128.6) (end 122.7 129.3) (width 0.15) (layer "B.Cu") (net 133))
  (segment (start 89.817803 116.617803) (end 90 116.8) (width 0.15) (layer "B.Cu") (net 133))
  (segment (start 117.25 88.05) (end 117.25 86.9) (width 0.3) (layer "B.Cu") (net 133))
  (segment (start 117.35 88.2) (end 117.25 88.05) (width 0.3) (layer "B.Cu") (net 133))
  (segment (start 111.035 138.565) (end 111.9 137.7) (width 0.2) (layer "B.Cu") (net 133))
  (segment (start 123.4 128.2) (end 123.4 128.6) (width 0.15) (layer "B.Cu") (net 133))
  (segment (start 112 140.415) (end 108.865 140.415) (width 0.25) (layer "B.Cu") (net 133))
  (segment (start 90 116.8) (end 90 119.2) (width 0.15) (layer "B.Cu") (net 133))
  (segment (start 116.75 88.05) (end 116.75 86.9) (width 0.3) (layer "B.Cu") (net 133))
  (segment (start 88.94795 116.617803) (end 89.817803 116.617803) (width 0.15) (layer "B.Cu") (net 133))
  (segment (start 83.1508 118.7508) (end 83 118.6) (width 0.125) (layer "B.Cu") (net 133))
  (segment (start 116.75 88.2) (end 116.75 88.05) (width 0.3) (layer "B.Cu") (net 133))
  (segment (start 111.1 137.7) (end 111.1 138.1) (width 0.155) (layer "F.Cu") (net 134))
  (segment (start 111.1 137.45) (end 111.1 137.7) (width 0.155) (layer "F.Cu") (net 134))
  (segment (start 111.1 137.45) (end 111.1 136.7) (width 0.15) (layer "F.Cu") (net 134))
  (segment (start 111.4 136.4) (end 111.1 136.7) (width 0.15) (layer "F.Cu") (net 134))
  (segment (start 111.275 137.675) (end 111.125 137.675) (width 0.15) (layer "F.Cu") (net 134))
  (segment (start 111.7 136.4) (end 111.4 136.4) (width 0.15) (layer "F.Cu") (net 134))
  (segment (start 111.125 137.675) (end 111.1 137.7) (width 0.15) (layer "F.Cu") (net 134))
  (via (at 111.7 136.4) (size 0.6) (drill 0.25) (layers "F.Cu" "B.Cu") (net 134))
  (segment (start 111.035 136.765) (end 111.4 136.4) (width 0.15) (layer "B.Cu") (net 134))
  (segment (start 111.035 137.5) (end 111.035 136.765) (width 0.15) (layer "B.Cu") (net 134))
  (segment (start 111.4 136.4) (end 111.7 136.4) (width 0.15) (layer "B.Cu") (net 134))
  (segment (start 80.385 122.9) (end 81.05 122.9) (width 0.125) (layer "F.Cu") (net 136))
  (segment (start 74 126.352399) (end 74 127.8) (width 0.15) (layer "F.Cu") (net 136))
  (segment (start 81.85 107.3) (end 80.3 107.3) (width 0.155) (layer "F.Cu") (net 136))
  (segment (start 80.3 107.3) (end 78.16 105.16) (width 0.155) (layer "F.Cu") (net 136))
  (via (at 74 127.8) (size 0.6) (drill 0.25) (layers "F.Cu" "B.Cu") (net 136))
  (via (at 81.05 122.9) (size 0.6) (drill 0.25) (layers "F.Cu" "B.Cu") (net 136))
  (segment (start 77 122.4) (end 77.5 122.9) (width 0.2) (layer "In3.Cu") (net 136))
  (segment (start 77.5 122.9) (end 81.05 122.9) (width 0.2) (layer "In3.Cu") (net 136))
  (segment (start 78.16 105.16) (end 77 106.32) (width 0.2) (layer "In3.Cu") (net 136))
  (segment (start 77 106.32) (end 77 122.4) (width 0.2) (layer "In3.Cu") (net 136))
  (segment (start 79.585 96.585) (end 75.6 96.585) (width 0.15) (layer "B.Cu") (net 136))
  (segment (start 80.05 123.6) (end 80.35 123.6) (width 0.15) (layer "B.Cu") (net 136))
  (segment (start 80.4 96.77) (end 80.215 96.585) (width 0.15) (layer "B.Cu") (net 136))
  (segment (start 74 126.9) (end 74 127.8) (width 0.125) (layer "B.Cu") (net 136))
  (segment (start 75.9 126.4) (end 75.6 126.7) (width 0.125) (layer "B.Cu") (net 136))
  (segment (start 74.2 126.7) (end 74 126.9) (width 0.125) (layer "B.Cu") (net 136))
  (segment (start 80.4 96.6) (end 80.4 96.4) (width 0.15) (layer "B.Cu") (net 136))
  (segment (start 77.6 124.5) (end 77.4 124.7) (width 0.125) (layer "B.Cu") (net 136))
  (segment (start 80.185 96.585) (end 80.215 96.585) (width 0.15) (layer "B.Cu") (net 136))
  (segment (start 75.9 125.2) (end 75.9 126.4) (width 0.125) (layer "B.Cu") (net 136))
  (segment (start 80.185 96.585) (end 80.385 96.585) (width 0.15) (layer "B.Cu") (net 136))
  (segment (start 76.4 124.7) (end 75.9 125.2) (width 0.125) (layer "B.Cu") (net 136))
  (segment (start 79.1 102.95) (end 80.05 102.95) (width 0.15) (layer "B.Cu") (net 136))
  (segment (start 80.4 96.8) (end 80.4 96.6) (width 0.15) (layer "B.Cu") (net 136))
  (segment (start 80.4 102.6) (end 80.4 97.4) (width 0.15) (layer "B.Cu") (net 136))
  (segment (start 80.4 96.4) (end 80.4 92) (width 0.15) (layer "B.Cu") (net 136))
  (segment (start 75.6 126.7) (end 74.2 126.7) (width 0.125) (layer "B.Cu") (net 136))
  (segment (start 80.385 96.585) (end 80.4 96.6) (width 0.15) (layer "B.Cu") (net 136))
  (segment (start 80.05 123.6) (end 79.75 123.3) (width 0.125) (layer "B.Cu") (net 136))
  (segment (start 80.05 102.95) (end 80.4 102.6) (width 0.15) (layer "B.Cu") (net 136))
  (segment (start 79.75 123.3) (end 77.8 123.3) (width 0.125) (layer "B.Cu") (net 136))
  (segment (start 75.25 90.85) (end 75.25 84) (width 0.15) (layer "B.Cu") (net 136))
  (segment (start 77.6 123.5) (end 77.6 124.5) (width 0.125) (layer "B.Cu") (net 136))
  (segment (start 80.35 123.6) (end 81.05 122.9) (width 0.15) (layer "B.Cu") (net 136))
  (segment (start 77.4 124.7) (end 76.4 124.7) (width 0.125) (layer "B.Cu") (net 136))
  (segment (start 80.4 92) (end 79.8 91.4) (width 0.15) (layer "B.Cu") (net 136))
  (segment (start 75.8 91.4) (end 75.25 90.85) (width 0.15) (layer "B.Cu") (net 136))
  (segment (start 80.215 96.585) (end 80.4 96.4) (width 0.15) (layer "B.Cu") (net 136))
  (segment (start 79.585 96.585) (end 80.185 96.585) (width 0.15) (layer "B.Cu") (net 136))
  (segment (start 77.8 123.3) (end 77.6 123.5) (width 0.125) (layer "B.Cu") (net 136))
  (segment (start 80.4 97.4) (end 80.4 96.8) (width 0.15) (layer "B.Cu") (net 136))
  (segment (start 80.4 96.8) (end 80.4 96.77) (width 0.15) (layer "B.Cu") (net 136))
  (segment (start 79.8 91.4) (end 75.8 91.4) (width 0.15) (layer "B.Cu") (net 136))
  (segment (start 81.3 100.4) (end 81.3 101.135) (width 0.155) (layer "F.Cu") (net 137))
  (segment (start 89.5 98.25) (end 89.75 98.25) (width 0.155) (layer "F.Cu") (net 137))
  (segment (start 87.7471 96.4971) (end 89.5 98.25) (width 0.155) (layer "F.Cu") (net 137))
  (via (at 81.3 100.4) (size 0.6) (drill 0.25) (layers "F.Cu" "B.Cu") (net 137))
  (via (at 89.75 98.25) (size 0.6) (drill 0.25) (layers "F.Cu" "B.Cu") (net 137))
  (segment (start 90.1 100.4) (end 90.1 98.6) (width 0.155) (layer "B.Cu") (net 137))
  (segment (start 86 102.75) (end 86.5 102.75) (width 0.155) (layer "B.Cu") (net 137))
  (segment (start 81.3 100.4) (end 83.65 102.75) (width 0.155) (layer "B.Cu") (net 137))
  (segment (start 90.1 98.6) (end 89.75 98.25) (width 0.155) (layer "B.Cu") (net 137))
  (segment (start 85.75 102.75) (end 86 102.75) (width 0.155) (layer "B.Cu") (net 137))
  (segment (start 86.5 102.75) (end 87.75 102.75) (width 0.155) (layer "B.Cu") (net 137))
  (segment (start 85.5 102.75) (end 85.75 102.75) (width 0.155) (layer "B.Cu") (net 137))
  (segment (start 83.65 102.75) (end 85.5 102.75) (width 0.155) (layer "B.Cu") (net 137))
  (segment (start 87.75 102.75) (end 90.1 100.4) (width 0.155) (layer "B.Cu") (net 137))
  (segment (start 129.599999 123.299999) (end 130.3 124) (width 0.15) (layer "F.Cu") (net 138))
  (segment (start 147.528 118.528) (end 147 118) (width 0.4) (layer "F.Cu") (net 138))
  (segment (start 146.25 118) (end 147 118) (width 0.4) (layer "F.Cu") (net 138))
  (segment (start 120.7 124.1) (end 121.500001 123.299999) (width 0.15) (layer "F.Cu") (net 138))
  (segment (start 147.528 119.4) (end 147.528 118.528) (width 0.4) (layer "F.Cu") (net 138))
  (segment (start 121.500001 123.299999) (end 129.599999 123.299999) (width 0.15) (layer "F.Cu") (net 138))
  (via (at 145.8 130.3) (size 0.6) (drill 0.25) (layers "F.Cu" "B.Cu") (net 138))
  (via (at 146.25 118) (size 0.6) (drill 0.25) (layers "F.Cu" "B.Cu") (net 138))
  (via (at 120.7 124.1) (size 0.6) (drill 0.25) (layers "F.Cu" "B.Cu") (net 138))
  (via (at 130.3 124) (size 0.6) (drill 0.25) (layers "F.Cu" "B.Cu") (net 138))
  (via (at 132.1 120.8) (size 0.6) (drill 0.25) (layers "F.Cu" "B.Cu") (net 138))
  (via (at 132.733151 120.766849) (size 0.6) (drill 0.25) (layers "F.Cu" "B.Cu") (net 138))
  (segment (start 136.95 121.65) (end 145.45 121.65) (width 0.4) (layer "In1.Cu") (net 138))
  (segment (start 134.6 120.8) (end 136.1 120.8) (width 0.4) (layer "In1.Cu") (net 138))
  (segment (start 145.3 121.8) (end 145.3 129.8) (width 0.4) (layer "In1.Cu") (net 138))
  (segment (start 145.45 121.65) (end 145.3 121.8) (width 0.4) (layer "In1.Cu") (net 138))
  (segment (start 145.3 129.8) (end 145.8 130.3) (width 0.4) (layer "In1.Cu") (net 138))
  (segment (start 146.25 120.85) (end 145.45 121.65) (width 0.4) (layer "In1.Cu") (net 138))
  (segment (start 146.25 118) (end 146.25 120.85) (width 0.4) (layer "In1.Cu") (net 138))
  (segment (start 136.1 120.8) (end 136.95 121.65) (width 0.4) (layer "In1.Cu") (net 138))
  (segment (start 134.6 120.8) (end 132.1 120.8) (width 0.4) (layer "In1.Cu") (net 138))
  (segment (start 132.733151 120.766849) (end 133.272003 120.766849) (width 0.25) (layer "B.Cu") (net 138))
  (segment (start 130.22 121.95) (end 130.22 124.82) (width 0.25) (layer "B.Cu") (net 138))
  (segment (start 130.25 124.85) (end 130.25 126.35) (width 0.25) (layer "B.Cu") (net 138))
  (segment (start 144.528 130.65) (end 145.45 130.65) (width 0.4) (layer "B.Cu") (net 138))
  (segment (start 126 127.3) (end 126 128.2) (width 0.15) (layer "B.Cu") (net 138))
  (segment (start 132.1 120.8) (end 130.5 120.8) (width 0.25) (layer "B.Cu") (net 138))
  (segment (start 121.365 124.05) (end 120.75 124.05) (width 0.15) (layer "B.Cu") (net 138))
  (segment (start 129.7 127.1) (end 126.2 127.1) (width 0.15) (layer "B.Cu") (net 138))
  (segment (start 145.45 130.65) (end 145.8 130.3) (width 0.4) (layer "B.Cu") (net 138))
  (segment (start 120.75 124.05) (end 120.7 124.1) (width 0.15) (layer "B.Cu") (net 138))
  (segment (start 132.1 120.8) (end 132.133151 120.766849) (width 0.25) (layer "B.Cu") (net 138))
  (segment (start 126.2 127.1) (end 126 127.3) (width 0.15) (layer "B.Cu") (net 138))
  (segment (start 130.3 126.5) (end 129.7 127.1) (width 0.15) (layer "B.Cu") (net 138))
  (segment (start 132.133151 120.766849) (end 132.733151 120.766849) (width 0.25) (layer "B.Cu") (net 138))
  (segment (start 98.7 87.6) (end 97.6 87.6) (width 0.3) (layer "F.Cu") (net 139))
  (segment (start 109.435 94.285) (end 109.05 94.285) (width 0.2) (layer "F.Cu") (net 139))
  (segment (start 99.05 87.95) (end 98.7 87.6) (width 0.3) (layer "F.Cu") (net 139))
  (segment (start 123.285 109.965) (end 122.65 110.6) (width 0.2) (layer "F.Cu") (net 139))
  (segment (start 99.05 88.3) (end 99.05 87.95) (width 0.3) (layer "F.Cu") (net 139))
  (segment (start 97.25 87.95) (end 97.25 89.55) (width 0.3) (layer "F.Cu") (net 139))
  (segment (start 110.595 94.55) (end 110.005 94.55) (width 0.2) (layer "F.Cu") (net 139))
  (segment (start 109.05 94.804502) (end 109.05 94.285) (width 0.23) (layer "F.Cu") (net 139))
  (segment (start 112.55 94.285) (end 112.935 94.285) (width 0.2) (layer "F.Cu") (net 139))
  (segment (start 113.2 94.55) (end 113.505 94.55) (width 0.2) (layer "F.Cu") (net 139))
  (segment (start 113.285 97.235) (end 112.55 96.5) (width 0.2) (layer "F.Cu") (net 139))
  (segment (start 112.55 96.5) (end 112.55 94.95) (width 0.2) (layer "F.Cu") (net 139))
  (segment (start 118.515 109.8) (end 117.85 109.8) (width 0.2) (layer "F.Cu") (net 139))
  (segment (start 109.335 97.235) (end 109.8 97.235) (width 0.23) (layer "F.Cu") (net 139))
  (segment (start 110.8 97.235) (end 109.8 97.235) (width 0.2) (layer "F.Cu") (net 139))
  (segment (start 109.295498 95.05) (end 109.05 94.804502) (width 0.23) (layer "F.Cu") (net 139))
  (segment (start 109.1 97) (end 109.335 97.235) (width 0.23) (layer "F.Cu") (net 139))
  (segment (start 110.005 94.55) (end 109.7 94.55) (width 0.2) (layer "F.Cu") (net 139))
  (segment (start 121.19 108.85) (end 119.535 108.85) (width 0.2) (layer "F.Cu") (net 139))
  (segment (start 112.55 94.285) (end 112.55 94.95) (width 0.2) (layer "F.Cu") (net 139))
  (segment (start 109.1 95.245498) (end 109.1 97) (width 0.23) (layer "F.Cu") (net 139))
  (segment (start 97.6 87.6) (end 97.25 87.95) (width 0.3) (layer "F.Cu") (net 139))
  (segment (start 113.3 97.235) (end 114.3 97.235) (width 0.2) (layer "F.Cu") (net 139))
  (segment (start 109.7 94.55) (end 109.435 94.285) (width 0.2) (layer "F.Cu") (net 139))
  (segment (start 114.095 94.55) (end 113.505 94.55) (width 0.2) (layer "F.Cu") (net 139))
  (segment (start 112.935 94.285) (end 113.2 94.55) (width 0.2) (layer "F.Cu") (net 139))
  (segment (start 109.295498 95.05) (end 109.1 95.245498) (width 0.23) (layer "F.Cu") (net 139))
  (segment (start 118.515 109.77) (end 119.485 108.8) (width 0.2) (layer "F.Cu") (net 139))
  (via (at 117.85 109.8) (size 0.6) (drill 0.25) (layers "F.Cu" "B.Cu") (net 139))
  (via (at 122.65 110.6) (size 0.6) (drill 0.25) (layers "F.Cu" "B.Cu") (net 139))
  (via (at 99.05 88.3) (size 0.6) (drill 0.25) (layers "F.Cu" "B.Cu") (net 139))
  (via (at 109.295498 95.05) (size 0.6) (drill 0.25) (layers "F.Cu" "B.Cu") (net 139))
  (via (at 112.55 94.95) (size 0.6) (drill 0.25) (layers "F.Cu" "B.Cu") (net 139))
  (segment (start 109.295498 95.05) (end 109.695497 94.650001) (width 0.23) (layer "In1.Cu") (net 139))
  (segment (start 109.695497 94.650001) (end 112.250001 94.650001) (width 0.23) (layer "In1.Cu") (net 139))
  (segment (start 112.250001 94.650001) (end 112.55 94.95) (width 0.23) (layer "In1.Cu") (net 139))
  (segment (start 121.85 109.8) (end 117.85 109.8) (width 0.2) (layer "In3.Cu") (net 139))
  (segment (start 122.65 110.6) (end 121.85 109.8) (width 0.2) (layer "In3.Cu") (net 139))
  (segment (start 117.35 103.45) (end 115.55 103.45) (width 0.3) (layer "B.Cu") (net 139))
  (segment (start 99.824999 90.024999) (end 99.05 89.25) (width 0.3) (layer "B.Cu") (net 139))
  (segment (start 99.824999 95.824999) (end 99.824999 95.124999) (width 0.3) (layer "B.Cu") (net 139))
  (segment (start 115.3 94.8) (end 114.9 94.4) (width 0.3) (layer "B.Cu") (net 139))
  (segment (start 115.3 98.2) (end 114.9 98.6) (width 0.3) (layer "B.Cu") (net 139))
  (segment (start 115.3 99) (end 115.3 98.6) (width 0.3) (layer "B.Cu") (net 139))
  (segment (start 110.705012 98.6) (end 114.9 98.6) (width 0.3) (layer "B.Cu") (net 139))
  (segment (start 113.1 94.4) (end 112.55 94.95) (width 0.3) (layer "B.Cu") (net 139))
  (segment (start 114.9 94.4) (end 113.1 94.4) (width 0.3) (layer "B.Cu") (net 139))
  (segment (start 105.2 98.6) (end 104.8 98.2) (width 0.3) (layer "B.Cu") (net 139))
  (segment (start 115.55 103.45) (end 115.3 103.2) (width 0.3) (layer "B.Cu") (net 139))
  (segment (start 114.9 98.6) (end 115.3 99) (width 0.3) (layer "B.Cu") (net 139))
  (segment (start 117.85 103.95) (end 117.35 103.45) (width 0.3) (layer "B.Cu") (net 139))
  (segment (start 115.3 103.2) (end 115.3 99) (width 0.3) (layer "B.Cu") (net 139))
  (segment (start 110.705012 98.6) (end 105.2 98.6) (width 0.3) (layer "B.Cu") (net 139))
  (segment (start 100.2 96.2) (end 99.824999 95.824999) (width 0.3) (layer "B.Cu") (net 139))
  (segment (start 115.3 98.1) (end 115.3 94.8) (width 0.3) (layer "B.Cu") (net 139))
  (segment (start 117.85 109.8) (end 117.85 103.95) (width 0.3) (layer "B.Cu") (net 139))
  (segment (start 104.4 96.2) (end 100.2 96.2) (width 0.3) (layer "B.Cu") (net 139))
  (segment (start 99.824999 95.124999) (end 99.824999 90.024999) (width 0.3) (layer "B.Cu") (net 139))
  (segment (start 115.3 98.1) (end 115.3 98.2) (width 0.3) (layer "B.Cu") (net 139))
  (segment (start 104.8 96.6) (end 104.4 96.2) (width 0.3) (layer "B.Cu") (net 139))
  (segment (start 104.8 98.2) (end 104.8 96.6) (width 0.3) (layer "B.Cu") (net 139))
  (segment (start 114.9 98.6) (end 115.3 98.6) (width 0.3) (layer "B.Cu") (net 139))
  (segment (start 115.3 98.6) (end 115.3 98.1) (width 0.3) (layer "B.Cu") (net 139))
  (segment (start 99.05 89.25) (end 99.05 88.3) (width 0.3) (layer "B.Cu") (net 139))
  (segment (start 86.8 138.205) (end 86.8 139.008501) (width 0.15) (layer "F.Cu") (net 140))
  (segment (start 86.8 138.205) (end 86.8 139.39) (width 0.25) (layer "F.Cu") (net 140))
  (via (at 86.8 139.008501) (size 0.6) (drill 0.25) (layers "F.Cu" "B.Cu") (net 140))
  (segment (start 86.8 139.008501) (end 87.957701 137.8508) (width 0.15) (layer "B.Cu") (net 140))
  (segment (start 87.8 138.96534) (end 87.756838 139.008502) (width 0.2) (layer "F.Cu") (net 141))
  (segment (start 87.8 138.205) (end 87.8 139.39) (width 0.25) (layer "F.Cu") (net 141))
  (segment (start 87.8 138.205) (end 87.8 138.96534) (width 0.2) (layer "F.Cu") (net 141))
  (segment (start 82.45 133) (end 81.9 133.55) (width 0.2) (layer "F.Cu") (net 141))
  (segment (start 82.915 132) (end 82.915 133) (width 0.2) (layer "F.Cu") (net 141))
  (segment (start 82.915 133) (end 82.45 133) (width 0.2) (layer "F.Cu") (net 141))
  (segment (start 81.9 133.55) (end 81.9 134.35) (width 0.2) (layer "F.Cu") (net 141))
  (via (at 87.756838 139.008502) (size 0.6) (drill 0.25) (layers "F.Cu" "B.Cu") (net 141))
  (via (at 81.9 134.35) (size 0.6) (drill 0.25) (layers "F.Cu" "B.Cu") (net 141))
  (segment (start 82.65 137.6) (end 86.348336 137.6) (width 0.2) (layer "In3.Cu") (net 141))
  (segment (start 81.9 136.85) (end 82.65 137.6) (width 0.2) (layer "In3.Cu") (net 141))
  (segment (start 86.348336 137.6) (end 87.756838 139.008502) (width 0.2) (layer "In3.Cu") (net 141))
  (segment (start 81.9 134.35) (end 81.9 136.85) (width 0.2) (layer "In3.Cu") (net 141))
  (segment (start 88.191498 139.008502) (end 89.3492 137.8508) (width 0.15) (layer "B.Cu") (net 141))
  (segment (start 87.756838 139.008502) (end 88.191498 139.008502) (width 0.15) (layer "B.Cu") (net 141))
  (segment (start 92.45 149.45) (end 93.4 149.45) (width 0.2) (layer "F.Cu") (net 142))
  (segment (start 74.499999 127.199999) (end 74.5 127.2) (width 0.15) (layer "F.Cu") (net 142))
  (segment (start 87.3 131.3) (end 87.3 131.615) (width 0.15) (layer "F.Cu") (net 142))
  (segment (start 80.385 124.9) (end 81.05 124.9) (width 0.125) (layer "F.Cu") (net 142))
  (segment (start 81.66 138.05) (end 82.125 138.05) (width 0.15) (layer "F.Cu") (net 142))
  (segment (start 87 124.9) (end 86.5 124.9) (width 0.15) (layer "F.Cu") (net 142))
  (segment (start 90.265 130.55) (end 89.6 130.55) (width 0.15) (layer "F.Cu") (net 142))
  (segment (start 87.3 131.3) (end 87.3 125.2) (width 0.15) (layer "F.Cu") (net 142))
  (segment (start 87.3 131.615) (end 87 131.915) (width 0.15) (layer "F.Cu") (net 142))
  (segment (start 81.05 124.9) (end 86.5 124.9) (width 0.15) (layer "F.Cu") (net 142))
  (segment (start 82.125 138.05) (end 82.525 138.45) (width 0.15) (layer "F.Cu") (net 142))
  (segment (start 74.499999 126.352399) (end 74.499999 127.199999) (width 0.15) (layer "F.Cu") (net 142))
  (segment (start 87.3 125.2) (end 87 124.9) (width 0.15) (layer "F.Cu") (net 142))
  (via (at 87.3 131.3) (size 0.6) (drill 0.25) (layers "F.Cu" "B.Cu") (net 142))
  (via (at 81.05 124.9) (size 0.6) (drill 0.25) (layers "F.Cu" "B.Cu") (net 142))
  (via (at 92.45 149.45) (size 0.6) (drill 0.25) (layers "F.Cu" "B.Cu") (net 142))
  (via (at 74.5 127.2) (size 0.6) (drill 0.25) (layers "F.Cu" "B.Cu") (net 142))
  (via (at 89.6 130.55) (size 0.6) (drill 0.25) (layers "F.Cu" "B.Cu") (net 142))
  (via (at 82.525 138.45) (size 0.6) (drill 0.25) (layers "F.Cu" "B.Cu") (net 142))
  (segment (start 80.1 143.5) (end 81.9 145.3) (width 0.2) (layer "B.Cu") (net 142))
  (segment (start 85.4 138.2) (end 84.5 139.1) (width 0.2) (layer "B.Cu") (net 142))
  (segment (start 76.587499 124.987499) (end 79.837499 124.987499) (width 0.125) (layer "B.Cu") (net 142))
  (segment (start 82.0575 140.4425) (end 81.2 141.3) (width 0.2) (layer "B.Cu") (net 142))
  (segment (start 87.3 131.3) (end 85.9 131.3) (width 0.2) (layer "B.Cu") (net 142))
  (segment (start 76.2 125.374998) (end 76.587499 124.987499) (width 0.125) (layer "B.Cu") (net 142))
  (segment (start 81.05 124.9) (end 80.35 124.9) (width 0.15) (layer "B.Cu") (net 142))
  (segment (start 75.7 127.2) (end 76.2 126.7) (width 0.125) (layer "B.Cu") (net 142))
  (segment (start 83.3425 139.45) (end 82.35 140.4425) (width 0.2) (layer "B.Cu") (net 142))
  (segment (start 81.2 141.3) (end 80.4 141.3) (width 0.2) (layer "B.Cu") (net 142))
  (segment (start 80.1 141.6) (end 80.1 143.5) (width 0.2) (layer "B.Cu") (net 142))
  (segment (start 89.6 130.55) (end 88.85 131.3) (width 0.2) (layer "B.Cu") (net 142))
  (segment (start 81.9 145.3) (end 81.9 147.9) (width 0.2) (layer "B.Cu") (net 142))
  (segment (start 80.4 141.3) (end 80.1 141.6) (width 0.2) (layer "B.Cu") (net 142))
  (segment (start 88.85 131.3) (end 87.3 131.3) (width 0.2) (layer "B.Cu") (net 142))
  (segment (start 85.4 131.8) (end 85.4 138.2) (width 0.2) (layer "B.Cu") (net 142))
  (segment (start 74.5 127.2) (end 75.7 127.2) (width 0.125) (layer "B.Cu") (net 142))
  (segment (start 76.2 126.7) (end 76.2 125.374998) (width 0.125) (layer "B.Cu") (net 142))
  (segment (start 85.9 131.3) (end 85.4 131.8) (width 0.2) (layer "B.Cu") (net 142))
  (segment (start 81.9 147.9) (end 83.45 149.45) (width 0.2) (layer "B.Cu") (net 142))
  (segment (start 83.6 139.1) (end 82.35 140.35) (width 0.2) (layer "B.Cu") (net 142))
  (segment (start 80.35 124.9) (end 80.05 125.2) (width 0.15) (layer "B.Cu") (net 142))
  (segment (start 84.5 139.1) (end 83.6 139.1) (width 0.2) (layer "B.Cu") (net 142))
  (segment (start 83.45 149.45) (end 92.45 149.45) (width 0.2) (layer "B.Cu") (net 142))
  (segment (start 90.38 137.28) (end 90.125 137.025) (width 0.182) (layer "F.Cu") (net 143))
  (segment (start 87 143.04) (end 87 143.8) (width 0.182) (layer "F.Cu") (net 143))
  (segment (start 88.98 137.025) (end 88.98 137.525) (width 0.15) (layer "F.Cu") (net 143))
  (segment (start 90.38 139.4) (end 90.38 140.294997) (width 0.182) (layer "F.Cu") (net 143))
  (segment (start 90.125 137.025) (end 88.98 137.025) (width 0.182) (layer "F.Cu") (net 143))
  (segment (start 90.38 140.294997) (end 90.274997 140.4) (width 0.182) (layer "F.Cu") (net 143))
  (segment (start 90.38 139.4) (end 90.38 137.28) (width 0.182) (layer "F.Cu") (net 143))
  (via (at 90.274997 140.4) (size 0.6) (drill 0.25) (layers "F.Cu" "B.Cu") (net 143))
  (via (at 87 143.8) (size 0.6) (drill 0.25) (layers "F.Cu" "B.Cu") (net 143))
  (segment (start 90.4 142.4) (end 89.5 143.3) (width 0.182) (layer "In2.Cu") (net 143))
  (segment (start 87.5 143.3) (end 87 143.8) (width 0.182) (layer "In2.Cu") (net 143))
  (segment (start 90.274997 140.4) (end 90.4 140.525003) (width 0.182) (layer "In2.Cu") (net 143))
  (segment (start 89.5 143.3) (end 87.5 143.3) (width 0.182) (layer "In2.Cu") (net 143))
  (segment (start 90.4 140.525003) (end 90.4 142.4) (width 0.182) (layer "In2.Cu") (net 143))
  (segment (start 89.4 140.2508) (end 90.125797 140.2508) (width 0.125) (layer "B.Cu") (net 143))
  (segment (start 90.125797 140.2508) (end 90.274997 140.4) (width 0.125) (layer "B.Cu") (net 143))
  (segment (start 90.175 136.025) (end 88.98 136.025) (width 0.182) (layer "F.Cu") (net 144))
  (segment (start 88.98 135.525) (end 88.98 136.025) (width 0.15) (layer "F.Cu") (net 144))
  (segment (start 89.825 136.025) (end 89.9 136.025) (width 0.15) (layer "F.Cu") (net 144))
  (segment (start 90.82 138.4) (end 90.82 140.22) (width 0.182) (layer "F.Cu") (net 144))
  (segment (start 88.25 144.74) (end 88.25 144) (width 0.182) (layer "F.Cu") (net 144))
  (segment (start 90.82 136.62) (end 90.82 138.4) (width 0.182) (layer "F.Cu") (net 144))
  (segment (start 90.225 136.025) (end 90.82 136.62) (width 0.182) (layer "F.Cu") (net 144))
  (segment (start 90.175 136.025) (end 90.225 136.025) (width 0.182) (layer "F.Cu") (net 144))
  (segment (start 89.825 136.025) (end 90.175 136.025) (width 0.182) (layer "F.Cu") (net 144))
  (segment (start 90.82 140.22) (end 91 140.4) (width 0.182) (layer "F.Cu") (net 144))
  (segment (start 88.98 136.025) (end 89.825 136.025) (width 0.15) (layer "F.Cu") (net 144))
  (via (at 91 140.4) (size 0.6) (drill 0.25) (layers "F.Cu" "B.Cu") (net 144))
  (via (at 88.25 144) (size 0.6) (drill 0.25) (layers "F.Cu" "B.Cu") (net 144))
  (segment (start 89.625 143.675) (end 88.575 143.675) (width 0.182) (layer "In2.Cu") (net 144))
  (segment (start 89.625 143.675) (end 90.783999 142.516001) (width 0.182) (layer "In2.Cu") (net 144))
  (segment (start 90.783999 140.616001) (end 91 140.4) (width 0.182) (layer "In2.Cu") (net 144))
  (segment (start 90.783999 142.516001) (end 90.783999 140.616001) (width 0.182) (layer "In2.Cu") (net 144))
  (segment (start 88.575 143.675) (end 88.25 144) (width 0.182) (layer "In2.Cu") (net 144))
  (segment (start 92 140.2508) (end 91.1492 140.2508) (width 0.125) (layer "B.Cu") (net 144))
  (segment (start 91.1492 140.2508) (end 91 140.4) (width 0.125) (layer "B.Cu") (net 144))
  (segment (start 61.335 112.212) (end 61.335 113.72) (width 0.15) (layer "B.Cu") (net 145))
  (segment (start 60.065 112.212) (end 60.065 113.78) (width 0.15) (layer "B.Cu") (net 146))
  (segment (start 60.065 106.788) (end 60.065 105.22) (width 0.15) (layer "B.Cu") (net 147))
  (segment (start 121.19 107.285003) (end 121.275003 107.2) (width 0.15) (layer "F.Cu") (net 148))
  (segment (start 121.19 107.85) (end 121.19 107.285003) (width 0.15) (layer "F.Cu") (net 148))
  (segment (start 121.19 107.85) (end 122.265 107.85) (width 0.15) (layer "F.Cu") (net 148))
  (via (at 121.275003 107.2) (size 0.6) (drill 0.25) (layers "F.Cu" "B.Cu") (net 148))
  (segment (start 135.199893 131.32499) (end 119.313912 131.32499) (width 0.15) (layer "B.Cu") (net 148))
  (segment (start 121.275003 107.224997) (end 121.275003 107.2) (width 0.15) (layer "B.Cu") (net 148))
  (segment (start 121.1 107.4) (end 121.275003 107.224997) (width 0.15) (layer "B.Cu") (net 148))
  (segment (start 119.313912 131.32499) (end 118.95002 130.961098) (width 0.15) (layer "B.Cu") (net 148))
  (segment (start 148.8 133.4) (end 137.274903 133.4) (width 0.15) (layer "B.Cu") (net 148))
  (segment (start 118.95002 130.961098) (end 118.95002 109.14998) (width 0.15) (layer "B.Cu") (net 148))
  (segment (start 118.95002 109.14998) (end 119.22499 108.87501) (width 0.15) (layer "B.Cu") (net 148))
  (segment (start 137.274903 133.4) (end 135.199893 131.32499) (width 0.15) (layer "B.Cu") (net 148))
  (segment (start 121.1 108.488922) (end 121.1 107.4) (width 0.15) (layer "B.Cu") (net 148))
  (segment (start 120.713912 108.87501) (end 121.1 108.488922) (width 0.15) (layer "B.Cu") (net 148))
  (segment (start 119.22499 108.87501) (end 120.713912 108.87501) (width 0.15) (layer "B.Cu") (net 148))
  (segment (start 149.2 133) (end 148.8 133.4) (width 0.15) (layer "B.Cu") (net 148))
  (segment (start 120.55 106.85) (end 120.8 106.6) (width 0.155) (layer "F.Cu") (net 149))
  (segment (start 120.8 106.6) (end 122.115 106.6) (width 0.155) (layer "F.Cu") (net 149))
  (segment (start 120.605 107.255) (end 120.55 107.2) (width 0.15) (layer "F.Cu") (net 149))
  (segment (start 120.605 107.85) (end 120.605 107.255) (width 0.15) (layer "F.Cu") (net 149))
  (segment (start 120.55 107.2) (end 120.55 106.85) (width 0.155) (layer "F.Cu") (net 149))
  (via (at 120.55 107.2) (size 0.6) (drill 0.25) (layers "F.Cu" "B.Cu") (net 149))
  (segment (start 119 108.6) (end 118.67501 108.92499) (width 0.15) (layer "B.Cu") (net 149))
  (segment (start 120.82499 108.37501) (end 120.6 108.6) (width 0.15) (layer "B.Cu") (net 149))
  (segment (start 120.55 107.25) (end 120.82499 107.52499) (width 0.15) (layer "B.Cu") (net 149))
  (segment (start 120.55 107.2) (end 120.55 107.25) (width 0.15) (layer "B.Cu") (net 149))
  (segment (start 137.160991 133.67501) (end 148.77501 133.67501) (width 0.15) (layer "B.Cu") (net 149))
  (segment (start 120.82499 107.52499) (end 120.82499 108.37501) (width 0.15) (layer "B.Cu") (net 149))
  (segment (start 149.1 134) (end 149.5 134) (width 0.15) (layer "B.Cu") (net 149))
  (segment (start 119.2 131.6) (end 135.085981 131.6) (width 0.15) (layer "B.Cu") (net 149))
  (segment (start 120.6 108.6) (end 119 108.6) (width 0.15) (layer "B.Cu") (net 149))
  (segment (start 148.77501 133.67501) (end 149.1 134) (width 0.15) (layer "B.Cu") (net 149))
  (segment (start 135.085981 131.6) (end 137.160991 133.67501) (width 0.15) (layer "B.Cu") (net 149))
  (segment (start 118.67501 108.92499) (end 118.67501 131.07501) (width 0.15) (layer "B.Cu") (net 149))
  (segment (start 118.67501 131.07501) (end 119.2 131.6) (width 0.15) (layer "B.Cu") (net 149))
  (segment (start 88.3 133.5) (end 88.2 133.4) (width 0.15) (layer "F.Cu") (net 150))
  (segment (start 88.3 134.345) (end 88.3 133.5) (width 0.15) (layer "F.Cu") (net 150))
  (segment (start 96.5 124.6) (end 92.4 124.6) (width 0.15) (layer "F.Cu") (net 150))
  (segment (start 88.2 125.2) (end 88.8 124.6) (width 0.15) (layer "F.Cu") (net 150))
  (segment (start 96.7 124.8) (end 96.5 124.6) (width 0.15) (layer "F.Cu") (net 150))
  (segment (start 113.8 120.7) (end 113.8 118.6) (width 0.15) (layer "F.Cu") (net 150))
  (segment (start 113.8 120.7) (end 114.115 120.7) (width 0.15) (layer "F.Cu") (net 150))
  (segment (start 112.605 107.995) (end 112.5 108.1) (width 0.15) (layer "F.Cu") (net 150))
  (segment (start 114.115 120.7) (end 114.515 120.3) (width 0.15) (layer "F.Cu") (net 150))
  (segment (start 113.05 107.995) (end 112.605 107.995) (width 0.15) (layer "F.Cu") (net 150))
  (segment (start 92.4 124.6) (end 88.8 124.6) (width 0.15) (layer "F.Cu") (net 150))
  (segment (start 88.2 133.4) (end 88.2 125.2) (width 0.15) (layer "F.Cu") (net 150))
  (via (at 113.8 120.7) (size 0.6) (drill 0.25) (layers "F.Cu" "B.Cu") (net 150))
  (via (at 112.5 108.1) (size 0.6) (drill 0.25) (layers "F.Cu" "B.Cu") (net 150))
  (via (at 96.7 124.8) (size 0.6) (drill 0.25) (layers "F.Cu" "B.Cu") (net 150))
  (via (at 114.1 124) (size 0.6) (drill 0.25) (layers "F.Cu" "B.Cu") (net 150))
  (segment (start 112.182511 108.417489) (end 112.5 108.1) (width 0.155) (layer "In2.Cu") (net 150))
  (segment (start 97.936088 122.42499) (end 96.811079 123.549999) (width 0.15) (layer "In2.Cu") (net 150))
  (segment (start 113.8 116.804007) (end 113.88001 116.884017) (width 0.155) (layer "In2.Cu") (net 150))
  (segment (start 96.811079 123.549999) (end 96.459999 123.549999) (width 0.15) (layer "In2.Cu") (net 150))
  (segment (start 113.88001 120.61999) (end 113.8 120.7) (width 0.155) (layer "In2.Cu") (net 150))
  (segment (start 112.4 115.4) (end 112.182511 115.182511) (width 0.155) (layer "In2.Cu") (net 150))
  (segment (start 96.199999 123.809999) (end 96.199999 124.399999) (width 0.15) (layer "In2.Cu") (net 150))
  (segment (start 96.459999 123.549999) (end 96.199999 123.809999) (width 0.15) (layer "In2.Cu") (net 150))
  (segment (start 113.8 116.8) (end 113.8 116.804007) (width 0.155) (layer "In2.Cu") (net 150))
  (segment (start 112.4 115.4) (end 112.27751 115.27751) (width 0.155) (layer "In2.Cu") (net 150))
  (segment (start 112.182511 115.182511) (end 112.182511 108.417489) (width 0.155) (layer "In2.Cu") (net 150))
  (segment (start 113.8 116.8) (end 112.4 115.4) (width 0.155) (layer "In2.Cu") (net 150))
  (segment (start 110.086088 122.42499) (end 97.936088 122.42499) (width 0.15) (layer "In2.Cu") (net 150))
  (segment (start 96.6 124.8) (end 96.7 124.8) (width 0.15) (layer "In2.Cu") (net 150))
  (segment (start 111.82499 121.72499) (end 110.786088 121.72499) (width 0.15) (layer "In2.Cu") (net 150))
  (segment (start 114.1 124) (end 111.82499 121.72499) (width 0.15) (layer "In2.Cu") (net 150))
  (segment (start 110.786088 121.72499) (end 110.086088 122.42499) (width 0.15) (layer "In2.Cu") (net 150))
  (segment (start 113.88001 116.884017) (end 113.88001 120.61999) (width 0.155) (layer "In2.Cu") (net 150))
  (segment (start 96.199999 124.399999) (end 96.6 124.8) (width 0.15) (layer "In2.Cu") (net 150))
  (segment (start 113.850001 123.750001) (end 113.850001 120.750001) (width 0.15) (layer "B.Cu") (net 150))
  (segment (start 114.1 124) (end 113.850001 123.750001) (width 0.15) (layer "B.Cu") (net 150))
  (segment (start 112.5 108.1) (end 111.7508 108.1) (width 0.15) (layer "B.Cu") (net 150))
  (segment (start 113.850001 120.750001) (end 113.8 120.7) (width 0.15) (layer "B.Cu") (net 150))
  (segment (start 112.605 107.405) (end 112.5 107.3) (width 0.15) (layer "F.Cu") (net 151))
  (segment (start 96.42501 124.32499) (end 88.67501 124.32499) (width 0.15) (layer "F.Cu") (net 151))
  (segment (start 87.92499 133.4) (end 87.92499 125.086088) (width 0.15) (layer "F.Cu") (net 151))
  (segment (start 87.92499 125.086088) (end 88.67501 124.336068) (width 0.15) (layer "F.Cu") (net 151))
  (segment (start 113.659998 121.3) (end 113.3 120.940002) (width 0.15) (layer "F.Cu") (net 151))
  (segment (start 113.3 120.940002) (end 113.3 120.1) (width 0.15) (layer "F.Cu") (net 151))
  (segment (start 87.8 134.345) (end 87.8 133.52499) (width 0.15) (layer "F.Cu") (net 151))
  (segment (start 88.67501 124.336068) (end 88.67501 124.32499) (width 0.15) (layer "F.Cu") (net 151))
  (segment (start 113.25 118.55) (end 113.25 120.05) (width 0.15) (layer "F.Cu") (net 151))
  (segment (start 114.515 121.3) (end 113.659998 121.3) (width 0.15) (layer "F.Cu") (net 151))
  (segment (start 113.05 107.405) (end 112.605 107.405) (width 0.15) (layer "F.Cu") (net 151))
  (segment (start 87.8 133.52499) (end 87.92499 133.4) (width 0.15) (layer "F.Cu") (net 151))
  (segment (start 113.25 120.05) (end 113.3 120.1) (width 0.15) (layer "F.Cu") (net 151))
  (segment (start 96.7 124.05) (end 96.42501 124.32499) (width 0.15) (layer "F.Cu") (net 151))
  (via (at 113.3 120.1) (size 0.6) (drill 0.25) (layers "F.Cu" "B.Cu") (net 151))
  (via (at 113.35 124) (size 0.6) (drill 0.25) (layers "F.Cu" "B.Cu") (net 151))
  (via (at 96.7 124.05) (size 0.6) (drill 0.25) (layers "F.Cu" "B.Cu") (net 151))
  (via (at 112.5 107.3) (size 0.6) (drill 0.25) (layers "F.Cu" "B.Cu") (net 151))
  (segment (start 113.6 119.8) (end 113.6 117) (width 0.155) (layer "In2.Cu") (net 151))
  (segment (start 111.7 122) (end 110.9 122) (width 0.15) (layer "In2.Cu") (net 151))
  (segment (start 111.902501 109.641201) (end 111.902501 107.897499) (width 0.155) (layer "In2.Cu") (net 151))
  (segment (start 110.9 122) (end 110.2 122.7) (width 0.15) (layer "In2.Cu") (net 151))
  (segment (start 111.9 109.643702) (end 111.902501 109.641201) (width 0.155) (layer "In2.Cu") (net 151))
  (segment (start 111.902501 107.897499) (end 112.1 107.7) (width 0.155) (layer "In2.Cu") (net 151))
  (segment (start 113.35 123.65) (end 111.7 122) (width 0.15) (layer "In2.Cu") (net 151))
  (segment (start 110.2 122.7) (end 98.05 122.7) (width 0.15) (layer "In2.Cu") (net 151))
  (segment (start 113.3 120.1) (end 113.6 119.8) (width 0.155) (layer "In2.Cu") (net 151))
  (segment (start 112 107.8) (end 112.1 107.7) (width 0.15) (layer "In2.Cu") (net 151))
  (segment (start 98.05 122.7) (end 96.7 124.05) (width 0.15) (layer "In2.Cu") (net 151))
  (segment (start 113.6 117) (end 111.9 115.3) (width 0.155) (layer "In2.Cu") (net 151))
  (segment (start 113.35 124) (end 113.35 123.65) (width 0.15) (layer "In2.Cu") (net 151))
  (segment (start 111.9 115.3) (end 111.9 109.643702) (width 0.155) (layer "In2.Cu") (net 151))
  (segment (start 112.1 107.7) (end 112.5 107.3) (width 0.15) (layer "In2.Cu") (net 151))
  (segment (start 111.8492 107.3) (end 111.6 107.0508) (width 0.15) (layer "B.Cu") (net 151))
  (segment (start 113.3 123.95) (end 113.35 124) (width 0.15) (layer "B.Cu") (net 151))
  (segment (start 113.3 120.1) (end 113.3 123.95) (width 0.15) (layer "B.Cu") (net 151))
  (segment (start 112.5 107.3) (end 111.8492 107.3) (width 0.15) (layer "B.Cu") (net 151))
  (segment (start 79.4 134.8) (end 79 135.2) (width 0.15) (layer "F.Cu") (net 152))
  (segment (start 79.400001 141.849999) (end 78.25 143) (width 0.15) (layer "F.Cu") (net 152))
  (segment (start 78.25 144.65) (end 78.25 143) (width 0.2) (layer "F.Cu") (net 152))
  (segment (start 81.25 147.65) (end 78.25 144.65) (width 0.2) (layer "F.Cu") (net 152))
  (segment (start 79.52999 136.52999) (end 79.52999 141.72001) (width 0.15) (layer "F.Cu") (net 152))
  (segment (start 81.25 149.45) (end 81.25 147.65) (width 0.2) (layer "F.Cu") (net 152))
  (segment (start 79 135.2) (end 79 136) (width 0.15) (layer "F.Cu") (net 152))
  (segment (start 79.52999 141.72001) (end 79.400001 141.849999) (width 0.15) (layer "F.Cu") (net 152))
  (segment (start 80.8 134.8) (end 79.4 134.8) (width 0.15) (layer "F.Cu") (net 152))
  (segment (start 81.05 134.55) (end 80.8 134.8) (width 0.15) (layer "F.Cu") (net 152))
  (segment (start 81.05 126.9) (end 81.05 134.55) (width 0.15) (layer "F.Cu") (net 152))
  (segment (start 75 126.352399) (end 75 127.8) (width 0.15) (layer "F.Cu") (net 152))
  (segment (start 79 136) (end 79.52999 136.52999) (width 0.15) (layer "F.Cu") (net 152))
  (segment (start 80.385 126.9) (end 81.05 126.9) (width 0.125) (layer "F.Cu") (net 152))
  (via (at 81.05 126.9) (size 0.6) (drill 0.25) (layers "F.Cu" "B.Cu") (net 152))
  (via (at 75 127.8) (size 0.6) (drill 0.25) (layers "F.Cu" "B.Cu") (net 152))
  (segment (start 76.7 126.3) (end 79.8 126.3) (width 0.125) (layer "B.Cu") (net 152))
  (segment (start 76.5 127) (end 76.5 126.5) (width 0.125) (layer "B.Cu") (net 152))
  (segment (start 81.05 126.9) (end 80.1508 126.9) (width 0.15) (layer "B.Cu") (net 152))
  (segment (start 75.3 127.5) (end 76 127.5) (width 0.125) (layer "B.Cu") (net 152))
  (segment (start 75 127.8) (end 75.3 127.5) (width 0.125) (layer "B.Cu") (net 152))
  (segment (start 76 127.5) (end 76.5 127) (width 0.125) (layer "B.Cu") (net 152))
  (segment (start 80.05 126.55) (end 80.05 127.0008) (width 0.125) (layer "B.Cu") (net 152))
  (segment (start 79.8 126.3) (end 80.05 126.55) (width 0.125) (layer "B.Cu") (net 152))
  (segment (start 81.05 126.9) (end 80.1008 126.9) (width 0.15) (layer "B.Cu") (net 152))
  (segment (start 76.5 126.5) (end 76.7 126.3) (width 0.125) (layer "B.Cu") (net 152))
  (segment (start 74.885 94.585) (end 74.7 94.4) (width 0.15) (layer "B.Cu") (net 153))
  (segment (start 75.6 94.585) (end 75.6 95.615) (width 0.15) (layer "B.Cu") (net 153))
  (segment (start 75.6 94.585) (end 77.745 94.585) (width 0.15) (layer "B.Cu") (net 153))
  (segment (start 75.6 94.585) (end 74.885 94.585) (width 0.15) (layer "B.Cu") (net 153))
  (segment (start 74.7 85.6) (end 73.1 84) (width 0.15) (layer "B.Cu") (net 153))
  (segment (start 74.7 94.4) (end 74.7 85.6) (width 0.15) (layer "B.Cu") (net 153))
  (segment (start 135.65 145.065) (end 136.765 145.065) (width 0.15) (layer "B.Cu") (net 154))
  (segment (start 133.97 133.5) (end 133.97 134.43) (width 0.2) (layer "B.Cu") (net 155))
  (segment (start 71 120.6) (end 71.2 120.8) (width 0.15) (layer "F.Cu") (net 156))
  (segment (start 71 120.085) (end 71 120.6) (width 0.15) (layer "F.Cu") (net 156))
  (via (at 71.2 120.8) (size 0.6) (drill 0.25) (layers "F.Cu" "B.Cu") (net 156))
  (segment (start 77.91 116.61) (end 77.265 116.61) (width 0.15) (layer "B.Cu") (net 156))
  (segment (start 78.3 119.2) (end 78.1 119) (width 0.15) (layer "B.Cu") (net 156))
  (segment (start 71.9 118.6) (end 71.55 118.95) (width 0.155) (layer "B.Cu") (net 156))
  (segment (start 73.952501 118.247499) (end 75.791201 118.247499) (width 0.15) (layer "B.Cu") (net 156))
  (segment (start 78.1 119.1) (end 78 119.2) (width 0.15) (layer "B.Cu") (net 156))
  (segment (start 78.4 119.2) (end 82.760002 119.2) (width 0.15) (layer "B.Cu") (net 156))
  (segment (start 85.75 124.05) (end 85.15 124.05) (width 0.15) (layer "B.Cu") (net 156))
  (segment (start 85.15 124.05) (end 85.15 121.589998) (width 0.15) (layer "B.Cu") (net 156))
  (segment (start 73.6 118.6) (end 73.952501 118.247499) (width 0.15) (layer "B.Cu") (net 156))
  (segment (start 77.7 119.2) (end 78 119.2) (width 0.15) (layer "B.Cu") (net 156))
  (segment (start 86.15 124.05) (end 85.75 124.05) (width 0.15) (layer "B.Cu") (net 156))
  (segment (start 71.25 120.75) (end 71.2 120.8) (width 0.15) (layer "B.Cu") (net 156))
  (segment (start 71.25 119.25) (end 71.55 118.95) (width 0.15) (layer "B.Cu") (net 156))
  (segment (start 84.680001 121.119999) (end 83.130001 119.569999) (width 0.15) (layer "B.Cu") (net 156))
  (segment (start 78.1 119) (end 78.1 116.8) (width 0.15) (layer "B.Cu") (net 156))
  (segment (start 86.450001 123.749999) (end 86.15 124.05) (width 0.15) (layer "B.Cu") (net 156))
  (segment (start 71.25 119.65) (end 71.25 120.75) (width 0.15) (layer "B.Cu") (net 156))
  (segment (start 78 119.2) (end 78.4 119.2) (width 0.15) (layer "B.Cu") (net 156))
  (segment (start 73.6 118.6) (end 71.9 118.6) (width 0.155) (layer "B.Cu") (net 156))
  (segment (start 71.25 119.65) (end 71.25 119.25) (width 0.155) (layer "B.Cu") (net 156))
  (segment (start 78.4 119.2) (end 78.3 119.2) (width 0.15) (layer "B.Cu") (net 156))
  (segment (start 86.450001 117.800799) (end 86.450001 123.749999) (width 0.15) (layer "B.Cu") (net 156))
  (segment (start 83.130001 119.569999) (end 82.860002 119.3) (width 0.15) (layer "B.Cu") (net 156))
  (segment (start 85.15 121.589998) (end 84.680001 121.119999) (width 0.15) (layer "B.Cu") (net 156))
  (segment (start 82.760002 119.2) (end 83.130001 119.569999) (width 0.15) (layer "B.Cu") (net 156))
  (segment (start 71.25 119.25) (end 71.9 118.6) (width 0.155) (layer "B.Cu") (net 156))
  (segment (start 77.7 119.2) (end 77.9 119.2) (width 0.15) (layer "B.Cu") (net 156))
  (segment (start 76.743702 119.2) (end 77.7 119.2) (width 0.15) (layer "B.Cu") (net 156))
  (segment (start 78.1 119) (end 78.1 119.1) (width 0.15) (layer "B.Cu") (net 156))
  (segment (start 77.9 119.2) (end 78.1 119) (width 0.15) (layer "B.Cu") (net 156))
  (segment (start 78.1 116.8) (end 77.91 116.61) (width 0.15) (layer "B.Cu") (net 156))
  (segment (start 76.743702 119.2) (end 75.791201 118.247499) (width 0.15) (layer "B.Cu") (net 156))
  (segment (start 87 117.2508) (end 86.450001 117.800799) (width 0.15) (layer "B.Cu") (net 156))
  (segment (start 72.125028 132.925028) (end 73.149979 133.949979) (width 0.15) (layer "F.Cu") (net 157))
  (segment (start 72.399999 125.700001) (end 72.125028 125.974972) (width 0.15) (layer "F.Cu") (net 157))
  (segment (start 78.6 137.35) (end 78.95 137.7) (width 0.15) (layer "F.Cu") (net 157))
  (segment (start 78.6 134.411078) (end 78.6 137.35) (width 0.15) (layer "F.Cu") (net 157))
  (segment (start 73.2476 125.700001) (end 72.399999 125.700001) (width 0.15) (layer "F.Cu") (net 157))
  (segment (start 73.149979 133.949979) (end 78.138901 133.949979) (width 0.15) (layer "F.Cu") (net 157))
  (segment (start 78.138901 133.949979) (end 78.6 134.411078) (width 0.15) (layer "F.Cu") (net 157))
  (segment (start 72.125028 125.974972) (end 72.125028 132.925028) (width 0.15) (layer "F.Cu") (net 157))
  (via (at 78.95 137.7) (size 0.6) (drill 0.25) (layers "F.Cu" "B.Cu") (net 157))
  (segment (start 78.824993 137.074993) (end 78.2458 137.074993) (width 0.15) (layer "B.Cu") (net 157))
  (segment (start 78.95 137.2) (end 78.824993 137.074993) (width 0.15) (layer "B.Cu") (net 157))
  (segment (start 78.95 137.7) (end 78.95 137.2) (width 0.15) (layer "B.Cu") (net 157))
  (segment (start 71.575008 133.152852) (end 72.922155 134.499999) (width 0.15) (layer "F.Cu") (net 158))
  (segment (start 72.922155 134.499999) (end 74.219999 134.499999) (width 0.15) (layer "F.Cu") (net 158))
  (segment (start 73.297601 124.65) (end 71.95 124.65) (width 0.15) (layer "F.Cu") (net 158))
  (segment (start 74.219999 134.499999) (end 74.46 134.74) (width 0.15) (layer "F.Cu") (net 158))
  (segment (start 71.575008 125.024991) (end 71.575008 133.152852) (width 0.15) (layer "F.Cu") (net 158))
  (segment (start 71.95 124.65) (end 71.8 124.8) (width 0.15) (layer "F.Cu") (net 158))
  (segment (start 71.8 124.8) (end 71.575008 125.024991) (width 0.15) (layer "F.Cu") (net 158))
  (via (at 74.46 134.74) (size 0.6) (drill 0.25) (layers "F.Cu" "B.Cu") (net 158))
  (via (at 84.05 136.65) (size 0.6) (drill 0.25) (layers "F.Cu" "B.Cu") (net 158))
  (segment (start 82.95 136.65) (end 84.05 136.65) (width 0.15) (layer "In2.Cu") (net 158))
  (segment (start 74.75 134.45) (end 80.75 134.45) (width 0.15) (layer "In2.Cu") (net 158))
  (segment (start 74.46 134.74) (end 74.75 134.45) (width 0.15) (layer "In2.Cu") (net 158))
  (segment (start 80.75 134.45) (end 82.95 136.65) (width 0.15) (layer "In2.Cu") (net 158))
  (segment (start 72.256298 123.55) (end 72.356297 123.649999) (width 0.155) (layer "F.Cu") (net 159))
  (segment (start 72.356297 123.649999) (end 73.297601 123.649999) (width 0.155) (layer "F.Cu") (net 159))
  (segment (start 71.85 123.55) (end 72.256298 123.55) (width 0.155) (layer "F.Cu") (net 159))
  (via (at 71.85 123.55) (size 0.6) (drill 0.25) (layers "F.Cu" "B.Cu") (net 159))
  (via (at 71.85 107.2) (size 0.6) (drill 0.25) (layers "F.Cu" "B.Cu") (net 159))
  (segment (start 72.6 108.6) (end 71.7 108.6) (width 0.15) (layer "In3.Cu") (net 159))
  (segment (start 72.9 120.5) (end 72.9 108.9) (width 0.15) (layer "In3.Cu") (net 159))
  (segment (start 71.3 107.4) (end 71.5 107.2) (width 0.15) (layer "In3.Cu") (net 159))
  (segment (start 71.85 123.55) (end 71.85 123.15) (width 0.15) (layer "In3.Cu") (net 159))
  (segment (start 71.3 108.2) (end 71.3 107.4) (width 0.15) (layer "In3.Cu") (net 159))
  (segment (start 71.8 121.6) (end 72.9 120.5) (width 0.15) (layer "In3.Cu") (net 159))
  (segment (start 71.7 108.6) (end 71.3 108.2) (width 0.15) (layer "In3.Cu") (net 159))
  (segment (start 71.8 123.1) (end 71.8 121.6) (width 0.15) (layer "In3.Cu") (net 159))
  (segment (start 72.9 108.9) (end 72.6 108.6) (width 0.15) (layer "In3.Cu") (net 159))
  (segment (start 71.5 107.2) (end 71.85 107.2) (width 0.15) (layer "In3.Cu") (net 159))
  (segment (start 71.85 123.15) (end 71.8 123.1) (width 0.15) (layer "In3.Cu") (net 159))
  (segment (start 71.85 107.2) (end 72.52 107.2) (width 0.15) (layer "B.Cu") (net 159))
  (segment (start 85.8 133.785) (end 84.9 132.885) (width 0.2) (layer "F.Cu") (net 160))
  (segment (start 85.8 134.345) (end 85.8 133.785) (width 0.2) (layer "F.Cu") (net 160))
  (segment (start 84.77 132.885) (end 83.885 132) (width 0.2) (layer "F.Cu") (net 160))
  (segment (start 106.75 93.15) (end 106.75 89.55) (width 0.125) (layer "F.Cu") (net 161))
  (segment (start 108 95.2) (end 108 94.4) (width 0.125) (layer "F.Cu") (net 161))
  (segment (start 102.2 100.1) (end 103.1 100.1) (width 0.125) (layer "F.Cu") (net 161))
  (segment (start 108 94.4) (end 106.75 93.15) (width 0.125) (layer "F.Cu") (net 161))
  (segment (start 103.1 100.1) (end 108 95.2) (width 0.125) (layer "F.Cu") (net 161))
  (via (at 102.2 100.1) (size 0.6) (drill 0.25) (layers "F.Cu" "B.Cu") (net 161))
  (via (at 100.40818 103.422788) (size 0.6) (drill 0.25) (layers "F.Cu" "B.Cu") (net 161))
  (segment (start 101.752212 103.422788) (end 100.40818 103.422788) (width 0.21) (layer "In2.Cu") (net 161))
  (segment (start 102.2 102.975) (end 101.752212 103.422788) (width 0.21) (layer "In2.Cu") (net 161))
  (segment (start 102.2 100.1) (end 102.2 102.975) (width 0.21) (layer "In2.Cu") (net 161))
  (segment (start 99.176211 103.29844) (end 101.023468 103.29844) (width 0.125) (layer "B.Cu") (net 161))
  (segment (start 102.2 100.1) (end 102.2 99.8508) (width 0.15) (layer "B.Cu") (net 161))
  (segment (start 99.176211 103.29844) (end 100.283832 103.29844) (width 0.125) (layer "B.Cu") (net 161))
  (segment (start 100.283832 103.29844) (end 100.40818 103.422788) (width 0.125) (layer "B.Cu") (net 161))
  (segment (start 102.2 99.8508) (end 102.6 99.4508) (width 0.15) (layer "B.Cu") (net 161))
  (segment (start 108.25001 95.303557) (end 107.903566 95.65) (width 0.125) (layer "F.Cu") (net 162))
  (segment (start 107.25 90.65) (end 107.00001 90.89999) (width 0.125) (layer "F.Cu") (net 162))
  (segment (start 107.903566 95.65) (end 102.853566 100.7) (width 0.125) (layer "F.Cu") (net 162))
  (segment (start 102.853566 100.7) (end 102.8 100.7) (width 0.125) (layer "F.Cu") (net 162))
  (segment (start 107.00001 93.046444) (end 108.25001 94.296443) (width 0.125) (layer "F.Cu") (net 162))
  (segment (start 107.00001 90.89999) (end 107.00001 93.046444) (width 0.125) (layer "F.Cu") (net 162))
  (segment (start 107.25 89.55) (end 107.25 90.65) (width 0.125) (layer "F.Cu") (net 162))
  (segment (start 108.25001 94.296443) (end 108.25001 95.303557) (width 0.125) (layer "F.Cu") (net 162))
  (via (at 96.8 99.2) (size 0.6) (drill 0.25) (layers "F.Cu" "B.Cu") (net 162))
  (via (at 102.8 100.7) (size 0.6) (drill 0.25) (layers "F.Cu" "B.Cu") (net 162))
  (segment (start 102.325 99.2) (end 96.8 99.2) (width 0.21) (layer "In2.Cu") (net 162))
  (segment (start 102.8 100.7) (end 102.8 99.675) (width 0.21) (layer "In2.Cu") (net 162))
  (segment (start 102.8 99.675) (end 102.325 99.2) (width 0.21) (layer "In2.Cu") (net 162))
  (segment (start 96.971211 101.09344) (end 96.971211 100.284402) (width 0.21) (layer "B.Cu") (net 162))
  (segment (start 103.5508 100.7) (end 103.8 100.4508) (width 0.15) (layer "B.Cu") (net 162))
  (segment (start 97.001212 99.401212) (end 96.8 99.2) (width 0.21) (layer "B.Cu") (net 162))
  (segment (start 96.8 98.485) (end 96.8 99.2) (width 0.21) (layer "B.Cu") (net 162))
  (segment (start 97.001212 100.254401) (end 97.001212 99.401212) (width 0.21) (layer "B.Cu") (net 162))
  (segment (start 96.971211 100.284402) (end 97.001212 100.254401) (width 0.21) (layer "B.Cu") (net 162))
  (segment (start 102.8 100.7) (end 103.5508 100.7) (width 0.15) (layer "B.Cu") (net 162))
  (segment (start 103.9 100.007132) (end 108.50002 95.407114) (width 0.125) (layer "F.Cu") (net 163))
  (segment (start 107.749999 90.503567) (end 107.75 89.55) (width 0.125) (layer "F.Cu") (net 163))
  (segment (start 108.50002 95.407114) (end 108.50002 94.192886) (width 0.125) (layer "F.Cu") (net 163))
  (segment (start 107.25002 92.942887) (end 107.25002 91.003546) (width 0.125) (layer "F.Cu") (net 163))
  (segment (start 103.9 101.8) (end 103.9 100.007132) (width 0.125) (layer "F.Cu") (net 163))
  (segment (start 107.25002 91.003546) (end 107.749999 90.503567) (width 0.125) (layer "F.Cu") (net 163))
  (segment (start 108.50002 94.192886) (end 107.25002 92.942887) (width 0.125) (layer "F.Cu") (net 163))
  (via (at 103.9 101.8) (size 0.6) (drill 0.25) (layers "F.Cu" "B.Cu") (net 163))
  (segment (start 99.823467 102.49844) (end 101.064173 101.257734) (width 0.125) (layer "B.Cu") (net 163))
  (segment (start 99.176211 102.49844) (end 99.823467 102.49844) (width 0.125) (layer "B.Cu") (net 163))
  (segment (start 101.064173 100.664173) (end 101.064173 101.257734) (width 0.125) (layer "B.Cu") (net 163))
  (segment (start 102 98.6) (end 103.6 98.6) (width 0.125) (layer "B.Cu") (net 163))
  (segment (start 101.064173 100.664173) (end 101.064173 99.535827) (width 0.125) (layer "B.Cu") (net 163))
  (segment (start 103.6 98.6) (end 104.8 99.8) (width 0.125) (layer "B.Cu") (net 163))
  (segment (start 101.064173 99.535827) (end 102 98.6) (width 0.125) (layer "B.Cu") (net 163))
  (segment (start 103.9 101.8) (end 104.6508 101.8) (width 0.125) (layer "B.Cu") (net 163))
  (segment (start 104.8 99.8) (end 104.8 101.6508) (width 0.125) (layer "B.Cu") (net 163))
  (segment (start 73.4 116) (end 74.1 116) (width 0.155) (layer "F.Cu") (net 164))
  (segment (start 72.085 115.3) (end 72.085 114.085) (width 0.15) (layer "F.Cu") (net 164))
  (segment (start 72.085 115.3) (end 73.04 115.3) (width 0.155) (layer "F.Cu") (net 164))
  (segment (start 74.3 117.5) (end 74.15 117.65) (width 0.155) (layer "F.Cu") (net 164))
  (segment (start 73.04 115.3) (end 73.04 115.64) (width 0.155) (layer "F.Cu") (net 164))
  (segment (start 73.3 117.65) (end 72.55 117.65) (width 0.15) (layer "F.Cu") (net 164))
  (segment (start 72.55 117.65) (end 71.085 119.115) (width 0.15) (layer "F.Cu") (net 164))
  (segment (start 73.04 115.64) (end 73.4 116) (width 0.155) (layer "F.Cu") (net 164))
  (segment (start 74.3 116.2) (end 74.3 117.5) (width 0.155) (layer "F.Cu") (net 164))
  (segment (start 74.15 117.65) (end 73.3 117.65) (width 0.155) (layer "F.Cu") (net 164))
  (segment (start 72.085 114.085) (end 71.4 113.4) (width 0.15) (layer "F.Cu") (net 164))
  (segment (start 74.1 116) (end 74.3 116.2) (width 0.155) (layer "F.Cu") (net 164))
  (segment (start 72.65 117.65) (end 73.3 117.65) (width 0.155) (layer "F.Cu") (net 164))
  (via (at 71.4 113.4) (size 0.6) (drill 0.25) (layers "F.Cu" "B.Cu") (net 164))
  (via (at 85.6 113.2) (size 0.6) (drill 0.25) (layers "F.Cu" "B.Cu") (net 164))
  (segment (start 71.600001 114.000001) (end 71.4 113.8) (width 0.15) (layer "In2.Cu") (net 164))
  (segment (start 77.9 113) (end 77.9 113.8) (width 0.15) (layer "In2.Cu") (net 164))
  (segment (start 85.2 112.8) (end 78.1 112.8) (width 0.15) (layer "In2.Cu") (net 164))
  (segment (start 77.699999 114.000001) (end 71.600001 114.000001) (width 0.15) (layer "In2.Cu") (net 164))
  (segment (start 71.4 113.8) (end 71.4 113.4) (width 0.15) (layer "In2.Cu") (net 164))
  (segment (start 77.9 113.8) (end 77.699999 114.000001) (width 0.15) (layer "In2.Cu") (net 164))
  (segment (start 78.1 112.8) (end 77.9 113) (width 0.15) (layer "In2.Cu") (net 164))
  (segment (start 85.6 113.2) (end 85.2 112.8) (width 0.15) (layer "In2.Cu") (net 164))
  (segment (start 87.8 113.6) (end 87.8 116.6508) (width 0.15) (layer "B.Cu") (net 164))
  (segment (start 85.6 113.2) (end 87.4 113.2) (width 0.15) (layer "B.Cu") (net 164))
  (segment (start 87.8 116.6508) (end 88.4 117.2508) (width 0.15) (layer "B.Cu") (net 164))
  (segment (start 87.4 113.2) (end 87.8 113.6) (width 0.15) (layer "B.Cu") (net 164))
  (segment (start 116.25 112.45) (end 116.25 111.15) (width 0.15) (layer "F.Cu") (net 165))
  (segment (start 116.25 111.15) (end 116.1 111) (width 0.15) (layer "F.Cu") (net 165))
  (segment (start 95.635 127) (end 96.3 127) (width 0.15) (layer "F.Cu") (net 165))
  (via (at 112 123.1) (size 0.6) (drill 0.25) (layers "F.Cu" "B.Cu") (net 165))
  (via (at 96.3 127) (size 0.6) (drill 0.25) (layers "F.Cu" "B.Cu") (net 165))
  (via (at 116.1 111) (size 0.6) (drill 0.25) (layers "F.Cu" "B.Cu") (net 165))
  (segment (start 97.1 126.7) (end 96.8 127) (width 0.15) (layer "In2.Cu") (net 165))
  (segment (start 97.6 124.7) (end 97.6 124.133234) (width 0.15) (layer "In2.Cu") (net 165))
  (segment (start 110.675402 123.124598) (end 111.975402 123.124598) (width 0.15) (layer "In2.Cu") (net 165))
  (segment (start 110.450411 123.349589) (end 110.675402 123.124598) (width 0.15) (layer "In2.Cu") (net 165))
  (segment (start 96.3 127) (end 96.8 127) (width 0.15) (layer "In2.Cu") (net 165))
  (segment (start 98.383645 123.349589) (end 110.450411 123.349589) (width 0.15) (layer "In2.Cu") (net 165))
  (segment (start 97.1 126.3) (end 97.1 126.7) (width 0.15) (layer "In2.Cu") (net 165))
  (segment (start 97.6 125.8) (end 97.1 126.3) (width 0.15) (layer "In2.Cu") (net 165))
  (segment (start 97.6 124.133234) (end 98.383645 123.349589) (width 0.15) (layer "In2.Cu") (net 165))
  (segment (start 111.975402 123.124598) (end 112 123.1) (width 0.15) (layer "In2.Cu") (net 165))
  (segment (start 97.6 124.7) (end 97.6 125.8) (width 0.15) (layer "In2.Cu") (net 165))
  (segment (start 114.9 114.840002) (end 114.670001 115.070001) (width 0.15) (layer "B.Cu") (net 165))
  (segment (start 114.9 112.2) (end 114.9 114.840002) (width 0.15) (layer "B.Cu") (net 165))
  (segment (start 112 123.1) (end 112 117.740002) (width 0.15) (layer "B.Cu") (net 165))
  (segment (start 112 117.740002) (end 112.170001 117.570001) (width 0.15) (layer "B.Cu") (net 165))
  (segment (start 114.670001 115.070001) (end 112.170001 117.570001) (width 0.15) (layer "B.Cu") (net 165))
  (segment (start 116.1 111) (end 114.9 112.2) (width 0.15) (layer "B.Cu") (net 165))
  (segment (start 114.75 114.25) (end 114.75 112.45) (width 0.155) (layer "F.Cu") (net 166))
  (segment (start 95.635 126) (end 96.3 126) (width 0.15) (layer "F.Cu") (net 166))
  (segment (start 114.4 114.5) (end 114.75 114.25) (width 0.155) (layer "F.Cu") (net 166))
  (via (at 96.3 126) (size 0.6) (drill 0.25) (layers "F.Cu" "B.Cu") (net 166))
  (via (at 111.4 122.612654) (size 0.6) (drill 0.25) (layers "F.Cu" "B.Cu") (net 166))
  (via (at 114.4 114.5) (size 0.6) (drill 0.25) (layers "F.Cu" "B.Cu") (net 166))
  (segment (start 97.3 124.044312) (end 98.269733 123.074579) (width 0.15) (layer "In2.Cu") (net 166))
  (segment (start 96.3 126) (end 97 126) (width 0.15) (layer "In2.Cu") (net 166))
  (segment (start 97 126) (end 97.3 125.7) (width 0.15) (layer "In2.Cu") (net 166))
  (segment (start 97.3 125.7) (end 97.3 124.044312) (width 0.15) (layer "In2.Cu") (net 166))
  (segment (start 98.269733 123.074579) (end 110.3 123.074579) (width 0.15) (layer "In2.Cu") (net 166))
  (segment (start 110.761925 122.612654) (end 111.4 122.612654) (width 0.15) (layer "In2.Cu") (net 166))
  (segment (start 110.3 123.074579) (end 110.761925 122.612654) (width 0.15) (layer "In2.Cu") (net 166))
  (segment (start 111.75 117.15) (end 114.4 114.5) (width 0.15) (layer "B.Cu") (net 166))
  (segment (start 111.4 117.5) (end 111.75 117.15) (width 0.15) (layer "B.Cu") (net 166))
  (segment (start 111.4 122.612654) (end 111.4 117.5) (width 0.15) (layer "B.Cu") (net 166))
  (segment (start 114.25 112.45) (end 114.25 113.691364) (width 0.155) (layer "F.Cu") (net 167))
  (segment (start 95.635 128) (end 96.3 128) (width 0.15) (layer "F.Cu") (net 167))
  (segment (start 114.25 113.691364) (end 114.239244 113.70212) (width 0.155) (layer "F.Cu") (net 167))
  (via (at 96.3 128) (size 0.6) (drill 0.25) (layers "F.Cu" "B.Cu") (net 167))
  (via (at 110.998689 123.624599) (size 0.6) (drill 0.25) (layers "F.Cu" "B.Cu") (net 167))
  (via (at 114.239244 113.70212) (size 0.6) (drill 0.25) (layers "F.Cu" "B.Cu") (net 167))
  (segment (start 97.9 124.222156) (end 98.497557 123.624599) (width 0.15) (layer "In2.Cu") (net 167))
  (segment (start 97.37501 126.42499) (end 97.37501 126.82499) (width 0.15) (layer "In2.Cu") (net 167))
  (segment (start 97.9 125.9) (end 97.37501 126.42499) (width 0.15) (layer "In2.Cu") (net 167))
  (segment (start 97.37501 126.82499) (end 97.1 127.1) (width 0.15) (layer "In2.Cu") (net 167))
  (segment (start 97.9 124.8) (end 97.9 124.222156) (width 0.15) (layer "In2.Cu") (net 167))
  (segment (start 98.675401 123.624599) (end 110.998689 123.624599) (width 0.15) (layer "In2.Cu") (net 167))
  (segment (start 97.1 127.7) (end 96.8 128) (width 0.15) (layer "In2.Cu") (net 167))
  (segment (start 97.1 127.1) (end 97.1 127.7) (width 0.15) (layer "In2.Cu") (net 167))
  (segment (start 96.3 128) (end 96.8 128) (width 0.15) (layer "In2.Cu") (net 167))
  (segment (start 97.9 124.8) (end 97.9 125.9) (width 0.15) (layer "In2.Cu") (net 167))
  (segment (start 98.497557 123.624599) (end 98.675401 123.624599) (width 0.15) (layer "In2.Cu") (net 167))
  (segment (start 112.091984 116.4) (end 110.945992 117.545992) (width 0.155) (layer "B.Cu") (net 167))
  (segment (start 113.795309 114.146055) (end 113.795309 114.696676) (width 0.155) (layer "B.Cu") (net 167))
  (segment (start 110.852906 121.947094) (end 110.852906 123.478816) (width 0.15) (layer "B.Cu") (net 167))
  (segment (start 110.945992 117.545992) (end 110.852906 117.639078) (width 0.15) (layer "B.Cu") (net 167))
  (segment (start 114.239244 113.70212) (end 113.795309 114.146055) (width 0.155) (layer "B.Cu") (net 167))
  (segment (start 110.852906 123.478816) (end 110.998689 123.624599) (width 0.15) (layer "B.Cu") (net 167))
  (segment (start 110.852906 117.639078) (end 110.852906 121.652906) (width 0.15) (layer "B.Cu") (net 167))
  (segment (start 113.795309 114.696676) (end 112.091984 116.4) (width 0.155) (layer "B.Cu") (net 167))
  (segment (start 110.852906 121.652906) (end 110.852906 121.947094) (width 0.15) (layer "B.Cu") (net 167))
  (segment (start 95.635 129) (end 96.3 129) (width 0.15) (layer "F.Cu") (net 168))
  (segment (start 116.75 111.075003) (end 116.825003 111) (width 0.15) (layer "F.Cu") (net 168))
  (segment (start 116.75 112.45) (end 116.75 111.075003) (width 0.15) (layer "F.Cu") (net 168))
  (via (at 116.825003 111) (size 0.6) (drill 0.25) (layers "F.Cu" "B.Cu") (net 168))
  (via (at 96.3 129) (size 0.6) (drill 0.25) (layers "F.Cu" "B.Cu") (net 168))
  (via (at 112.6 123.7) (size 0.6) (drill 0.25) (layers "F.Cu" "B.Cu") (net 168))
  (segment (start 110.8 124.2) (end 112.1 124.2) (width 0.15) (layer "In2.Cu") (net 168))
  (segment (start 110.499609 123.899609) (end 110.8 124.2) (width 0.15) (layer "In2.Cu") (net 168))
  (segment (start 97.1 128.8) (end 97.1 128.088922) (width 0.15) (layer "In2.Cu") (net 168))
  (segment (start 112.1 124.2) (end 112.6 123.7) (width 0.15) (layer "In2.Cu") (net 168))
  (segment (start 96.3 129) (end 96.9 129) (width 0.15) (layer "In2.Cu") (net 168))
  (segment (start 96.9 129) (end 97.1 128.8) (width 0.15) (layer "In2.Cu") (net 168))
  (segment (start 97.1 128.088922) (end 97.37501 127.813912) (width 0.15) (layer "In2.Cu") (net 168))
  (segment (start 98.17501 126.013912) (end 98.17501 124.336068) (width 0.15) (layer "In2.Cu") (net 168))
  (segment (start 97.37501 127.213912) (end 97.65002 126.938902) (width 0.15) (layer "In2.Cu") (net 168))
  (segment (start 98.17501 124.336068) (end 98.611469 123.899609) (width 0.15) (layer "In2.Cu") (net 168))
  (segment (start 97.37501 127.813912) (end 97.37501 127.213912) (width 0.15) (layer "In2.Cu") (net 168))
  (segment (start 98.611469 123.899609) (end 110.499609 123.899609) (width 0.15) (layer "In2.Cu") (net 168))
  (segment (start 97.65002 126.938902) (end 97.65002 126.538902) (width 0.15) (layer "In2.Cu") (net 168))
  (segment (start 97.65002 126.538902) (end 98.17501 126.013912) (width 0.15) (layer "In2.Cu") (net 168))
  (segment (start 115.3 112.525003) (end 116.825003 111) (width 0.15) (layer "B.Cu") (net 168))
  (segment (start 115.17501 112.62499) (end 115.274997 112.525003) (width 0.15) (layer "B.Cu") (net 168))
  (segment (start 115.17501 114.953914) (end 115.17501 112.62499) (width 0.15) (layer "B.Cu") (net 168))
  (segment (start 115.274997 112.525003) (end 115.3 112.525003) (width 0.15) (layer "B.Cu") (net 168))
  (segment (start 112.6 123.7) (end 112.6 117.528924) (width 0.15) (layer "B.Cu") (net 168))
  (segment (start 112.6 117.528924) (end 115.17501 114.953914) (width 0.15) (layer "B.Cu") (net 168))
  (segment (start 95.8 132.65) (end 94.65 132.65) (width 0.15) (layer "F.Cu") (net 169))
  (segment (start 86.3 139.1) (end 85.95 139.45) (width 0.15) (layer "F.Cu") (net 169))
  (segment (start 85.95 139.45) (end 85.95 139.6) (width 0.15) (layer "F.Cu") (net 169))
  (segment (start 86.3 138.205) (end 86.3 139.1) (width 0.15) (layer "F.Cu") (net 169))
  (via (at 94.65 132.65) (size 0.6) (drill 0.25) (layers "F.Cu" "B.Cu") (net 169))
  (via (at 85.95 139.6) (size 0.6) (drill 0.25) (layers "F.Cu" "B.Cu") (net 169))
  (segment (start 87.92501 136.663912) (end 87.92501 134.47499) (width 0.15) (layer "B.Cu") (net 169))
  (segment (start 88.349981 134.050019) (end 93.369247 134.050019) (width 0.15) (layer "B.Cu") (net 169))
  (segment (start 85.95 139.6) (end 85.95 138.638922) (width 0.15) (layer "B.Cu") (net 169))
  (segment (start 93.369247 134.050019) (end 94.65 132.769266) (width 0.15) (layer "B.Cu") (net 169))
  (segment (start 94.65 132.769266) (end 94.65 132.65) (width 0.15) (layer "B.Cu") (net 169))
  (segment (start 85.95 138.638922) (end 87.92501 136.663912) (width 0.15) (layer "B.Cu") (net 169))
  (segment (start 94.65 132.65) (end 95.3992 132.65) (width 0.125) (layer "B.Cu") (net 169))
  (segment (start 87.92501 134.47499) (end 88.349981 134.050019) (width 0.15) (layer "B.Cu") (net 169))
  (segment (start 95.8 131.6) (end 94.65 131.6) (width 0.2) (layer "F.Cu") (net 170))
  (segment (start 84.797804 135.525) (end 84.101055 134.828251) (width 0.15) (layer "F.Cu") (net 170))
  (segment (start 84.101055 134.828251) (end 84.101055 134.822566) (width 0.15) (layer "F.Cu") (net 170))
  (via (at 94.65 131.6) (size 0.6) (drill 0.25) (layers "F.Cu" "B.Cu") (net 170))
  (via (at 84.101055 134.822566) (size 0.6) (drill 0.25) (layers "F.Cu" "B.Cu") (net 170))
  (segment (start 93.4 125.2) (end 93.4 126) (width 0.15) (layer "B.Cu") (net 170))
  (segment (start 95.8 130.8) (end 95.8 131.0508) (width 0.15) (layer "B.Cu") (net 170))
  (segment (start 95.6 131.2508) (end 94.9992 131.2508) (width 0.15) (layer "B.Cu") (net 170))
  (segment (start 95.8 125.2) (end 95.4 124.8) (width 0.15) (layer "B.Cu") (net 170))
  (segment (start 95.4 124.8) (end 93.8 124.8) (width 0.15) (layer "B.Cu") (net 170))
  (segment (start 89.390387 126.34998) (end 84.324991 131.415377) (width 0.15) (layer "B.Cu") (net 170))
  (segment (start 84.32499 134.47501) (end 84.101055 134.698945) (width 0.15) (layer "B.Cu") (net 170))
  (segment (start 84.101055 134.698945) (end 84.101055 134.822566) (width 0.15) (layer "B.Cu") (net 170))
  (segment (start 95.8 130) (end 95.8 125.2) (width 0.15) (layer "B.Cu") (net 170))
  (segment (start 95.8 130) (end 95.8 130.4) (width 0.15) (layer "B.Cu") (net 170))
  (segment (start 95.8 130.4) (end 95.8 130.6) (width 0.15) (layer "B.Cu") (net 170))
  (segment (start 95.8 130.6) (end 95.8 130.8) (width 0.15) (layer "B.Cu") (net 170))
  (segment (start 93.05002 126.34998) (end 89.390387 126.34998) (width 0.15) (layer "B.Cu") (net 170))
  (segment (start 93.4 126) (end 93.05002 126.34998) (width 0.15) (layer "B.Cu") (net 170))
  (segment (start 93.8 124.8) (end 93.4 125.2) (width 0.15) (layer "B.Cu") (net 170))
  (segment (start 94.9992 131.2508) (end 94.65 131.6) (width 0.15) (layer "B.Cu") (net 170))
  (segment (start 84.324991 131.415377) (end 84.32499 134.47501) (width 0.15) (layer "B.Cu") (net 170))
  (segment (start 95.8 130.8) (end 95.8 130.7) (width 0.15) (layer "B.Cu") (net 170))
  (segment (start 82.2 100.05) (end 82.2 101.285) (width 0.15) (layer "F.Cu") (net 171))
  (segment (start 82.185 102.3) (end 82.185 101.3) (width 0.15) (layer "F.Cu") (net 171))
  (segment (start 122.335 124.05) (end 122.335 123.05) (width 0.15) (layer "B.Cu") (net 172))
  (segment (start 123.55 122.9) (end 122.485 122.9) (width 0.15) (layer "B.Cu") (net 172))
  (segment (start 72.7 116.3) (end 72.085 116.3) (width 0.155) (layer "F.Cu") (net 173))
  (segment (start 72.085 117.3) (end 72.085 116.3) (width 0.155) (layer "F.Cu") (net 173))
  (segment (start 73.1 116.7) (end 72.7 116.3) (width 0.155) (layer "F.Cu") (net 173))
  (segment (start 62.605 106.788) (end 62.605 105.19) (width 0.15) (layer "B.Cu") (net 174))
  (segment (start 61.5 124.2) (end 62.475 123.225) (width 0.25) (layer "B.Cu") (net 175))
  (segment (start 57.8 124.2) (end 61.5 124.2) (width 0.25) (layer "B.Cu") (net 175))
  (segment (start 62.475 120.925) (end 62.85 120.55) (width 0.25) (layer "B.Cu") (net 175))
  (segment (start 62.85 120.55) (end 64 120.55) (width 0.25) (layer "B.Cu") (net 175))
  (segment (start 62.475 122.75) (end 62.475 120.925) (width 0.25) (layer "B.Cu") (net 175))
  (segment (start 56.875 123.275) (end 57.8 124.2) (width 0.25) (layer "B.Cu") (net 175))
  (segment (start 128.750001 118.550004) (end 128.750001 117.349853) (width 0.125) (layer "F.Cu") (net 176))
  (segment (start 128.875001 117.224853) (end 128.875 117.204109) (width 0.125) (layer "F.Cu") (net 176))
  (segment (start 128.750001 117.349853) (end 128.875001 117.224853) (width 0.125) (layer "F.Cu") (net 176))
  (segment (start 138.77322 120.749999) (end 138.84822 120.674999) (width 0.125) (layer "F.Cu") (net 176))
  (segment (start 138.77322 121.5) (end 138.77322 120.749999) (width 0.125) (layer "F.Cu") (net 176))
  (segment (start 128.875 117.204109) (end 128.6375 116.966609) (width 0.125) (layer "F.Cu") (net 176))
  (segment (start 136.843673 118.356327) (end 137.17955 118.356327) (width 0.125) (layer "F.Cu") (net 176))
  (segment (start 137.17955 118.356327) (end 137.36161 118.538387) (width 0.125) (layer "F.Cu") (net 176))
  (segment (start 137.403046 118.719929) (end 137.386043 118.755236) (width 0.125) (layer "F.Cu") (net 176))
  (segment (start 138.066799 119.336758) (end 138.105987 119.336758) (width 0.125) (layer "F.Cu") (net 176))
  (segment (start 137.993287 119.362481) (end 138.028594 119.345478) (width 0.125) (layer "F.Cu") (net 176))
  (segment (start 136.741224 119.462341) (end 136.721271 119.549763) (width 0.125) (layer "F.Cu") (net 176))
  (segment (start 137.411766 118.681724) (end 137.403046 118.719929) (width 0.125) (layer "F.Cu") (net 176))
  (segment (start 137.386043 118.755236) (end 137.36161 118.785874) (width 0.125) (layer "F.Cu") (net 176))
  (segment (start 136.87077 119.912484) (end 136.940877 119.968392) (width 0.125) (layer "F.Cu") (net 176))
  (segment (start 136.741224 119.726856) (end 136.780131 119.807647) (width 0.125) (layer "F.Cu") (net 176))
  (segment (start 136.83604 119.877754) (end 136.87077 119.912484) (width 0.125) (layer "F.Cu") (net 176))
  (segment (start 136.940877 119.968392) (end 137.021667 120.007299) (width 0.125) (layer "F.Cu") (net 176))
  (segment (start 138.028594 119.345478) (end 138.066799 119.336758) (width 0.125) (layer "F.Cu") (net 176))
  (segment (start 138.84822 120.024997) (end 138.84822 120.674999) (width 0.125) (layer "F.Cu") (net 176))
  (segment (start 137.366973 119.968392) (end 137.43708 119.912484) (width 0.125) (layer "F.Cu") (net 176))
  (segment (start 137.386043 118.569025) (end 137.403046 118.604332) (width 0.125) (layer "F.Cu") (net 176))
  (segment (start 137.19876 120.027252) (end 137.286183 120.007299) (width 0.125) (layer "F.Cu") (net 176))
  (segment (start 136.83604 119.311443) (end 136.780131 119.381551) (width 0.125) (layer "F.Cu") (net 176))
  (segment (start 138.144192 119.345478) (end 138.179499 119.362481) (width 0.125) (layer "F.Cu") (net 176))
  (segment (start 137.286183 120.007299) (end 137.366973 119.968392) (width 0.125) (layer "F.Cu") (net 176))
  (segment (start 137.403046 118.604332) (end 137.411766 118.642537) (width 0.125) (layer "F.Cu") (net 176))
  (segment (start 137.36161 118.538387) (end 137.386043 118.569025) (width 0.125) (layer "F.Cu") (net 176))
  (segment (start 137.36161 118.785874) (end 136.83604 119.311443) (width 0.125) (layer "F.Cu") (net 176))
  (segment (start 137.10909 120.027252) (end 137.19876 120.027252) (width 0.125) (layer "F.Cu") (net 176))
  (segment (start 137.411766 118.642537) (end 137.411766 118.681724) (width 0.125) (layer "F.Cu") (net 176))
  (segment (start 137.962649 119.386914) (end 137.993287 119.362481) (width 0.125) (layer "F.Cu") (net 176))
  (segment (start 137.43708 119.912484) (end 137.962649 119.386914) (width 0.125) (layer "F.Cu") (net 176))
  (segment (start 136.780131 119.381551) (end 136.741224 119.462341) (width 0.125) (layer "F.Cu") (net 176))
  (segment (start 136.721271 119.639434) (end 136.741224 119.726856) (width 0.125) (layer "F.Cu") (net 176))
  (segment (start 138.105987 119.336758) (end 138.144192 119.345478) (width 0.125) (layer "F.Cu") (net 176))
  (segment (start 137.021667 120.007299) (end 137.10909 120.027252) (width 0.125) (layer "F.Cu") (net 176))
  (segment (start 136.721271 119.549763) (end 136.721271 119.639434) (width 0.125) (layer "F.Cu") (net 176))
  (segment (start 136.780131 119.807647) (end 136.83604 119.877754) (width 0.125) (layer "F.Cu") (net 176))
  (segment (start 138.179499 119.362481) (end 138.210138 119.386915) (width 0.125) (layer "F.Cu") (net 176))
  (segment (start 138.210138 119.386915) (end 138.84822 120.024997) (width 0.125) (layer "F.Cu") (net 176))
  (via (at 128.6375 116.966609) (size 0.6) (drill 0.25) (layers "F.Cu" "B.Cu") (net 176))
  (via (at 136.843673 118.356327) (size 0.6) (drill 0.25) (layers "F.Cu" "B.Cu") (net 176))
  (segment (start 135.177271 114.897064) (end 135.197063 114.877272) (width 0.125) (layer "B.Cu") (net 176))
  (segment (start 130.387621 115.970765) (end 130.396865 115.997185) (width 0.125) (layer "B.Cu") (net 176))
  (segment (start 134.072914 117.791968) (end 134.115009 117.724974) (width 0.125) (layer "B.Cu") (net 176))
  (segment (start 132.753331 117.925) (end 132.796668 117.925) (width 0.125) (layer "B.Cu") (net 176))
  (segment (start 132.352936 114.877272) (end 132.372728 114.897064) (width 0.125) (layer "B.Cu") (net 176))
  (segment (start 133.15 117.571669) (end 133.15 116.925) (width 0.125) (layer "B.Cu") (net 176))
  (segment (start 135.162378 114.920765) (end 135.177271 114.897064) (width 0.125) (layer "B.Cu") (net 176))
  (segment (start 133.15 116.925) (end 133.153134 116.897185) (width 0.125) (layer "B.Cu") (net 176))
  (segment (start 130.875292 117.916142) (end 130.949973 117.89001) (width 0.125) (layer "B.Cu") (net 176))
  (segment (start 132.674707 117.916142) (end 132.753331 117.925) (width 0.125) (layer "B.Cu") (net 176))
  (segment (start 130.533032 117.847915) (end 130.600026 117.89001) (width 0.125) (layer "B.Cu") (net 176))
  (segment (start 130.072914 117.791968) (end 130.115009 117.724974) (width 0.125) (layer "B.Cu") (net 176))
  (segment (start 131.396865 115.947185) (end 131.4 115.975) (width 0.125) (layer "B.Cu") (net 176))
  (segment (start 135.15 114.975) (end 135.153134 114.947185) (width 0.125) (layer "B.Cu") (net 176))
  (segment (start 132.372728 114.897064) (end 132.387621 114.920765) (width 0.125) (layer "B.Cu") (net 176))
  (segment (start 132.197063 114.877272) (end 132.220764 114.862379) (width 0.125) (layer "B.Cu") (net 176))
  (segment (start 131.408858 117.650293) (end 131.43499 117.724974) (width 0.125) (layer "B.Cu") (net 176))
  (segment (start 133.302815 116.803135) (end 133.329235 116.812379) (width 0.125) (layer "B.Cu") (net 176))
  (segment (start 134.674707 117.916142) (end 134.753331 117.925) (width 0.125) (layer "B.Cu") (net 176))
  (segment (start 132.275 114.85) (end 132.302815 114.853135) (width 0.125) (layer "B.Cu") (net 176))
  (segment (start 135.115009 117.724974) (end 135.141141 117.650293) (width 0.125) (layer "B.Cu") (net 176))
  (segment (start 130.247184 115.903135) (end 130.275 115.9) (width 0.125) (layer "B.Cu") (net 176))
  (segment (start 129.348222 117.925) (end 129.796668 117.925) (width 0.125) (layer "B.Cu") (net 176))
  (segment (start 132.302815 114.853135) (end 132.329235 114.862379) (width 0.125) (layer "B.Cu") (net 176))
  (segment (start 134.372728 116.797064) (end 134.387621 116.820765) (width 0.125) (layer "B.Cu") (net 176))
  (segment (start 132.408858 117.650293) (end 132.43499 117.724974) (width 0.125) (layer "B.Cu") (net 176))
  (segment (start 135.247184 114.853135) (end 135.275 114.85) (width 0.125) (layer "B.Cu") (net 176))
  (segment (start 135.016967 117.847915) (end 135.072914 117.791968) (width 0.125) (layer "B.Cu") (net 176))
  (segment (start 134.275 116.75) (end 134.302815 116.753135) (width 0.125) (layer "B.Cu") (net 176))
  (segment (start 131.796668 117.925) (end 131.875292 117.916142) (width 0.125) (layer "B.Cu") (net 176))
  (segment (start 130.197063 115.927272) (end 130.220764 115.912379) (width 0.125) (layer "B.Cu") (net 176))
  (segment (start 131.43499 117.724974) (end 131.477085 117.791968) (width 0.125) (layer "B.Cu") (net 176))
  (segment (start 133.533032 117.847915) (end 133.600026 117.89001) (width 0.125) (layer "B.Cu") (net 176))
  (segment (start 130.302815 115.903135) (end 130.329235 115.912379) (width 0.125) (layer "B.Cu") (net 176))
  (segment (start 135.387621 114.920765) (end 135.396865 114.947185) (width 0.125) (layer "B.Cu") (net 176))
  (segment (start 131.177271 115.897064) (end 131.197063 115.877272) (width 0.125) (layer "B.Cu") (net 176))
  (segment (start 133.016967 117.847915) (end 133.072914 117.791968) (width 0.125) (layer "B.Cu") (net 176))
  (segment (start 130.115009 117.724974) (end 130.141141 117.650293) (width 0.125) (layer "B.Cu") (net 176))
  (segment (start 130.372728 115.947064) (end 130.387621 115.970765) (width 0.125) (layer "B.Cu") (net 176))
  (segment (start 132.387621 114.920765) (end 132.396865 114.947185) (width 0.125) (layer "B.Cu") (net 176))
  (segment (start 133.4 117.571669) (end 133.408858 117.650293) (width 0.125) (layer "B.Cu") (net 176))
  (segment (start 132.43499 117.724974) (end 132.477085 117.791968) (width 0.125) (layer "B.Cu") (net 176))
  (segment (start 135.302815 114.853135) (end 135.329235 114.862379) (width 0.125) (layer "B.Cu") (net 176))
  (segment (start 133.197063 116.827272) (end 133.220764 116.812379) (width 0.125) (layer "B.Cu") (net 176))
  (segment (start 132.220764 114.862379) (end 132.247184 114.853135) (width 0.125) (layer "B.Cu") (net 176))
  (segment (start 134.396865 116.847185) (end 134.4 116.875) (width 0.125) (layer "B.Cu") (net 176))
  (segment (start 134.302815 116.753135) (end 134.329235 116.762379) (width 0.125) (layer "B.Cu") (net 176))
  (segment (start 132.477085 117.791968) (end 132.533032 117.847915) (width 0.125) (layer "B.Cu") (net 176))
  (segment (start 133.141141 117.650293) (end 133.15 117.571669) (width 0.125) (layer "B.Cu") (net 176))
  (segment (start 134.4 116.875) (end 134.4 117.571669) (width 0.125) (layer "B.Cu") (net 176))
  (segment (start 130.275 115.9) (end 130.302815 115.903135) (width 0.125) (layer "B.Cu") (net 176))
  (segment (start 133.153134 116.897185) (end 133.162378 116.870765) (width 0.125) (layer "B.Cu") (net 176))
  (segment (start 130.396865 115.997185) (end 130.4 116.025) (width 0.125) (layer "B.Cu") (net 176))
  (segment (start 136.843673 118.356327) (end 136.843673 118.02045) (width 0.125) (layer "B.Cu") (net 176))
  (segment (start 130.408858 117.650293) (end 130.43499 117.724974) (width 0.125) (layer "B.Cu") (net 176))
  (segment (start 135.372728 114.897064) (end 135.387621 114.920765) (width 0.125) (layer "B.Cu") (net 176))
  (segment (start 130.4 117.571669) (end 130.408858 117.650293) (width 0.125) (layer "B.Cu") (net 176))
  (segment (start 130.753331 117.925) (end 130.796668 117.925) (width 0.125) (layer "B.Cu") (net 176))
  (segment (start 131.197063 115.877272) (end 131.220764 115.862379) (width 0.125) (layer "B.Cu") (net 176))
  (segment (start 135.275 114.85) (end 135.302815 114.853135) (width 0.125) (layer "B.Cu") (net 176))
  (segment (start 131.533032 117.847915) (end 131.600026 117.89001) (width 0.125) (layer "B.Cu") (net 176))
  (segment (start 130.674707 117.916142) (end 130.753331 117.925) (width 0.125) (layer "B.Cu") (net 176))
  (segment (start 135.329235 114.862379) (end 135.352936 114.877272) (width 0.125) (layer "B.Cu") (net 176))
  (segment (start 130.15 117.571669) (end 130.15 116.025) (width 0.125) (layer "B.Cu") (net 176))
  (segment (start 132.949973 117.89001) (end 133.016967 117.847915) (width 0.125) (layer "B.Cu") (net 176))
  (segment (start 134.153134 116.847185) (end 134.162378 116.820765) (width 0.125) (layer "B.Cu") (net 176))
  (segment (start 132.177271 114.897064) (end 132.197063 114.877272) (width 0.125) (layer "B.Cu") (net 176))
  (segment (start 132.533032 117.847915) (end 132.600026 117.89001) (width 0.125) (layer "B.Cu") (net 176))
  (segment (start 130.949973 117.89001) (end 131.016967 117.847915) (width 0.125) (layer "B.Cu") (net 176))
  (segment (start 134.875292 117.916142) (end 134.949973 117.89001) (width 0.125) (layer "B.Cu") (net 176))
  (segment (start 132.875292 117.916142) (end 132.949973 117.89001) (width 0.125) (layer "B.Cu") (net 176))
  (segment (start 131.141141 117.650293) (end 131.15 117.571669) (width 0.125) (layer "B.Cu") (net 176))
  (segment (start 134.477085 117.791968) (end 134.533032 117.847915) (width 0.125) (layer "B.Cu") (net 176))
  (segment (start 132.600026 117.89001) (end 132.674707 117.916142) (width 0.125) (layer "B.Cu") (net 176))
  (segment (start 134.600026 117.89001) (end 134.674707 117.916142) (width 0.125) (layer "B.Cu") (net 176))
  (segment (start 133.177271 116.847064) (end 133.197063 116.827272) (width 0.125) (layer "B.Cu") (net 176))
  (segment (start 131.352936 115.877272) (end 131.372728 115.897064) (width 0.125) (layer "B.Cu") (net 176))
  (segment (start 131.600026 117.89001) (end 131.674707 117.916142) (width 0.125) (layer "B.Cu") (net 176))
  (segment (start 134.016967 117.847915) (end 134.072914 117.791968) (width 0.125) (layer "B.Cu") (net 176))
  (segment (start 131.072914 117.791968) (end 131.115009 117.724974) (width 0.125) (layer "B.Cu") (net 176))
  (segment (start 134.4 117.571669) (end 134.408858 117.650293) (width 0.125) (layer "B.Cu") (net 176))
  (segment (start 133.220764 116.812379) (end 133.247184 116.803135) (width 0.125) (layer "B.Cu") (net 176))
  (segment (start 130.600026 117.89001) (end 130.674707 117.916142) (width 0.125) (layer "B.Cu") (net 176))
  (segment (start 133.247184 116.803135) (end 133.275 116.8) (width 0.125) (layer "B.Cu") (net 176))
  (segment (start 128.875 117.204109) (end 128.875 117.451778) (width 0.125) (layer "B.Cu") (net 176))
  (segment (start 134.247184 116.753135) (end 134.275 116.75) (width 0.125) (layer "B.Cu") (net 176))
  (segment (start 132.4 117.571669) (end 132.408858 117.650293) (width 0.125) (layer "B.Cu") (net 176))
  (segment (start 136.843673 118.02045) (end 136.748223 117.925) (width 0.125) (layer "B.Cu") (net 176))
  (segment (start 135.477085 117.791968) (end 135.533032 117.847915) (width 0.125) (layer "B.Cu") (net 176))
  (segment (start 133.072914 117.791968) (end 133.115009 117.724974) (width 0.125) (layer "B.Cu") (net 176))
  (segment (start 132.072914 117.791968) (end 132.115009 117.724974) (width 0.125) (layer "B.Cu") (net 176))
  (segment (start 132.796668 117.925) (end 132.875292 117.916142) (width 0.125) (layer "B.Cu") (net 176))
  (segment (start 131.753331 117.925) (end 131.796668 117.925) (width 0.125) (layer "B.Cu") (net 176))
  (segment (start 132.115009 117.724974) (end 132.141141 117.650293) (width 0.125) (layer "B.Cu") (net 176))
  (segment (start 131.247184 115.853135) (end 131.275 115.85) (width 0.125) (layer "B.Cu") (net 176))
  (segment (start 130.477085 117.791968) (end 130.533032 117.847915) (width 0.125) (layer "B.Cu") (net 176))
  (segment (start 133.115009 117.724974) (end 133.141141 117.650293) (width 0.125) (layer "B.Cu") (net 176))
  (segment (start 131.477085 117.791968) (end 131.533032 117.847915) (width 0.125) (layer "B.Cu") (net 176))
  (segment (start 130.329235 115.912379) (end 130.352936 115.927272) (width 0.125) (layer "B.Cu") (net 176))
  (segment (start 130.220764 115.912379) (end 130.247184 115.903135) (width 0.125) (layer "B.Cu") (net 176))
  (segment (start 130.43499 117.724974) (end 130.477085 117.791968) (width 0.125) (layer "B.Cu") (net 176))
  (segment (start 135.153134 114.947185) (end 135.162378 114.920765) (width 0.125) (layer "B.Cu") (net 176))
  (segment (start 132.15 117.571669) (end 132.15 114.975) (width 0.125) (layer "B.Cu") (net 176))
  (segment (start 130.141141 117.650293) (end 130.15 117.571669) (width 0.125) (layer "B.Cu") (net 176))
  (segment (start 131.220764 115.862379) (end 131.247184 115.853135) (width 0.125) (layer "B.Cu") (net 176))
  (segment (start 131.329235 115.862379) (end 131.352936 115.877272) (width 0.125) (layer "B.Cu") (net 176))
  (segment (start 135.4 117.571669) (end 135.408858 117.650293) (width 0.125) (layer "B.Cu") (net 176))
  (segment (start 130.4 116.025) (end 130.4 117.571669) (width 0.125) (layer "B.Cu") (net 176))
  (segment (start 134.796668 117.925) (end 134.875292 117.916142) (width 0.125) (layer "B.Cu") (net 176))
  (segment (start 129.796668 117.925) (end 129.875292 117.916142) (width 0.125) (layer "B.Cu") (net 176))
  (segment (start 131.4 117.571669) (end 131.408858 117.650293) (width 0.125) (layer "B.Cu") (net 176))
  (segment (start 135.533032 117.847915) (end 135.600026 117.89001) (width 0.125) (layer "B.Cu") (net 176))
  (segment (start 132.162378 114.920765) (end 132.177271 114.897064) (width 0.125) (layer "B.Cu") (net 176))
  (segment (start 130.016967 117.847915) (end 130.072914 117.791968) (width 0.125) (layer "B.Cu") (net 176))
  (segment (start 134.177271 116.797064) (end 134.197063 116.777272) (width 0.125) (layer "B.Cu") (net 176))
  (segment (start 135.352936 114.877272) (end 135.372728 114.897064) (width 0.125) (layer "B.Cu") (net 176))
  (segment (start 133.600026 117.89001) (end 133.674707 117.916142) (width 0.125) (layer "B.Cu") (net 176))
  (segment (start 130.153134 115.997185) (end 130.162378 115.970765) (width 0.125) (layer "B.Cu") (net 176))
  (segment (start 134.329235 116.762379) (end 134.352936 116.777272) (width 0.125) (layer "B.Cu") (net 176))
  (segment (start 133.4 116.925) (end 133.4 117.571669) (width 0.125) (layer "B.Cu") (net 176))
  (segment (start 134.533032 117.847915) (end 134.600026 117.89001) (width 0.125) (layer "B.Cu") (net 176))
  (segment (start 134.220764 116.762379) (end 134.247184 116.753135) (width 0.125) (layer "B.Cu") (net 176))
  (segment (start 133.372728 116.847064) (end 133.387621 116.870765) (width 0.125) (layer "B.Cu") (net 176))
  (segment (start 133.396865 116.897185) (end 133.4 116.925) (width 0.125) (layer "B.Cu") (net 176))
  (segment (start 131.949973 117.89001) (end 132.016967 117.847915) (width 0.125) (layer "B.Cu") (net 176))
  (segment (start 130.15 116.025) (end 130.153134 115.997185) (width 0.125) (layer "B.Cu") (net 176))
  (segment (start 131.15 117.571669) (end 131.15 115.975) (width 0.125) (layer "B.Cu") (net 176))
  (segment (start 133.753331 117.925) (end 133.796668 117.925) (width 0.125) (layer "B.Cu") (net 176))
  (segment (start 131.115009 117.724974) (end 131.141141 117.650293) (width 0.125) (layer "B.Cu") (net 176))
  (segment (start 133.796668 117.925) (end 133.875292 117.916142) (width 0.125) (layer "B.Cu") (net 176))
  (segment (start 129.875292 117.916142) (end 129.949973 117.89001) (width 0.125) (layer "B.Cu") (net 176))
  (segment (start 133.329235 116.812379) (end 133.352936 116.827272) (width 0.125) (layer "B.Cu") (net 176))
  (segment (start 133.408858 117.650293) (end 133.43499 117.724974) (width 0.125) (layer "B.Cu") (net 176))
  (segment (start 133.477085 117.791968) (end 133.533032 117.847915) (width 0.125) (layer "B.Cu") (net 176))
  (segment (start 131.372728 115.897064) (end 131.387621 115.920765) (width 0.125) (layer "B.Cu") (net 176))
  (segment (start 136.748223 117.925) (end 135.753331 117.925) (width 0.125) (layer "B.Cu") (net 176))
  (segment (start 134.162378 116.820765) (end 134.177271 116.797064) (width 0.125) (layer "B.Cu") (net 176))
  (segment (start 128.6375 116.966609) (end 128.875 117.204109) (width 0.125) (layer "B.Cu") (net 176))
  (segment (start 131.275 115.85) (end 131.302815 115.853135) (width 0.125) (layer "B.Cu") (net 176))
  (segment (start 134.949973 117.89001) (end 135.016967 117.847915) (width 0.125) (layer "B.Cu") (net 176))
  (segment (start 131.387621 115.920765) (end 131.396865 115.947185) (width 0.125) (layer "B.Cu") (net 176))
  (segment (start 134.115009 117.724974) (end 134.141141 117.650293) (width 0.125) (layer "B.Cu") (net 176))
  (segment (start 130.162378 115.970765) (end 130.177271 115.947064) (width 0.125) (layer "B.Cu") (net 176))
  (segment (start 133.949973 117.89001) (end 134.016967 117.847915) (width 0.125) (layer "B.Cu") (net 176))
  (segment (start 135.220764 114.862379) (end 135.247184 114.853135) (width 0.125) (layer "B.Cu") (net 176))
  (segment (start 135.408858 117.650293) (end 135.43499 117.724974) (width 0.125) (layer "B.Cu") (net 176))
  (segment (start 134.352936 116.777272) (end 134.372728 116.797064) (width 0.125) (layer "B.Cu") (net 176))
  (segment (start 132.15 114.975) (end 132.153134 114.947185) (width 0.125) (layer "B.Cu") (net 176))
  (segment (start 133.275 116.8) (end 133.302815 116.803135) (width 0.125) (layer "B.Cu") (net 176))
  (segment (start 133.43499 117.724974) (end 133.477085 117.791968) (width 0.125) (layer "B.Cu") (net 176))
  (segment (start 132.4 114.975) (end 132.4 117.571669) (width 0.125) (layer "B.Cu") (net 176))
  (segment (start 134.197063 116.777272) (end 134.220764 116.762379) (width 0.125) (layer "B.Cu") (net 176))
  (segment (start 131.15 115.975) (end 131.153134 115.947185) (width 0.125) (layer "B.Cu") (net 176))
  (segment (start 134.408858 117.650293) (end 134.43499 117.724974) (width 0.125) (layer "B.Cu") (net 176))
  (segment (start 135.197063 114.877272) (end 135.220764 114.862379) (width 0.125) (layer "B.Cu") (net 176))
  (segment (start 134.753331 117.925) (end 134.796668 117.925) (width 0.125) (layer "B.Cu") (net 176))
  (segment (start 134.15 117.571669) (end 134.15 116.875) (width 0.125) (layer "B.Cu") (net 176))
  (segment (start 135.396865 114.947185) (end 135.4 114.975) (width 0.125) (layer "B.Cu") (net 176))
  (segment (start 135.072914 117.791968) (end 135.115009 117.724974) (width 0.125) (layer "B.Cu") (net 176))
  (segment (start 131.674707 117.916142) (end 131.753331 117.925) (width 0.125) (layer "B.Cu") (net 176))
  (segment (start 128.875 117.451778) (end 129.348222 117.925) (width 0.125) (layer "B.Cu") (net 176))
  (segment (start 135.43499 117.724974) (end 135.477085 117.791968) (width 0.125) (layer "B.Cu") (net 176))
  (segment (start 131.016967 117.847915) (end 131.072914 117.791968) (width 0.125) (layer "B.Cu") (net 176))
  (segment (start 132.153134 114.947185) (end 132.162378 114.920765) (width 0.125) (layer "B.Cu") (net 176))
  (segment (start 129.949973 117.89001) (end 130.016967 117.847915) (width 0.125) (layer "B.Cu") (net 176))
  (segment (start 134.387621 116.820765) (end 134.396865 116.847185) (width 0.125) (layer "B.Cu") (net 176))
  (segment (start 132.396865 114.947185) (end 132.4 114.975) (width 0.125) (layer "B.Cu") (net 176))
  (segment (start 131.4 115.975) (end 131.4 117.571669) (width 0.125) (layer "B.Cu") (net 176))
  (segment (start 130.177271 115.947064) (end 130.197063 115.927272) (width 0.125) (layer "B.Cu") (net 176))
  (segment (start 131.875292 117.916142) (end 131.949973 117.89001) (width 0.125) (layer "B.Cu") (net 176))
  (segment (start 133.387621 116.870765) (end 133.396865 116.897185) (width 0.125) (layer "B.Cu") (net 176))
  (segment (start 134.15 116.875) (end 134.153134 116.847185) (width 0.125) (layer "B.Cu") (net 176))
  (segment (start 133.162378 116.870765) (end 133.177271 116.847064) (width 0.125) (layer "B.Cu") (net 176))
  (segment (start 131.302815 115.853135) (end 131.329235 115.862379) (width 0.125) (layer "B.Cu") (net 176))
  (segment (start 134.141141 117.650293) (end 134.15 117.571669) (width 0.125) (layer "B.Cu") (net 176))
  (segment (start 135.141141 117.650293) (end 135.15 117.571669) (width 0.125) (layer "B.Cu") (net 176))
  (segment (start 135.674707 117.916142) (end 135.753331 117.925) (width 0.125) (layer "B.Cu") (net 176))
  (segment (start 132.247184 114.853135) (end 132.275 114.85) (width 0.125) (layer "B.Cu") (net 176))
  (segment (start 131.162378 115.920765) (end 131.177271 115.897064) (width 0.125) (layer "B.Cu") (net 176))
  (segment (start 133.674707 117.916142) (end 133.753331 117.925) (width 0.125) (layer "B.Cu") (net 176))
  (segment (start 134.43499 117.724974) (end 134.477085 117.791968) (width 0.125) (layer "B.Cu") (net 176))
  (segment (start 133.352936 116.827272) (end 133.372728 116.847064) (width 0.125) (layer "B.Cu") (net 176))
  (segment (start 135.600026 117.89001) (end 135.674707 117.916142) (width 0.125) (layer "B.Cu") (net 176))
  (segment (start 135.15 117.571669) (end 135.15 114.975) (width 0.125) (layer "B.Cu") (net 176))
  (segment (start 132.329235 114.862379) (end 132.352936 114.877272) (width 0.125) (layer "B.Cu") (net 176))
  (segment (start 135.4 114.975) (end 135.4 117.571669) (width 0.125) (layer "B.Cu") (net 176))
  (segment (start 132.016967 117.847915) (end 132.072914 117.791968) (width 0.125) (layer "B.Cu") (net 176))
  (segment (start 132.141141 117.650293) (end 132.15 117.571669) (width 0.125) (layer "B.Cu") (net 176))
  (segment (start 133.875292 117.916142) (end 133.949973 117.89001) (width 0.125) (layer "B.Cu") (net 176))
  (segment (start 131.153134 115.947185) (end 131.162378 115.920765) (width 0.125) (layer "B.Cu") (net 176))
  (segment (start 130.796668 117.925) (end 130.875292 117.916142) (width 0.125) (layer "B.Cu") (net 176))
  (segment (start 130.352936 115.927272) (end 130.372728 115.947064) (width 0.125) (layer "B.Cu") (net 176))
  (segment (start 95.124372 105.432933) (end 95.149173 105.457734) (width 0.2) (layer "F.Cu") (net 177))
  (segment (start 94.413774 105.432933) (end 95.124372 105.432933) (width 0.2) (layer "F.Cu") (net 177))
  (segment (start 101.049174 105.057734) (end 101.049174 105.657734) (width 0.25) (layer "F.Cu") (net 177))
  (segment (start 101.049174 105.657734) (end 100.749174 105.957734) (width 0.25) (layer "F.Cu") (net 177))
  (segment (start 99.949174 105.957733) (end 100.349174 105.957734) (width 0.25) (layer "F.Cu") (net 177))
  (segment (start 100.349174 105.957734) (end 100.749174 105.957734) (width 0.25) (layer "F.Cu") (net 177))
  (segment (start 99.449174 105.457733) (end 99.949174 105.957733) (width 0.25) (layer "F.Cu") (net 177))
  (segment (start 101.064174 104.257734) (end 101.064174 102.315) (width 0.2) (layer "F.Cu") (net 177))
  (segment (start 98.249173 105.457734) (end 98.557734 105.457734) (width 0.25) (layer "F.Cu") (net 177))
  (segment (start 96 100.471211) (end 96.471211 100) (width 0.25) (layer "F.Cu") (net 177))
  (segment (start 95.149173 105.457734) (end 98.057734 105.457734) (width 0.25) (layer "F.Cu") (net 177))
  (segment (start 97.935 101.8) (end 100.549174 101.8) (width 0.25) (layer "F.Cu") (net 177))
  (segment (start 98.057734 105.457734) (end 98.249173 105.457734) (width 0.25) (layer "F.Cu") (net 177))
  (segment (start 101.049174 105.057734) (end 101.049174 104.272734) (width 0.23) (layer "F.Cu") (net 177))
  (segment (start 97 100.865) (end 97 100.528789) (width 0.25) (layer "F.Cu") (net 177))
  (segment (start 101.064174 102.315) (end 100.549174 101.8) (width 0.2) (layer "F.Cu") (net 177))
  (segment (start 96 100.865) (end 96 100.471211) (width 0.25) (layer "F.Cu") (net 177))
  (segment (start 98.557734 105.457734) (end 99.449174 105.457733) (width 0.25) (layer "F.Cu") (net 177))
  (segment (start 97 100.528789) (end 96.471211 100) (width 0.25) (layer "F.Cu") (net 177))
  (segment (start 97 100.865) (end 97.935 101.8) (width 0.25) (layer "F.Cu") (net 177))
  (via (at 95.149173 105.457734) (size 0.6) (drill 0.25) (layers "F.Cu" "B.Cu") (net 177))
  (via (at 101.049174 105.057734) (size 0.6) (drill 0.25) (layers "F.Cu" "B.Cu") (net 177))
  (via (at 73.4 143.4) (size 0.6) (drill 0.25) (layers "F.Cu" "B.Cu") (net 177))
  (via (at 96.471211 100) (size 0.6) (drill 0.25) (layers "F.Cu" "B.Cu") (net 177))
  (segment (start 91 119.175722) (end 91 134.6) (width 0.2) (layer "In2.Cu") (net 177))
  (segment (start 91 134.6) (end 87.8 137.8) (width 0.2) (layer "In2.Cu") (net 177))
  (segment (start 85.3 137.8) (end 84 139.1) (width 0.2) (layer "In2.Cu") (net 177))
  (segment (start 87.8 137.8) (end 85.3 137.8) (width 0.2) (layer "In2.Cu") (net 177))
  (segment (start 93 106.5) (end 94.9 106.5) (width 0.2) (layer "In2.Cu") (net 177))
  (segment (start 74.5 139.1) (end 73.65 139.95) (width 0.2) (layer "In2.Cu") (net 177))
  (segment (start 73.65 143.15) (end 73.4 143.4) (width 0.2) (layer "In2.Cu") (net 177))
  (segment (start 73.65 139.95) (end 73.65 143.15) (width 0.2) (layer "In2.Cu") (net 177))
  (segment (start 84 139.1) (end 74.5 139.1) (width 0.2) (layer "In2.Cu") (net 177))
  (segment (start 94.9 106.5) (end 95.149173 106.250827) (width 0.2) (layer "In2.Cu") (net 177))
  (segment (start 93 106.5) (end 92.5 107) (width 0.2) (layer "In2.Cu") (net 177))
  (segment (start 92.5 107) (end 92.5 117.675722) (width 0.2) (layer "In2.Cu") (net 177))
  (segment (start 92.5 117.675722) (end 91 119.175722) (width 0.2) (layer "In2.Cu") (net 177))
  (segment (start 95.149173 105.457734) (end 95.149173 106.250827) (width 0.2) (layer "In2.Cu") (net 177))
  (segment (start 95.124372 105.432933) (end 95.149173 105.457734) (width 0.2) (layer "B.Cu") (net 177))
  (segment (start 94.413774 105.432933) (end 95.124372 105.432933) (width 0.2) (layer "B.Cu") (net 177))
  (segment (start 95.503468 105.103439) (end 95.149173 105.457734) (width 0.2) (layer "B.Cu") (net 177))
  (segment (start 95.771211 105.103439) (end 95.503468 105.103439) (width 0.2) (layer "B.Cu") (net 177))
  (segment (start 100.69144 104.7) (end 101.049174 105.057734) (width 0.2) (layer "B.Cu") (net 177))
  (segment (start 99.176211 104.09844) (end 99.555559 104.09844) (width 0.2) (layer "B.Cu") (net 177))
  (segment (start 100 104.7) (end 100.69144 104.7) (width 0.2) (layer "B.Cu") (net 177))
  (segment (start 73.385 145.3) (end 73.385 143.415) (width 0.2) (layer "B.Cu") (net 177))
  (segment (start 96.571211 101.09344) (end 96.571211 100.1) (width 0.23) (layer "B.Cu") (net 177))
  (segment (start 73.385 143.415) (end 73.4 143.4) (width 0.2) (layer "B.Cu") (net 177))
  (segment (start 99.756221 104.299102) (end 99.756221 104.456221) (width 0.2) (layer "B.Cu") (net 177))
  (segment (start 99.555559 104.09844) (end 99.756221 104.299102) (width 0.2) (layer "B.Cu") (net 177))
  (segment (start 96.571211 100.1) (end 96.471211 100) (width 0.23) (layer "B.Cu") (net 177))
  (segment (start 73.385 145.3) (end 73.385 144.3) (width 0.125) (layer "B.Cu") (net 177))
  (segment (start 99.756221 104.456221) (end 100 104.7) (width 0.2) (layer "B.Cu") (net 177))
  (segment (start 101.049174 105.057734) (end 101.049174 104.272734) (width 0.23) (layer "B.Cu") (net 177))
  (segment (start 96.471211 100) (end 95.6 99.128789) (width 0.15) (layer "B.Cu") (net 177))
  (segment (start 95.6 99.128789) (end 95.6 98.8508) (width 0.15) (layer "B.Cu") (net 177))
  (segment (start 73.385 144.3) (end 73.385 143.415) (width 0.125) (layer "B.Cu") (net 177))
  (segment (start 99.176211 105.499771) (end 99.549174 105.872733) (width 0.23) (layer "B.Cu") (net 178))
  (segment (start 99.176211 104.498439) (end 99.176211 105.499771) (width 0.23) (layer "B.Cu") (net 178))
  (segment (start 99.579174 105.872734) (end 100.549174 106.842734) (width 0.23) (layer "B.Cu") (net 178))
  (segment (start 100.549174 106.842734) (end 100.549174 107.799974) (width 0.125) (layer "B.Cu") (net 178))
  (segment (start 100.113852 100.532706) (end 100.478646 100.8975) (width 0.17) (layer "F.Cu") (net 179))
  (segment (start 106 92.885) (end 105.6475 93.2375) (width 0.17) (layer "F.Cu") (net 179))
  (segment (start 99.809795 100.532706) (end 100.113852 100.532706) (width 0.17) (layer "F.Cu") (net 179))
  (segment (start 101.061098 100.8975) (end 101.6475 100.311098) (width 0.17) (layer "F.Cu") (net 179))
  (segment (start 100.478646 100.8975) (end 101.061098 100.8975) (width 0.17) (layer "F.Cu") (net 179))
  (segment (start 101.6475 99.311098) (end 105.6475 95.311098) (width 0.17) (layer "F.Cu") (net 179))
  (segment (start 101.6475 100.311098) (end 101.6475 99.311098) (width 0.17) (layer "F.Cu") (net 179))
  (segment (start 105.6475 93.2375) (end 105.6475 95.311098) (width 0.17) (layer "F.Cu") (net 179))
  (via (at 99.809795 100.532706) (size 0.6) (drill 0.25) (layers "F.Cu" "B.Cu") (net 179))
  (segment (start 99.640462 101.75094) (end 100.1525 101.238902) (width 0.17) (layer "B.Cu") (net 179))
  (segment (start 100.1525 100.571354) (end 100.113852 100.532706) (width 0.17) (layer "B.Cu") (net 179))
  (segment (start 99.176211 101.69844) (end 99.228711 101.75094) (width 0.17) (layer "B.Cu") (net 179))
  (segment (start 100.113852 100.532706) (end 99.809795 100.532706) (width 0.17) (layer "B.Cu") (net 179))
  (segment (start 100.1525 101.238902) (end 100.1525 100.571354) (width 0.17) (layer "B.Cu") (net 179))
  (segment (start 99.228711 101.75094) (end 99.640462 101.75094) (width 0.17) (layer "B.Cu") (net 179))
  (segment (start 100.60084 100.6025) (end 100.938902 100.6025) (width 0.17) (layer "F.Cu") (net 180))
  (segment (start 105 92.885) (end 105.3525 93.2375) (width 0.17) (layer "F.Cu") (net 180))
  (segment (start 100.322449 100.020052) (end 100.322449 100.324109) (width 0.17) (layer "F.Cu") (net 180))
  (segment (start 100.938902 100.6025) (end 101.3525 100.188902) (width 0.17) (layer "F.Cu") (net 180))
  (segment (start 101.3525 100.188902) (end 101.3525 99.188902) (width 0.17) (layer "F.Cu") (net 180))
  (segment (start 105.3525 93.2375) (end 105.3525 95.188902) (width 0.17) (layer "F.Cu") (net 180))
  (segment (start 101.3525 99.188902) (end 105.3525 95.188902) (width 0.17) (layer "F.Cu") (net 180))
  (segment (start 100.322449 100.324109) (end 100.60084 100.6025) (width 0.17) (layer "F.Cu") (net 180))
  (via (at 100.322449 100.020052) (size 0.6) (drill 0.25) (layers "F.Cu" "B.Cu") (net 180))
  (segment (start 99.762658 102.04594) (end 100.4475 101.361098) (width 0.17) (layer "B.Cu") (net 180))
  (segment (start 100.4475 100.44916) (end 100.322449 100.324109) (width 0.17) (layer "B.Cu") (net 180))
  (segment (start 100.4475 101.361098) (end 100.4475 100.44916) (width 0.17) (layer "B.Cu") (net 180))
  (segment (start 100.322449 100.324109) (end 100.322449 100.020052) (width 0.17) (layer "B.Cu") (net 180))
  (segment (start 99.228711 102.04594) (end 99.762658 102.04594) (width 0.17) (layer "B.Cu") (net 180))
  (segment (start 99.176211 102.09844) (end 99.228711 102.04594) (width 0.17) (layer "B.Cu") (net 180))
  (segment (start 100.2 105.25) (end 100.2 104.21001) (width 0.2) (layer "F.Cu") (net 181))
  (segment (start 95.034764 103.700522) (end 93.922186 103.700522) (width 0.2) (layer "F.Cu") (net 181))
  (segment (start 93.922186 103.700522) (end 93.822708 103.8) (width 0.2) (layer "F.Cu") (net 181))
  (segment (start 99.939244 103.8) (end 100.274627 104.135383) (width 0.23) (layer "F.Cu") (net 181))
  (segment (start 100.2 104.21001) (end 100.274627 104.135383) (width 0.2) (layer "F.Cu") (net 181))
  (segment (start 99.485 103.8) (end 99.939244 103.8) (width 0.23) (layer "F.Cu") (net 181))
  (via (at 96.249174 106.157734) (size 0.6) (drill 0.25) (layers "F.Cu" "B.Cu") (net 181))
  (via (at 100.274627 104.135383) (size 0.6) (drill 0.25) (layers "F.Cu" "B.Cu") (net 181))
  (via (at 93.822708 103.8) (size 0.6) (drill 0.25) (layers "F.Cu" "B.Cu") (net 181))
  (via (at 100.2 105.25) (size 0.6) (drill 0.25) (layers "F.Cu" "B.Cu") (net 181))
  (via (at 95 101) (size 0.6) (drill 0.25) (layers "F.Cu" "B.Cu") (net 181))
  (segment (start 96.45 105.25) (end 96.249174 105.049174) (width 0.25) (layer "In3.Cu") (net 181))
  (segment (start 96.25 105.25) (end 96.249174 105.250826) (width 0.25) (layer "In3.Cu") (net 181))
  (segment (start 96.55 105.25) (end 96.25 105.25) (width 0.25) (layer "In3.Cu") (net 181))
  (segment (start 96.249174 105.049174) (end 96.249174 105.250826) (width 0.25) (layer "In3.Cu") (net 181))
  (segment (start 93.822708 102.177292) (end 95 101) (width 0.25) (layer "In3.Cu") (net 181))
  (segment (start 100.2 105.25) (end 96.55 105.25) (width 0.25) (layer "In3.Cu") (net 181))
  (segment (start 96.249174 104.499174) (end 96.249174 105.049174) (width 0.25) (layer "In3.Cu") (net 181))
  (segment (start 96.249174 105.450826) (end 96.249174 106.157734) (width 0.25) (layer "In3.Cu") (net 181))
  (segment (start 93.822708 103.8) (end 95.55 103.8) (width 0.25) (layer "In3.Cu") (net 181))
  (segment (start 96.249174 105.250826) (end 96.249174 105.450826) (width 0.25) (layer "In3.Cu") (net 181))
  (segment (start 95.55 103.8) (end 96.249174 104.499174) (width 0.25) (layer "In3.Cu") (net 181))
  (segment (start 96.55 105.25) (end 96.45 105.25) (width 0.25) (layer "In3.Cu") (net 181))
  (segment (start 93.822708 103.8) (end 93.822708 102.177292) (width 0.25) (layer "In3.Cu") (net 181))
  (segment (start 96.45 105.25) (end 96.249174 105.450826) (width 0.25) (layer "In3.Cu") (net 181))
  (segment (start 101.549173 105.872734) (end 100.549174 105.872733) (width 0.23) (layer "B.Cu") (net 181))
  (segment (start 96.571211 105.835697) (end 96.249174 106.157734) (width 0.2) (layer "B.Cu") (net 181))
  (segment (start 96.571211 105.10344) (end 96.571211 105.835697) (width 0.2) (layer "B.Cu") (net 181))
  (segment (start 96.249174 106.442733) (end 95.734174 106.957733) (width 0.2) (layer "B.Cu") (net 181))
  (segment (start 96.249174 106.157734) (end 96.249174 106.442733) (width 0.2) (layer "B.Cu") (net 181))
  (segment (start 100.549174 105.599174) (end 100.2 105.25) (width 0.2) (layer "B.Cu") (net 181))
  (segment (start 95 100.6508) (end 94.4 100.0508) (width 0.15) (layer "B.Cu") (net 181))
  (segment (start 95.166211 101.166211) (end 95 101) (width 0.2) (layer "B.Cu") (net 181))
  (segment (start 95.166211 101.69844) (end 95.166211 101.166211) (width 0.2) (layer "B.Cu") (net 181))
  (segment (start 94.28344 101.69844) (end 94.085 101.5) (width 0.2) (layer "B.Cu") (net 181))
  (segment (start 95 101) (end 95 100.6508) (width 0.15) (layer "B.Cu") (net 181))
  (segment (start 100.549174 105.872734) (end 100.549174 105.599174) (width 0.2) (layer "B.Cu") (net 181))
  (segment (start 95.166211 101.69844) (end 94.28344 101.69844) (width 0.2) (layer "B.Cu") (net 181))
  (segment (start 93.924268 103.69844) (end 93.822708 103.8) (width 0.2) (layer "B.Cu") (net 181))
  (segment (start 99.176211 103.69844) (end 99.837684 103.69844) (width 0.2) (layer "B.Cu") (net 181))
  (segment (start 95.166211 103.69844) (end 93.924268 103.69844) (width 0.2) (layer "B.Cu") (net 181))
  (segment (start 99.837684 103.69844) (end 100.274627 104.135383) (width 0.2) (layer "B.Cu") (net 181))
  (segment (start 97.371211 106.69477) (end 97.634174 106.957733) (width 0.15) (layer "B.Cu") (net 182))
  (segment (start 97.37121 105.10344) (end 97.371211 106.69477) (width 0.15) (layer "B.Cu") (net 182))
  (segment (start 97.396109 107.195799) (end 97.396109 109.404669) (width 0.15) (layer "B.Cu") (net 182))
  (segment (start 97.634174 106.957733) (end 97.396109 107.195799) (width 0.15) (layer "B.Cu") (net 182))
  (segment (start 97.396109 109.404669) (end 98.086684 110.095243) (width 0.15) (layer "B.Cu") (net 182))
  (segment (start 99.691695 109.630244) (end 98.71111 109.630244) (width 0.15) (layer "B.Cu") (net 182))
  (segment (start 96.971211 106.650696) (end 96.664174 106.957733) (width 0.15) (layer "B.Cu") (net 183))
  (segment (start 96.971211 105.103439) (end 96.971211 106.650696) (width 0.15) (layer "B.Cu") (net 183))
  (segment (start 96.664174 107.57718) (end 95.94611 108.295244) (width 0.15) (layer "B.Cu") (net 183))
  (segment (start 96.664174 106.957733) (end 96.664174 107.57718) (width 0.15) (layer "B.Cu") (net 183))
  (segment (start 94.459104 108.660244) (end 95.58111 108.660244) (width 0.15) (layer "B.Cu") (net 183))
  (segment (start 138.37322 128.5) (end 138.37322 129.405002) (width 0.2) (layer "F.Cu") (net 184))
  (segment (start 138.37322 129.405002) (end 138.178222 129.6) (width 0.2) (layer "F.Cu") (net 184))
  (segment (start 138.178222 129.6) (end 136.6 129.6) (width 0.2) (layer "F.Cu") (net 184))
  (segment (start 135.8 125.6) (end 135.7 125.7) (width 0.2) (layer "F.Cu") (net 184))
  (segment (start 137.47322 125.6) (end 135.8 125.6) (width 0.2) (layer "F.Cu") (net 184))
  (segment (start 134.85 130.05) (end 134.95 130.05) (width 0.25) (layer "F.Cu") (net 184))
  (segment (start 134.185 131.018) (end 133.828 131.375) (width 0.25) (layer "F.Cu") (net 184))
  (segment (start 134.185 130.05) (end 134.185 131.018) (width 0.25) (layer "F.Cu") (net 184))
  (segment (start 134.95 130.05) (end 134.185 130.05) (width 0.25) (layer "F.Cu") (net 184))
  (via (at 136.6 129.6) (size 0.6) (drill 0.25) (layers "F.Cu" "B.Cu") (net 184))
  (via (at 134.85 130.05) (size 0.6) (drill 0.25) (layers "F.Cu" "B.Cu") (net 184))
  (via (at 135.7 125.7) (size 0.6) (drill 0.25) (layers "F.Cu" "B.Cu") (net 184))
  (segment (start 137.39 129.195) (end 137.005 129.195) (width 0.2) (layer "B.Cu") (net 184))
  (segment (start 137.288164 126.212952) (end 136.487048 126.212952) (width 0.25) (layer "B.Cu") (net 184))
  (segment (start 135.4 128.3) (end 135.4 129.6) (width 0.25) (layer "B.Cu") (net 184))
  (segment (start 137.288164 126.212952) (end 136.212952 126.212952) (width 0.25) (layer "B.Cu") (net 184))
  (segment (start 135.4 129.4) (end 135.4 129.6) (width 0.2) (layer "B.Cu") (net 184))
  (segment (start 137.005 129.195) (end 136.6 129.6) (width 0.2) (layer "B.Cu") (net 184))
  (segment (start 137.002047 129.197953) (end 136.6 129.6) (width 0.25) (layer "B.Cu") (net 184))
  (segment (start 135.4 128.3) (end 135.4 129.4) (width 0.2) (layer "B.Cu") (net 184))
  (segment (start 138.388164 129.197953) (end 137.002047 129.197953) (width 0.25) (layer "B.Cu") (net 184))
  (segment (start 136.287048 126.212952) (end 136.1 126.4) (width 0.25) (layer "B.Cu") (net 184))
  (segment (start 135.9 126.6) (end 135.9 127.8) (width 0.25) (layer "B.Cu") (net 184))
  (segment (start 135.6 129.6) (end 135.4 129.4) (width 0.25) (layer "B.Cu") (net 184))
  (segment (start 138.388164 129.197953) (end 137.392953 129.197953) (width 0.2) (layer "B.Cu") (net 184))
  (segment (start 136.1 126.4) (end 135.9 126.6) (width 0.25) (layer "B.Cu") (net 184))
  (segment (start 135.4 129.6) (end 134.85 130.05) (width 0.25) (layer "B.Cu") (net 184))
  (segment (start 136.212952 126.212952) (end 136.1 126.1) (width 0.25) (layer "B.Cu") (net 184))
  (segment (start 136.487048 126.212952) (end 136.287048 126.212952) (width 0.25) (layer "B.Cu") (net 184))
  (segment (start 136.2 129.6) (end 135.4 129.6) (width 0.25) (layer "B.Cu") (net 184))
  (segment (start 136.2 129.6) (end 135.6 129.6) (width 0.25) (layer "B.Cu") (net 184))
  (segment (start 136.6 129.6) (end 136.2 129.6) (width 0.25) (layer "B.Cu") (net 184))
  (segment (start 135.4 129.6) (end 135.6 129.6) (width 0.2) (layer "B.Cu") (net 184))
  (segment (start 136.1 126.1) (end 135.7 125.7) (width 0.25) (layer "B.Cu") (net 184))
  (segment (start 135.9 127.8) (end 135.4 128.3) (width 0.25) (layer "B.Cu") (net 184))
  (segment (start 135.6 129.6) (end 136.6 129.6) (width 0.2) (layer "B.Cu") (net 184))
  (segment (start 136.1 126.1) (end 136.1 126.4) (width 0.25) (layer "B.Cu") (net 184))
  (segment (start 145.9 127.2) (end 146.1 127.4) (width 0.2) (layer "F.Cu") (net 185))
  (segment (start 143.17322 121.5) (end 143.17322 120.42678) (width 0.2) (layer "F.Cu") (net 185))
  (segment (start 146.3875 125.284434) (end 145.988558 125.284434) (width 0.2) (layer "F.Cu") (net 185))
  (segment (start 143.17322 120.42678) (end 143.8 119.8) (width 0.2) (layer "F.Cu") (net 185))
  (segment (start 146.072 122.678) (end 146 122.75) (width 0.25) (layer "F.Cu") (net 185))
  (segment (start 145 121) (end 143.8 119.8) (width 0.25) (layer "F.Cu") (net 185))
  (segment (start 144.47322 127.2) (end 145.9 127.2) (width 0.2) (layer "F.Cu") (net 185))
  (segment (start 145.988558 125.284434) (end 145.672992 125.6) (width 0.2) (layer "F.Cu") (net 185))
  (segment (start 146.072 121) (end 145 121) (width 0.25) (layer "F.Cu") (net 185))
  (segment (start 146.072 121) (end 146.072 122.678) (width 0.25) (layer "F.Cu") (net 185))
  (segment (start 145.672992 125.6) (end 144.47322 125.6) (width 0.2) (layer "F.Cu") (net 185))
  (via (at 143.8 119.8) (size 0.6) (drill 0.25) (layers "F.Cu" "B.Cu") (net 185))
  (via (at 146 122.75) (size 0.6) (drill 0.25) (layers "F.Cu" "B.Cu") (net 185))
  (via (at 146.1 127.4) (size 0.6) (drill 0.25) (layers "F.Cu" "B.Cu") (net 185))
  (via (at 146.3875 125.284434) (size 0.6) (drill 0.25) (layers "F.Cu" "B.Cu") (net 185))
  (segment (start 143.55 120.965) (end 143.55 120.05) (width 0.2) (layer "B.Cu") (net 185))
  (segment (start 146 122.75) (end 146.3008 122.75) (width 0.15) (layer "B.Cu") (net 185))
  (segment (start 146.75 126.838999) (end 146.188999 127.4) (width 0.25) (layer "B.Cu") (net 185))
  (segment (start 145.699999 124.799997) (end 145.500001 124.599999) (width 0.25) (layer "B.Cu") (net 185))
  (segment (start 145.699999 124.400001) (end 145.500001 124.599999) (width 0.25) (layer "B.Cu") (net 185))
  (segment (start 145.699999 124.599999) (end 145.699999 124.800001) (width 0.25) (layer "B.Cu") (net 185))
  (segment (start 145.699999 125.021197) (end 145.963236 125.284434) (width 0.25) (layer "B.Cu") (net 185))
  (segment (start 145.699999 124.800001) (end 145.699999 125.021197) (width 0.25) (layer "B.Cu") (net 185))
  (segment (start 145.085 122.9) (end 145.85 122.9) (width 0.25) (layer "B.Cu") (net 185))
  (segment (start 146.1 128.5) (end 145.45 129.15) (width 0.2) (layer "B.Cu") (net 185))
  (segment (start 146 122.75) (end 145.699999 123.050001) (width 0.25) (layer "B.Cu") (net 185))
  (segment (start 146.1 127.4) (end 146.1 128.5) (width 0.2) (layer "B.Cu") (net 185))
  (segment (start 145.963236 125.284434) (end 146.3875 125.284434) (width 0.25) (layer "B.Cu") (net 185))
  (segment (start 145.699999 124.200001) (end 145.699999 124.599999) (width 0.25) (layer "B.Cu") (net 185))
  (segment (start 146.3875 125.284434) (end 146.75 125.646934) (width 0.25) (layer "B.Cu") (net 185))
  (segment (start 143.55 120.05) (end 143.8 119.8) (width 0.2) (layer "B.Cu") (net 185))
  (segment (start 146.3008 122.75) (end 146.75 122.3008) (width 0.15) (layer "B.Cu") (net 185))
  (segment (start 145.45 129.15) (end 144.585 129.15) (width 0.2) (layer "B.Cu") (net 185))
  (segment (start 146.188999 127.4) (end 146.1 127.4) (width 0.25) (layer "B.Cu") (net 185))
  (segment (start 145.699999 123.050001) (end 145.699999 124.200001) (width 0.25) (layer "B.Cu") (net 185))
  (segment (start 145.85 122.9) (end 146 122.75) (width 0.25) (layer "B.Cu") (net 185))
  (segment (start 145.699999 124.800001) (end 145.699999 124.799997) (width 0.25) (layer "B.Cu") (net 185))
  (segment (start 144.985 124.6) (end 145.280001 124.599999) (width 0.25) (layer "B.Cu") (net 185))
  (segment (start 146.75 125.646934) (end 146.75 126.838999) (width 0.25) (layer "B.Cu") (net 185))
  (segment (start 145.500001 124.599999) (end 145.699999 124.599999) (width 0.25) (layer "B.Cu") (net 185))
  (segment (start 145.699999 124.200001) (end 145.699999 124.400001) (width 0.25) (layer "B.Cu") (net 185))
  (segment (start 145.280001 124.599999) (end 145.500001 124.599999) (width 0.25) (layer "B.Cu") (net 185))
  (segment (start 136.8 122) (end 135.3 120.5) (width 0.15) (layer "F.Cu") (net 186))
  (segment (start 135.3 120.5) (end 134.885 120.5) (width 0.15) (layer "F.Cu") (net 186))
  (segment (start 134.885 120.5) (end 134.885 119.685) (width 0.125) (layer "F.Cu") (net 186))
  (via (at 134.885 119.685) (size 0.6) (drill 0.25) (layers "F.Cu" "B.Cu") (net 186))
  (via (at 122.9 116) (size 0.6) (drill 0.25) (layers "F.Cu" "B.Cu") (net 186))
  (segment (start 134.560009 119.460009) (end 133.260009 119.460009) (width 0.15) (layer "In2.Cu") (net 186))
  (segment (start 130.12499 117.985157) (end 130.12499 116.613912) (width 0.15) (layer "In2.Cu") (net 186))
  (segment (start 134.785 119.685) (end 134.560009 119.460009) (width 0.15) (layer "In2.Cu") (net 186))
  (segment (start 130.739833 118.6) (end 130.12499 117.985157) (width 0.15) (layer "In2.Cu") (net 186))
  (segment (start 133.260009 119.460009) (end 132.4 118.6) (width 0.15) (layer "In2.Cu") (net 186))
  (segment (start 130.12499 116.613912) (end 129.586088 116.07501) (width 0.15) (layer "In2.Cu") (net 186))
  (segment (start 134.885 119.685) (end 134.785 119.685) (width 0.15) (layer "In2.Cu") (net 186))
  (segment (start 132.4 118.6) (end 130.739833 118.6) (width 0.15) (layer "In2.Cu") (net 186))
  (segment (start 122.97501 116.07501) (end 122.9 116) (width 0.15) (layer "In2.Cu") (net 186))
  (segment (start 129.586088 116.07501) (end 122.97501 116.07501) (width 0.15) (layer "In2.Cu") (net 186))
  (segment (start 140.67501 120.12499) (end 139.32499 120.12499) (width 0.15) (layer "B.Cu") (net 186))
  (segment (start 139.32499 120.12499) (end 138.699999 119.499999) (width 0.15) (layer "B.Cu") (net 186))
  (segment (start 135.070001 119.499999) (end 134.885 119.685) (width 0.15) (layer "B.Cu") (net 186))
  (segment (start 121.8 116.385) (end 122.515 116.385) (width 0.125) (layer "B.Cu") (net 186))
  (segment (start 120.8 116.385) (end 121.8 116.385) (width 0.125) (layer "B.Cu") (net 186))
  (segment (start 141 123.4) (end 141 120.44998) (width 0.15) (layer "B.Cu") (net 186))
  (segment (start 119.75 116.2) (end 120.615 116.2) (width 0.2) (layer "B.Cu") (net 186))
  (segment (start 122.515 116.385) (end 122.9 116) (width 0.125) (layer "B.Cu") (net 186))
  (segment (start 138.699999 119.499999) (end 135.070001 119.499999) (width 0.15) (layer "B.Cu") (net 186))
  (segment (start 141 120.44998) (end 140.67501 120.12499) (width 0.15) (layer "B.Cu") (net 186))
  (segment (start 142 123.5508) (end 141.1508 123.5508) (width 0.15) (layer "B.Cu") (net 186))
  (segment (start 141.1508 123.5508) (end 141 123.4) (width 0.15) (layer "B.Cu") (net 186))
  (segment (start 138.835 132.565) (end 138.85 132.55) (width 0.2) (layer "F.Cu") (net 187))
  (segment (start 138.2 132.565) (end 138.835 132.565) (width 0.2) (layer "F.Cu") (net 187))
  (segment (start 138.85 132.55) (end 139.485 132.55) (width 0.2) (layer "F.Cu") (net 187))
  (segment (start 142.7 132.565) (end 142.065 132.565) (width 0.2) (layer "F.Cu") (net 187))
  (segment (start 142.065 132.565) (end 142.05 132.55) (width 0.2) (layer "F.Cu") (net 187))
  (segment (start 142.035 132.565) (end 142.05 132.55) (width 0.2) (layer "F.Cu") (net 187))
  (segment (start 141.4 132.565) (end 142.035 132.565) (width 0.2) (layer "F.Cu") (net 187))
  (segment (start 148.454195 132.55) (end 147.815 132.55) (width 0.2) (layer "F.Cu") (net 187))
  (segment (start 141.97322 129.97322) (end 142 130) (width 0.2) (layer "F.Cu") (net 187))
  (segment (start 141.97322 128.5) (end 141.97322 129.97322) (width 0.2) (layer "F.Cu") (net 187))
  (segment (start 145.9 132.565) (end 145.315 132.565) (width 0.2) (layer "F.Cu") (net 187))
  (segment (start 145.315 132.565) (end 145.25 132.5) (width 0.2) (layer "F.Cu") (net 187))
  (segment (start 144.6 132.565) (end 145.185 132.565) (width 0.2) (layer "F.Cu") (net 187))
  (segment (start 145.185 132.565) (end 145.25 132.5) (width 0.2) (layer "F.Cu") (net 187))
  (segment (start 138.35 132.565) (end 138.835 132.565) (width 0.2) (layer "F.Cu") (net 187))
  (segment (start 136.3 132.565) (end 135.635 132.565) (width 0.25) (layer "F.Cu") (net 187))
  (segment (start 135.635 132.565) (end 135.1 133.1) (width 0.25) (layer "F.Cu") (net 187))
  (via (at 148.454195 132.55) (size 0.6) (drill 0.25) (layers "F.Cu" "B.Cu") (net 187))
  (via (at 142 130) (size 0.6) (drill 0.25) (layers "F.Cu" "B.Cu") (net 187))
  (via (at 138.85 132.55) (size 0.6) (drill 0.25) (layers "F.Cu" "B.Cu") (net 187))
  (via (at 145.25 132.5) (size 0.6) (drill 0.25) (layers "F.Cu" "B.Cu") (net 187))
  (via (at 142.05 132.55) (size 0.6) (drill 0.25) (layers "F.Cu" "B.Cu") (net 187))
  (via (at 135.1 133.1) (size 0.6) (drill 0.25) (layers "F.Cu" "B.Cu") (net 187))
  (segment (start 142.1 132.5) (end 142.05 132.55) (width 0.25) (layer "In3.Cu") (net 187))
  (segment (start 145.3 132.55) (end 145.25 132.5) (width 0.25) (layer "In3.Cu") (net 187))
  (segment (start 145.25 132.5) (end 142.1 132.5) (width 0.25) (layer "In3.Cu") (net 187))
  (segment (start 138.85 132.55) (end 135.65 132.55) (width 0.25) (layer "In3.Cu") (net 187))
  (segment (start 142.05 132.55) (end 138.85 132.55) (width 0.25) (layer "In3.Cu") (net 187))
  (segment (start 148.454195 132.55) (end 145.3 132.55) (width 0.25) (layer "In3.Cu") (net 187))
  (segment (start 135.65 132.55) (end 135.1 133.1) (width 0.25) (layer "In3.Cu") (net 187))
  (segment (start 141.25 130.922) (end 140.978 130.65) (width 0.2) (layer "B.Cu") (net 187))
  (segment (start 141.45 131.95) (end 142.05 132.55) (width 0.25) (layer "B.Cu") (net 187))
  (segment (start 141.335 131.95) (end 141.335 131.007) (width 0.25) (layer "B.Cu") (net 187))
  (segment (start 141.335 131.007) (end 140.978 130.65) (width 0.25) (layer "B.Cu") (net 187))
  (segment (start 141.3 132.8) (end 141.3 131.985) (width 0.15) (layer "B.Cu") (net 187))
  (segment (start 142 130) (end 142 129.535) (width 0.2) (layer "B.Cu") (net 187))
  (segment (start 142 129.535) (end 141.65 129.185) (width 0.2) (layer "B.Cu") (net 187))
  (segment (start 140.978 130.65) (end 140.978 129.857) (width 0.2) (layer "B.Cu") (net 187))
  (segment (start 140.978 129.857) (end 141.65 129.185) (width 0.2) (layer "B.Cu") (net 187))
  (segment (start 137.7 121.5) (end 137.5 121.3) (width 0.2) (layer "F.Cu") (net 188))
  (segment (start 137.5 121.3) (end 137.5 121) (width 0.2) (layer "F.Cu") (net 188))
  (segment (start 137.97322 121.5) (end 137.7 121.5) (width 0.2) (layer "F.Cu") (net 188))
  (segment (start 138.37322 121.5) (end 137.97322 121.5) (width 0.2) (layer "F.Cu") (net 188))
  (segment (start 146.048001 125.949994) (end 146.1 125.949994) (width 0.2) (layer "F.Cu") (net 188))
  (segment (start 136.624278 127.6) (end 136.362139 127.862139) (width 0.2) (layer "F.Cu") (net 188))
  (segment (start 136.362139 128.512139) (end 136.5 128.65) (width 0.2) (layer "F.Cu") (net 188))
  (segment (start 145.597995 126.4) (end 146.048001 125.949994) (width 0.2) (layer "F.Cu") (net 188))
  (segment (start 136.362139 127.862139) (end 136.362139 128.512139) (width 0.2) (layer "F.Cu") (net 188))
  (segment (start 144.47322 126.4) (end 145.597995 126.4) (width 0.2) (layer "F.Cu") (net 188))
  (segment (start 137.47322 127.6) (end 136.624278 127.6) (width 0.2) (layer "F.Cu") (net 188))
  (segment (start 144.47322 126) (end 146.049994 126) (width 0.2) (layer "F.Cu") (net 188))
  (segment (start 146.049994 126) (end 146.1 125.949994) (width 0.2) (layer "F.Cu") (net 188))
  (segment (start 135.723164 129.062953) (end 136.087047 129.062953) (width 0.2) (layer "F.Cu") (net 188))
  (segment (start 136.087047 129.062953) (end 136.5 128.65) (width 0.2) (layer "F.Cu") (net 188))
  (via (at 137.5 121) (size 0.6) (drill 0.25) (layers "F.Cu" "B.Cu") (net 188))
  (via (at 136.5 128.65) (size 0.6) (drill 0.25) (layers "F.Cu" "B.Cu") (net 188))
  (via (at 146.1 125.949994) (size 0.6) (drill 0.25) (layers "F.Cu" "B.Cu") (net 188))
  (segment (start 137.9 126.7) (end 137.6 126.7) (width 0.2) (layer "In3.Cu") (net 188))
  (segment (start 137.9 126.7) (end 139.1 126.7) (width 0.2) (layer "In3.Cu") (net 188))
  (segment (start 137.5 126.7) (end 137.7 126.7) (width 0.2) (layer "In3.Cu") (net 188))
  (segment (start 137.5 121) (end 137.5 126.4) (width 0.2) (layer "In3.Cu") (net 188))
  (segment (start 137.5 126.6) (end 137.5 126.7) (width 0.2) (layer "In3.Cu") (net 188))
  (segment (start 137.7 126.6) (end 137.5 126.4) (width 0.2) (layer "In3.Cu") (net 188))
  (segment (start 136.5 127) (end 136.8 126.7) (width 0.2) (layer "In3.Cu") (net 188))
  (segment (start 136.5 128.65) (end 136.5 127) (width 0.2) (layer "In3.Cu") (net 188))
  (segment (start 137.2 126.7) (end 137.5 126.4) (width 0.2) (layer "In3.Cu") (net 188))
  (segment (start 137.2 126.7) (end 137.5 126.7) (width 0.2) (layer "In3.Cu") (net 188))
  (segment (start 136.8 126.7) (end 137.2 126.7) (width 0.2) (layer "In3.Cu") (net 188))
  (segment (start 139.1 126.7) (end 139.850006 125.949994) (width 0.2) (layer "In3.Cu") (net 188))
  (segment (start 137.7 126.7) (end 137.9 126.7) (width 0.2) (layer "In3.Cu") (net 188))
  (segment (start 137.6 126.7) (end 137.5 126.6) (width 0.2) (layer "In3.Cu") (net 188))
  (segment (start 139.850006 125.949994) (end 146.1 125.949994) (width 0.2) (layer "In3.Cu") (net 188))
  (segment (start 137.7 126.7) (end 137.7 126.6) (width 0.2) (layer "In3.Cu") (net 188))
  (segment (start 137.5 126.4) (end 137.5 126.6) (width 0.2) (layer "In3.Cu") (net 188))
  (segment (start 146.050006 125.949994) (end 146.1 125.949994) (width 0.2) (layer "B.Cu") (net 188))
  (segment (start 135.085003 121.123849) (end 134.728003 120.766849) (width 0.25) (layer "B.Cu") (net 188))
  (segment (start 139.4 121.215) (end 138.4 121.215) (width 0.25) (layer "B.Cu") (net 188))
  (segment (start 145.750006 125.6) (end 144.985 125.6) (width 0.2) (layer "B.Cu") (net 188))
  (segment (start 144.985 126.6) (end 145.4 126.6) (width 0.2) (layer "B.Cu") (net 188))
  (segment (start 138.4 121.215) (end 137.715 121.215) (width 0.25) (layer "B.Cu") (net 188))
  (segment (start 137.715 121.215) (end 137.5 121) (width 0.25) (layer "B.Cu") (net 188))
  (segment (start 134.728003 120.766849) (end 137.266849 120.766849) (width 0.25) (layer "B.Cu") (net 188))
  (segment (start 146.1 125.949994) (end 145.750006 125.6) (width 0.2) (layer "B.Cu") (net 188))
  (segment (start 135.085003 122.066849) (end 135.085003 121.123849) (width 0.25) (layer "B.Cu") (net 188))
  (segment (start 145.4 126.6) (end 146.050006 125.949994) (width 0.2) (layer "B.Cu") (net 188))
  (segment (start 137.266849 120.766849) (end 137.5 121) (width 0.25) (layer "B.Cu") (net 188))
  (segment (start 135.085003 123.066848) (end 135.085003 122.066849) (width 0.25) (layer "B.Cu") (net 188))
  (segment (start 144.47322 125.2) (end 145.4 125.2) (width 0.2) (layer "F.Cu") (net 189))
  (segment (start 144.85 119.4) (end 144.75 119.5) (width 0.25) (layer "F.Cu") (net 189))
  (segment (start 142.77322 120.02678) (end 143 119.8) (width 0.2) (layer "F.Cu") (net 189))
  (segment (start 146.072 119.4) (end 144.85 119.4) (width 0.25) (layer "F.Cu") (net 189))
  (segment (start 147.470569 124.559431) (end 148.33 123.7) (width 0.2) (layer "F.Cu") (net 189))
  (segment (start 145.4 125.2) (end 146.040569 124.559431) (width 0.2) (layer "F.Cu") (net 189))
  (segment (start 146.3875 124.559431) (end 147.470569 124.559431) (width 0.2) (layer "F.Cu") (net 189))
  (segment (start 142.77322 121.5) (end 142.77322 120.02678) (width 0.2) (layer "F.Cu") (net 189))
  (segment (start 146.040569 124.559431) (end 146.3875 124.559431) (width 0.2) (layer "F.Cu") (net 189))
  (via (at 143 119.8) (size 0.6) (drill 0.25) (layers "F.Cu" "B.Cu") (net 189))
  (via (at 144.75 119.5) (size 0.6) (drill 0.25) (layers "F.Cu" "B.Cu") (net 189))
  (via (at 146.3875 124.559431) (size 0.6) (drill 0.25) (layers "F.Cu" "B.Cu") (net 189))
  (segment (start 143 119.8) (end 143 119.5) (width 0.25) (layer "B.Cu") (net 189))
  (segment (start 146.665 120.915) (end 145.665 120.915) (width 0.25) (layer "B.Cu") (net 189))
  (segment (start 145.665 120.915) (end 144.6 120.915) (width 0.25) (layer "B.Cu") (net 189))
  (segment (start 146.3875 124.559431) (end 147.5 123.446931) (width 0.25) (layer "B.Cu") (net 189))
  (segment (start 144.75 119.5) (end 144.450001 119.200001) (width 0.25) (layer "B.Cu") (net 189))
  (segment (start 142.55 120.965) (end 142.55 120.25) (width 0.2) (layer "B.Cu") (net 189))
  (segment (start 143 119.5) (end 143.299999 119.200001) (width 0.25) (layer "B.Cu") (net 189))
  (segment (start 147.5 123.446931) (end 147.5 121.75) (width 0.25) (layer "B.Cu") (net 189))
  (segment (start 144.450001 119.200001) (end 143.299999 119.200001) (width 0.25) (layer "B.Cu") (net 189))
  (segment (start 142.55 120.25) (end 143 119.8) (width 0.2) (layer "B.Cu") (net 189))
  (segment (start 147.5 121.75) (end 146.665 120.915) (width 0.25) (layer "B.Cu") (net 189))
  (segment (start 144.75 119.5) (end 144.75 120.765) (width 0.25) (layer "B.Cu") (net 189))
  (segment (start 145.9 128) (end 145.5 127.6) (width 0.125) (layer "F.Cu") (net 190))
  (segment (start 145.5 127.6) (end 144.47322 127.6) (width 0.125) (layer "F.Cu") (net 190))
  (segment (start 147.1 128.2) (end 146.015 128.2) (width 0.125) (layer "F.Cu") (net 190))
  (segment (start 145.9 128.315) (end 145.9 128) (width 0.125) (layer "F.Cu") (net 190))
  (segment (start 147.238164 128.061836) (end 147.1 128.2) (width 0.125) (layer "F.Cu") (net 190))
  (segment (start 147.238164 127.212952) (end 147.238164 128.061836) (width 0.125) (layer "F.Cu") (net 190))
  (segment (start 148.315 125.75) (end 148.315 126.085) (width 0.125) (layer "F.Cu") (net 190))
  (segment (start 148.315 126.085) (end 147.238164 127.161836) (width 0.125) (layer "F.Cu") (net 190))
  (segment (start 142.051999 130.725003) (end 142 130.725003) (width 0.2) (layer "F.Cu") (net 191))
  (segment (start 142.37322 128.5) (end 142.37322 129.596218) (width 0.2) (layer "F.Cu") (net 191))
  (segment (start 142.525001 129.747999) (end 142.525001 130.252001) (width 0.2) (layer "F.Cu") (net 191))
  (segment (start 142.525001 130.252001) (end 142.051999 130.725003) (width 0.2) (layer "F.Cu") (net 191))
  (segment (start 142.37322 129.596218) (end 142.525001 129.747999) (width 0.2) (layer "F.Cu") (net 191))
  (via (at 142 130.725003) (size 0.6) (drill 0.25) (layers "F.Cu" "B.Cu") (net 191))
  (segment (start 142.715 131.95) (end 142.715 131.007) (width 0.25) (layer "B.Cu") (net 191))
  (segment (start 142.715 131.007) (end 143.072 130.65) (width 0.25) (layer "B.Cu") (net 191))
  (segment (start 143.072 130.65) (end 143.072 129.607) (width 0.2) (layer "B.Cu") (net 191))
  (segment (start 142 130.725003) (end 142.996997 130.725003) (width 0.2) (layer "B.Cu") (net 191))
  (segment (start 142.996997 130.725003) (end 143.072 130.65) (width 0.2) (layer "B.Cu") (net 191))
  (segment (start 142.9 132.8) (end 142.9 132.135) (width 0.15) (layer "B.Cu") (net 191))
  (segment (start 143.072 129.607) (end 142.65 129.185) (width 0.2) (layer "B.Cu") (net 191))
  (segment (start 148.685 130.9) (end 148.685 129.866116) (width 0.125) (layer "F.Cu") (net 192))
  (segment (start 148.1 128.5) (end 149.038164 129.438164) (width 0.125) (layer "F.Cu") (net 192))
  (segment (start 145.1 128.5) (end 145.1 128) (width 0.125) (layer "F.Cu") (net 192))
  (segment (start 146.713614 128.5) (end 148.1 128.5) (width 0.125) (layer "F.Cu") (net 192))
  (segment (start 146.015 129.198614) (end 146.713614 128.5) (width 0.125) (layer "F.Cu") (net 192))
  (segment (start 145.885 129.285) (end 145.1 128.5) (width 0.125) (layer "F.Cu") (net 192))
  (segment (start 146.975 135.81) (end 147.35 135.435) (width 0.125) (layer "F.Cu") (net 193))
  (segment (start 147.09 136.374999) (end 146.975 136.259999) (width 0.125) (layer "F.Cu") (net 193))
  (segment (start 146.975 136.259999) (end 146.975 135.81) (width 0.125) (layer "F.Cu") (net 193))
  (segment (start 147.95 136.035) (end 147.35 135.435) (width 0.125) (layer "F.Cu") (net 193))
  (segment (start 147.09 136.6) (end 147.09 136.374999) (width 0.125) (layer "F.Cu") (net 193))
  (segment (start 147.95 136.365) (end 147.95 136.035) (width 0.125) (layer "F.Cu") (net 193))
  (segment (start 147.8 133.535) (end 147.8 134.015) (width 0.125) (layer "F.Cu") (net 194))
  (segment (start 147.8 134.015) (end 147.35 134.465) (width 0.125) (layer "F.Cu") (net 194))
  (segment (start 146.975 131.798222) (end 146.975 134.09) (width 0.125) (layer "F.Cu") (net 194))
  (segment (start 143.97322 128.5) (end 143.97322 129.311424) (width 0.125) (layer "F.Cu") (net 194))
  (segment (start 146.101778 130.925) (end 146.975 131.798222) (width 0.125) (layer "F.Cu") (net 194))
  (segment (start 143.89822 129.386424) (end 143.89822 129.771442) (width 0.125) (layer "F.Cu") (net 194))
  (segment (start 143.97322 129.311424) (end 143.89822 129.386424) (width 0.125) (layer "F.Cu") (net 194))
  (segment (start 146.975 134.09) (end 147.35 134.465) (width 0.125) (layer "F.Cu") (net 194))
  (segment (start 143.89822 129.771442) (end 145.051778 130.925) (width 0.125) (layer "F.Cu") (net 194))
  (segment (start 145.051778 130.925) (end 146.101778 130.925) (width 0.125) (layer "F.Cu") (net 194))
  (segment (start 146.61 136.6) (end 146.61 136.374999) (width 0.125) (layer "F.Cu") (net 195))
  (segment (start 146.725 135.81) (end 146.35 135.435) (width 0.125) (layer "F.Cu") (net 195))
  (segment (start 145.75 136.035) (end 146.35 135.435) (width 0.125) (layer "F.Cu") (net 195))
  (segment (start 146.725 136.259999) (end 146.725 135.81) (width 0.125) (layer "F.Cu") (net 195))
  (segment (start 145.75 136.365) (end 145.75 136.035) (width 0.125) (layer "F.Cu") (net 195))
  (segment (start 146.61 136.374999) (end 146.725 136.259999) (width 0.125) (layer "F.Cu") (net 195))
  (segment (start 145.9 134.015) (end 146.35 134.465) (width 0.125) (layer "F.Cu") (net 196))
  (segment (start 145.9 133.535) (end 145.9 134.015) (width 0.125) (layer "F.Cu") (net 196))
  (segment (start 145.998222 131.175) (end 146.725 131.901778) (width 0.125) (layer "F.Cu") (net 196))
  (segment (start 146.725 131.901778) (end 146.725 134.09) (width 0.125) (layer "F.Cu") (net 196))
  (segment (start 146.725 134.09) (end 146.35 134.465) (width 0.125) (layer "F.Cu") (net 196))
  (segment (start 143.57322 128.5) (end 143.57322 129.311424) (width 0.125) (layer "F.Cu") (net 196))
  (segment (start 143.57322 129.311424) (end 143.64822 129.386424) (width 0.125) (layer "F.Cu") (net 196))
  (segment (start 143.64822 129.874998) (end 144.948222 131.175) (width 0.125) (layer "F.Cu") (net 196))
  (segment (start 143.64822 129.386424) (end 143.64822 129.874998) (width 0.125) (layer "F.Cu") (net 196))
  (segment (start 144.948222 131.175) (end 145.998222 131.175) (width 0.125) (layer "F.Cu") (net 196))
  (segment (start 143.110598 131.567206) (end 143.125491 131.543505) (width 0.125) (layer "F.Cu") (net 197))
  (segment (start 143.145283 131.523713) (end 143.168984 131.50882) (width 0.125) (layer "F.Cu") (net 197))
  (segment (start 144.08038 131.021149) (end 144.054248 130.946468) (width 0.125) (layer "F.Cu") (net 197))
  (segment (start 143.956206 130.823527) (end 143.889212 130.781432) (width 0.125) (layer "F.Cu") (net 197))
  (segment (start 143.956206 131.419356) (end 144.012153 131.363409) (width 0.125) (layer "F.Cu") (net 197))
  (segment (start 143.09822 131.621442) (end 143.101354 131.593626) (width 0.125) (layer "F.Cu") (net 197))
  (segment (start 143.125491 131.543505) (end 143.145283 131.523713) (width 0.125) (layer "F.Cu") (net 197))
  (segment (start 143.101354 131.593626) (end 143.110598 131.567206) (width 0.125) (layer "F.Cu") (net 197))
  (segment (start 143.22322 131.496442) (end 143.735907 131.496442) (width 0.125) (layer "F.Cu") (net 197))
  (segment (start 144.054248 130.946468) (end 144.012153 130.879474) (width 0.125) (layer "F.Cu") (net 197))
  (segment (start 144.012153 131.363409) (end 144.054248 131.296415) (width 0.125) (layer "F.Cu") (net 197))
  (segment (start 143.168984 131.50882) (end 143.195404 131.499576) (width 0.125) (layer "F.Cu") (net 197))
  (segment (start 143.735907 131.496442) (end 143.814531 131.487583) (width 0.125) (layer "F.Cu") (net 197))
  (segment (start 143.22322 130.746442) (end 143.195404 130.743307) (width 0.125) (layer "F.Cu") (net 197))
  (segment (start 143.775 132.298222) (end 143.09822 131.621442) (width 0.125) (layer "F.Cu") (net 197))
  (segment (start 143.09822 130.621442) (end 143.09822 129.386424) (width 0.125) (layer "F.Cu") (net 197))
  (segment (start 143.168984 130.734063) (end 143.145283 130.71917) (width 0.125) (layer "F.Cu") (net 197))
  (segment (start 143.814531 131.487583) (end 143.889212 131.461451) (width 0.125) (layer "F.Cu") (net 197))
  (segment (start 143.125491 130.699378) (end 143.110598 130.675677) (width 0.125) (layer "F.Cu") (net 197))
  (segment (start 143.145283 130.71917) (end 143.125491 130.699378) (width 0.125) (layer "F.Cu") (net 197))
  (segment (start 144.012153 130.879474) (end 143.956206 130.823527) (width 0.125) (layer "F.Cu") (net 197))
  (segment (start 143.101354 130.649257) (end 143.09822 130.621442) (width 0.125) (layer "F.Cu") (net 197))
  (segment (start 143.110598 130.675677) (end 143.101354 130.649257) (width 0.125) (layer "F.Cu") (net 197))
  (segment (start 143.09822 129.386424) (end 143.17322 129.311424) (width 0.125) (layer "F.Cu") (net 197))
  (segment (start 144.6 134.015) (end 144.15 134.465) (width 0.125) (layer "F.Cu") (net 197))
  (segment (start 144.089239 131.099773) (end 144.08038 131.021149) (width 0.125) (layer "F.Cu") (net 197))
  (segment (start 144.6 133.535) (end 144.6 134.015) (width 0.125) (layer "F.Cu") (net 197))
  (segment (start 144.089239 131.14311) (end 144.089239 131.099773) (width 0.125) (layer "F.Cu") (net 197))
  (segment (start 143.195404 130.743307) (end 143.168984 130.734063) (width 0.125) (layer "F.Cu") (net 197))
  (segment (start 143.814531 130.7553) (end 143.735907 130.746442) (width 0.125) (layer "F.Cu") (net 197))
  (segment (start 144.054248 131.296415) (end 144.08038 131.221734) (width 0.125) (layer "F.Cu") (net 197))
  (segment (start 144.15 134.465) (end 143.775 134.09) (width 0.125) (layer "F.Cu") (net 197))
  (segment (start 143.735907 130.746442) (end 143.22322 130.746442) (width 0.125) (layer "F.Cu") (net 197))
  (segment (start 143.889212 131.461451) (end 143.956206 131.419356) (width 0.125) (layer "F.Cu") (net 197))
  (segment (start 144.08038 131.221734) (end 144.089239 131.14311) (width 0.125) (layer "F.Cu") (net 197))
  (segment (start 143.17322 129.311424) (end 143.17322 128.5) (width 0.125) (layer "F.Cu") (net 197))
  (segment (start 143.775 134.09) (end 143.775 132.298222) (width 0.125) (layer "F.Cu") (net 197))
  (segment (start 143.195404 131.499576) (end 143.22322 131.496442) (width 0.125) (layer "F.Cu") (net 197))
  (segment (start 143.889212 130.781432) (end 143.814531 130.7553) (width 0.125) (layer "F.Cu") (net 197))
  (segment (start 143.775 136.259999) (end 143.775 135.81) (width 0.125) (layer "F.Cu") (net 198))
  (segment (start 143.775 135.81) (end 144.15 135.435) (width 0.125) (layer "F.Cu") (net 198))
  (segment (start 144.75 136.365) (end 144.75 136.035) (width 0.125) (layer "F.Cu") (net 198))
  (segment (start 144.75 136.035) (end 144.15 135.435) (width 0.125) (layer "F.Cu") (net 198))
  (segment (start 143.89 136.6) (end 143.89 136.374999) (width 0.125) (layer "F.Cu") (net 198))
  (segment (start 143.89 136.374999) (end 143.775 136.259999) (width 0.125) (layer "F.Cu") (net 198))
  (segment (start 143.122927 131.2553) (end 143.201551 131.246442) (width 0.125) (layer "F.Cu") (net 199))
  (segment (start 143.714239 131.246442) (end 143.742054 131.243307) (width 0.125) (layer "F.Cu") (net 199))
  (segment (start 143.768474 131.234063) (end 143.792175 131.21917) (width 0.125) (layer "F.Cu") (net 199))
  (segment (start 143.836104 131.149257) (end 143.839239 131.121442) (width 0.125) (layer "F.Cu") (net 199))
  (segment (start 143.792175 131.21917) (end 143.811967 131.199378) (width 0.125) (layer "F.Cu") (net 199))
  (segment (start 143.82686 131.067206) (end 143.811967 131.043505) (width 0.125) (layer "F.Cu") (net 199))
  (segment (start 143.742054 131.243307) (end 143.768474 131.234063) (width 0.125) (layer "F.Cu") (net 199))
  (segment (start 143.839239 131.121442) (end 143.836104 131.093626) (width 0.125) (layer "F.Cu") (net 199))
  (segment (start 142.84822 130.64311) (end 142.84822 129.386424) (width 0.125) (layer "F.Cu") (net 199))
  (segment (start 143.714239 130.996442) (end 143.201551 130.996442) (width 0.125) (layer "F.Cu") (net 199))
  (segment (start 143.811967 131.043505) (end 143.792175 131.023713) (width 0.125) (layer "F.Cu") (net 199))
  (segment (start 142.981252 131.323527) (end 143.048246 131.281432) (width 0.125) (layer "F.Cu") (net 199))
  (segment (start 143.525 134.09) (end 143.525 132.401778) (width 0.125) (layer "F.Cu") (net 199))
  (segment (start 143.15 134.465) (end 143.525 134.09) (width 0.125) (layer "F.Cu") (net 199))
  (segment (start 142.857078 130.721734) (end 142.84822 130.64311) (width 0.125) (layer "F.Cu") (net 199))
  (segment (start 142.88321 130.796415) (end 142.857078 130.721734) (width 0.125) (layer "F.Cu") (net 199))
  (segment (start 143.201551 130.996442) (end 143.122927 130.987583) (width 0.125) (layer "F.Cu") (net 199))
  (segment (start 142.84822 129.386424) (end 142.77322 129.311424) (width 0.125) (layer "F.Cu") (net 199))
  (segment (start 143.82686 131.175677) (end 143.836104 131.149257) (width 0.125) (layer "F.Cu") (net 199))
  (segment (start 143.811967 131.199378) (end 143.82686 131.175677) (width 0.125) (layer "F.Cu") (net 199))
  (segment (start 142.981252 130.919356) (end 142.925305 130.863409) (width 0.125) (layer "F.Cu") (net 199))
  (segment (start 142.925305 130.863409) (end 142.88321 130.796415) (width 0.125) (layer "F.Cu") (net 199))
  (segment (start 142.88321 131.446468) (end 142.925305 131.379474) (width 0.125) (layer "F.Cu") (net 199))
  (segment (start 142.925305 131.379474) (end 142.981252 131.323527) (width 0.125) (layer "F.Cu") (net 199))
  (segment (start 143.122927 130.987583) (end 143.048246 130.961451) (width 0.125) (layer "F.Cu") (net 199))
  (segment (start 143.048246 130.961451) (end 142.981252 130.919356) (width 0.125) (layer "F.Cu") (net 199))
  (segment (start 143.048246 131.281432) (end 143.122927 131.2553) (width 0.125) (layer "F.Cu") (net 199))
  (segment (start 143.201551 131.246442) (end 143.714239 131.246442) (width 0.125) (layer "F.Cu") (net 199))
  (segment (start 143.836104 131.093626) (end 143.82686 131.067206) (width 0.125) (layer "F.Cu") (net 199))
  (segment (start 142.84822 131.599773) (end 142.857078 131.521149) (width 0.125) (layer "F.Cu") (net 199))
  (segment (start 142.84822 131.724998) (end 142.84822 131.599773) (width 0.125) (layer "F.Cu") (net 199))
  (segment (start 142.857078 131.521149) (end 142.88321 131.446468) (width 0.125) (layer "F.Cu") (net 199))
  (segment (start 142.7 134.015) (end 143.15 134.465) (width 0.125) (layer "F.Cu") (net 199))
  (segment (start 143.792175 131.023713) (end 143.768474 131.00882) (width 0.125) (layer "F.Cu") (net 199))
  (segment (start 143.768474 131.00882) (end 143.742054 130.999576) (width 0.125) (layer "F.Cu") (net 199))
  (segment (start 143.742054 130.999576) (end 143.714239 130.996442) (width 0.125) (layer "F.Cu") (net 199))
  (segment (start 143.525 132.401778) (end 142.84822 131.724998) (width 0.125) (layer "F.Cu") (net 199))
  (segment (start 142.77322 129.311424) (end 142.77322 128.5) (width 0.125) (layer "F.Cu") (net 199))
  (segment (start 142.7 133.535) (end 142.7 134.015) (width 0.125) (layer "F.Cu") (net 199))
  (segment (start 143.525 136.259999) (end 143.525 135.81) (width 0.125) (layer "F.Cu") (net 200))
  (segment (start 143.525 135.81) (end 143.15 135.435) (width 0.125) (layer "F.Cu") (net 200))
  (segment (start 142.55 136.365) (end 142.55 136.035) (width 0.125) (layer "F.Cu") (net 200))
  (segment (start 142.55 136.035) (end 143.15 135.435) (width 0.125) (layer "F.Cu") (net 200))
  (segment (start 143.41 136.6) (end 143.41 136.374999) (width 0.125) (layer "F.Cu") (net 200))
  (segment (start 143.41 136.374999) (end 143.525 136.259999) (width 0.125) (layer "F.Cu") (net 200))
  (segment (start 140.575 136.259999) (end 140.575 135.81) (width 0.125) (layer "F.Cu") (net 201))
  (segment (start 140.575 135.81) (end 140.95 135.435) (width 0.125) (layer "F.Cu") (net 201))
  (segment (start 140.69 136.6) (end 140.69 136.374999) (width 0.125) (layer "F.Cu") (net 201))
  (segment (start 140.69 136.374999) (end 140.575 136.259999) (width 0.125) (layer "F.Cu") (net 201))
  (segment (start 141.55 136.365) (end 141.55 136.035) (width 0.125) (layer "F.Cu") (net 201))
  (segment (start 141.55 136.035) (end 140.95 135.435) (width 0.125) (layer "F.Cu") (net 201))
  (segment (start 141.09822 131.878558) (end 141.09822 131.751888) (width 0.125) (layer "F.Cu") (net 202))
  (segment (start 141.088771 131.668023) (end 141.060897 131.588363) (width 0.125) (layer "F.Cu") (net 202))
  (segment (start 140.069249 131.159919) (end 140.08712 131.131478) (width 0.125) (layer "F.Cu") (net 202))
  (segment (start 140.139312 131.089856) (end 140.171016 131.078762) (width 0.125) (layer "F.Cu") (net 202))
  (segment (start 140.069249 131.290084) (end 140.058155 131.25838) (width 0.125) (layer "F.Cu") (net 202))
  (segment (start 140.204394 131.375002) (end 140.171016 131.371241) (width 0.125) (layer "F.Cu") (net 202))
  (segment (start 141.17322 129.311424) (end 141.17322 128.5) (width 0.125) (layer "F.Cu") (net 202))
  (segment (start 140.058155 131.25838) (end 140.054394 131.225002) (width 0.125) (layer "F.Cu") (net 202))
  (segment (start 140.110871 131.342276) (end 140.08712 131.318525) (width 0.125) (layer "F.Cu") (net 202))
  (segment (start 141.060897 130.86164) (end 141.088771 130.78198) (width 0.125) (layer "F.Cu") (net 202))
  (segment (start 140.95 134.465) (end 140.575 134.09) (width 0.125) (layer "F.Cu") (net 202))
  (segment (start 140.805199 131.384451) (end 140.721334 131.375002) (width 0.125) (layer "F.Cu") (net 202))
  (segment (start 140.575 132.401778) (end 141.09822 131.878558) (width 0.125) (layer "F.Cu") (net 202))
  (segment (start 140.805199 131.065552) (end 140.884859 131.037678) (width 0.125) (layer "F.Cu") (net 202))
  (segment (start 140.721334 131.375002) (end 140.204394 131.375002) (width 0.125) (layer "F.Cu") (net 202))
  (segment (start 141.060897 131.588363) (end 141.015996 131.516903) (width 0.125) (layer "F.Cu") (net 202))
  (segment (start 140.956319 131.457226) (end 140.884859 131.412325) (width 0.125) (layer "F.Cu") (net 202))
  (segment (start 140.884859 131.037678) (end 140.956319 130.992777) (width 0.125) (layer "F.Cu") (net 202))
  (segment (start 140.721334 131.075002) (end 140.805199 131.065552) (width 0.125) (layer "F.Cu") (net 202))
  (segment (start 141.088771 130.78198) (end 141.09822 130.698115) (width 0.125) (layer "F.Cu") (net 202))
  (segment (start 141.015996 130.9331) (end 141.060897 130.86164) (width 0.125) (layer "F.Cu") (net 202))
  (segment (start 141.09822 129.386424) (end 141.17322 129.311424) (width 0.125) (layer "F.Cu") (net 202))
  (segment (start 140.139312 131.360147) (end 140.110871 131.342276) (width 0.125) (layer "F.Cu") (net 202))
  (segment (start 141.015996 131.516903) (end 140.956319 131.457226) (width 0.125) (layer "F.Cu") (net 202))
  (segment (start 140.956319 130.992777) (end 141.015996 130.9331) (width 0.125) (layer "F.Cu") (net 202))
  (segment (start 140.110871 131.107727) (end 140.139312 131.089856) (width 0.125) (layer "F.Cu") (net 202))
  (segment (start 140.171016 131.078762) (end 140.204394 131.075002) (width 0.125) (layer "F.Cu") (net 202))
  (segment (start 140.058155 131.191623) (end 140.069249 131.159919) (width 0.125) (layer "F.Cu") (net 202))
  (segment (start 140.171016 131.371241) (end 140.139312 131.360147) (width 0.125) (layer "F.Cu") (net 202))
  (segment (start 140.054394 131.225002) (end 140.058155 131.191623) (width 0.125) (layer "F.Cu") (net 202))
  (segment (start 141.09822 131.751888) (end 141.088771 131.668023) (width 0.125) (layer "F.Cu") (net 202))
  (segment (start 140.575 134.09) (end 140.575 132.401778) (width 0.125) (layer "F.Cu") (net 202))
  (segment (start 141.09822 130.698115) (end 141.09822 129.386424) (width 0.125) (layer "F.Cu") (net 202))
  (segment (start 140.08712 131.318525) (end 140.069249 131.290084) (width 0.125) (layer "F.Cu") (net 202))
  (segment (start 140.884859 131.412325) (end 140.805199 131.384451) (width 0.125) (layer "F.Cu") (net 202))
  (segment (start 140.08712 131.131478) (end 140.110871 131.107727) (width 0.125) (layer "F.Cu") (net 202))
  (segment (start 141.4 134.015) (end 140.95 134.465) (width 0.125) (layer "F.Cu") (net 202))
  (segment (start 140.204394 131.075002) (end 140.721334 131.075002) (width 0.125) (layer "F.Cu") (net 202))
  (segment (start 141.4 133.535) (end 141.4 134.015) (width 0.125) (layer "F.Cu") (net 202))
  (segment (start 140.21 136.374999) (end 140.325 136.259999) (width 0.125) (layer "F.Cu") (net 203))
  (segment (start 140.325 136.259999) (end 140.325 135.81) (width 0.125) (layer "F.Cu") (net 203))
  (segment (start 140.325 135.81) (end 139.95 135.435) (width 0.125) (layer "F.Cu") (net 203))
  (segment (start 140.21 136.6) (end 140.21 136.374999) (width 0.125) (layer "F.Cu") (net 203))
  (segment (start 139.35 136.365) (end 139.35 136.035) (width 0.125) (layer "F.Cu") (net 203))
  (segment (start 139.35 136.035) (end 139.95 135.435) (width 0.125) (layer "F.Cu") (net 203))
  (segment (start 139.804394 131.201888) (end 139.813844 131.118023) (width 0.125) (layer "F.Cu") (net 204))
  (segment (start 140.731599 131.628762) (end 140.69822 131.625002) (width 0.125) (layer "F.Cu") (net 204))
  (segment (start 139.886619 130.966903) (end 139.946296 130.907226) (width 0.125) (layer "F.Cu") (net 204))
  (segment (start 139.95 134.465) (end 140.325 134.09) (width 0.125) (layer "F.Cu") (net 204))
  (segment (start 140.833366 131.709919) (end 140.815495 131.681478) (width 0.125) (layer "F.Cu") (net 204))
  (segment (start 139.841718 131.038363) (end 139.886619 130.966903) (width 0.125) (layer "F.Cu") (net 204))
  (segment (start 140.84822 129.386424) (end 140.77322 129.311424) (width 0.125) (layer "F.Cu") (net 204))
  (segment (start 140.763303 131.639856) (end 140.731599 131.628762) (width 0.125) (layer "F.Cu") (net 204))
  (segment (start 139.886619 131.4831) (end 139.841718 131.41164) (width 0.125) (layer "F.Cu") (net 204))
  (segment (start 140.097416 131.615552) (end 140.017756 131.587678) (width 0.125) (layer "F.Cu") (net 204))
  (segment (start 140.77322 129.311424) (end 140.77322 128.5) (width 0.125) (layer "F.Cu") (net 204))
  (segment (start 140.325 132.298222) (end 140.84822 131.775002) (width 0.125) (layer "F.Cu") (net 204))
  (segment (start 140.325 134.09) (end 140.325 132.298222) (width 0.125) (layer "F.Cu") (net 204))
  (segment (start 140.833366 130.740084) (end 140.84446 130.70838) (width 0.125) (layer "F.Cu") (net 204))
  (segment (start 140.84822 131.775002) (end 140.84446 131.741623) (width 0.125) (layer "F.Cu") (net 204))
  (segment (start 140.097416 130.834451) (end 140.181281 130.825002) (width 0.125) (layer "F.Cu") (net 204))
  (segment (start 140.84446 131.741623) (end 140.833366 131.709919) (width 0.125) (layer "F.Cu") (net 204))
  (segment (start 140.815495 131.681478) (end 140.791744 131.657727) (width 0.125) (layer "F.Cu") (net 204))
  (segment (start 140.017756 131.587678) (end 139.946296 131.542777) (width 0.125) (layer "F.Cu") (net 204))
  (segment (start 140.181281 131.625002) (end 140.097416 131.615552) (width 0.125) (layer "F.Cu") (net 204))
  (segment (start 139.813844 131.118023) (end 139.841718 131.038363) (width 0.125) (layer "F.Cu") (net 204))
  (segment (start 140.791744 131.657727) (end 140.763303 131.639856) (width 0.125) (layer "F.Cu") (net 204))
  (segment (start 140.69822 131.625002) (end 140.181281 131.625002) (width 0.125) (layer "F.Cu") (net 204))
  (segment (start 139.946296 131.542777) (end 139.886619 131.4831) (width 0.125) (layer "F.Cu") (net 204))
  (segment (start 139.813844 131.33198) (end 139.804394 131.248115) (width 0.125) (layer "F.Cu") (net 204))
  (segment (start 139.841718 131.41164) (end 139.813844 131.33198) (width 0.125) (layer "F.Cu") (net 204))
  (segment (start 139.804394 131.248115) (end 139.804394 131.201888) (width 0.125) (layer "F.Cu") (net 204))
  (segment (start 140.731599 130.821241) (end 140.763303 130.810147) (width 0.125) (layer "F.Cu") (net 204))
  (segment (start 140.763303 130.810147) (end 140.791744 130.792276) (width 0.125) (layer "F.Cu") (net 204))
  (segment (start 140.017756 130.862325) (end 140.097416 130.834451) (width 0.125) (layer "F.Cu") (net 204))
  (segment (start 140.69822 130.825002) (end 140.731599 130.821241) (width 0.125) (layer "F.Cu") (net 204))
  (segment (start 140.181281 130.825002) (end 140.69822 130.825002) (width 0.125) (layer "F.Cu") (net 204))
  (segment (start 139.946296 130.907226) (end 140.017756 130.862325) (width 0.125) (layer "F.Cu") (net 204))
  (segment (start 140.815495 130.768525) (end 140.833366 130.740084) (width 0.125) (layer "F.Cu") (net 204))
  (segment (start 140.84446 130.70838) (end 140.84822 130.675002) (width 0.125) (layer "F.Cu") (net 204))
  (segment (start 139.5 134.015) (end 139.95 134.465) (width 0.125) (layer "F.Cu") (net 204))
  (segment (start 140.84822 130.675002) (end 140.84822 129.386424) (width 0.125) (layer "F.Cu") (net 204))
  (segment (start 139.5 133.535) (end 139.5 134.015) (width 0.125) (layer "F.Cu") (net 204))
  (segment (start 140.791744 130.792276) (end 140.815495 130.768525) (width 0.125) (layer "F.Cu") (net 204))
  (segment (start 140.37322 129.311424) (end 140.29822 129.386424) (width 0.125) (layer "F.Cu") (net 205))
  (segment (start 140.37322 128.5) (end 140.37322 129.311424) (width 0.125) (layer "F.Cu") (net 205))
  (segment (start 137.375 131.701778) (end 137.375 134.09) (width 0.125) (layer "F.Cu") (net 205))
  (segment (start 137.375 134.09) (end 137.75 134.465) (width 0.125) (layer "F.Cu") (net 205))
  (segment (start 138.2 134.015) (end 137.75 134.465) (width 0.125) (layer "F.Cu") (net 205))
  (segment (start 137.901778 131.175) (end 137.375 131.701778) (width 0.125) (layer "F.Cu") (net 205))
  (segment (start 140.29822 129.386424) (end 140.29822 129.878558) (width 0.125) (layer "F.Cu") (net 205))
  (segment (start 138.2 133.535) (end 138.2 134.015) (width 0.125) (layer "F.Cu") (net 205))
  (segment (start 140.29822 129.878558) (end 139.001778 131.175) (width 0.125) (layer "F.Cu") (net 205))
  (segment (start 139.001778 131.175) (end 137.901778 131.175) (width 0.125) (layer "F.Cu") (net 205))
  (segment (start 137.375 135.81) (end 137.75 135.435) (width 0.125) (layer "F.Cu") (net 206))
  (segment (start 137.49 136.374999) (end 137.375 136.259999) (width 0.125) (layer "F.Cu") (net 206))
  (segment (start 137.375 136.259999) (end 137.375 135.81) (width 0.125) (layer "F.Cu") (net 206))
  (segment (start 137.49 136.6) (end 137.49 136.374999) (width 0.125) (layer "F.Cu") (net 206))
  (segment (start 138.6 135.4) (end 137.785 135.4) (width 0.125) (layer "F.Cu") (net 206))
  (segment (start 138.6 135.4) (end 138.6 136.165) (width 0.125) (layer "F.Cu") (net 206))
  (segment (start 138.6 136.165) (end 138.35 136.415) (width 0.125) (layer "F.Cu") (net 206))
  (via (at 138.6 135.4) (size 0.6) (drill 0.25) (layers "F.Cu" "B.Cu") (net 206))
  (segment (start 138.565 135.435) (end 138.6 135.4) (width 0.125) (layer "B.Cu") (net 206))
  (segment (start 137.75 135.435) (end 138.565 135.435) (width 0.125) (layer "B.Cu") (net 206))
  (segment (start 139.97322 129.311424) (end 140.04822 129.386424) (width 0.125) (layer "F.Cu") (net 207))
  (segment (start 139.97322 128.5) (end 139.97322 129.311424) (width 0.125) (layer "F.Cu") (net 207))
  (segment (start 137.798222 130.925) (end 137.125 131.598222) (width 0.125) (layer "F.Cu") (net 207))
  (segment (start 137.125 134.09) (end 136.75 134.465) (width 0.125) (layer "F.Cu") (net 207))
  (segment (start 136.3 134.015) (end 136.75 134.465) (width 0.125) (layer "F.Cu") (net 207))
  (segment (start 137.125 131.598222) (end 137.125 134.09) (width 0.125) (layer "F.Cu") (net 207))
  (segment (start 140.04822 129.386424) (end 140.04822 129.775002) (width 0.125) (layer "F.Cu") (net 207))
  (segment (start 136.3 133.535) (end 136.3 134.015) (width 0.125) (layer "F.Cu") (net 207))
  (segment (start 138.898222 130.925) (end 137.798222 130.925) (width 0.125) (layer "F.Cu") (net 207))
  (segment (start 140.04822 129.775002) (end 138.898222 130.925) (width 0.125) (layer "F.Cu") (net 207))
  (segment (start 137.01 136.6) (end 137.01 136.374999) (width 0.125) (layer "F.Cu") (net 208))
  (segment (start 137.125 136.259999) (end 137.125 135.81) (width 0.125) (layer "F.Cu") (net 208))
  (segment (start 137.01 136.374999) (end 137.125 136.259999) (width 0.125) (layer "F.Cu") (net 208))
  (segment (start 137.125 135.81) (end 136.75 135.435) (width 0.125) (layer "F.Cu") (net 208))
  (segment (start 135.965 135.435) (end 135.965 136.23) (width 0.125) (layer "F.Cu") (net 208))
  (segment (start 136.75 135.435) (end 135.965 135.435) (width 0.125) (layer "F.Cu") (net 208))
  (via (at 135.965 135.435) (size 0.6) (drill 0.25) (layers "F.Cu" "B.Cu") (net 208))
  (segment (start 136.75 135.435) (end 135.965 135.435) (width 0.125) (layer "B.Cu") (net 208))
  (segment (start 142.55 137.35) (end 142.05 137.85) (width 0.25) (layer "F.Cu") (net 209))
  (segment (start 141.55 137.35) (end 142.05 137.85) (width 0.25) (layer "F.Cu") (net 209))
  (segment (start 139.35 137.35) (end 138.85 137.85) (width 0.25) (layer "F.Cu") (net 209))
  (segment (start 138.35 137.35) (end 138.85 137.85) (width 0.25) (layer "F.Cu") (net 209))
  (segment (start 136.15 137.35) (end 135.65 137.85) (width 0.25) (layer "F.Cu") (net 209))
  (segment (start 148.45 137.85) (end 147.95 137.35) (width 0.25) (layer "F.Cu") (net 209))
  (segment (start 141.474999 130.977004) (end 141.948001 131.450006) (width 0.2) (layer "F.Cu") (net 209))
  (segment (start 141.948001 131.450006) (end 142 131.450006) (width 0.2) (layer "F.Cu") (net 209))
  (segment (start 141.57322 129.649778) (end 141.474999 129.747999) (width 0.2) (layer "F.Cu") (net 209))
  (segment (start 141.474999 129.747999) (end 141.474999 130.977004) (width 0.2) (layer "F.Cu") (net 209))
  (segment (start 141.57322 128.5) (end 141.57322 129.649778) (width 0.2) (layer "F.Cu") (net 209))
  (segment (start 145.75 137.35) (end 145.25 137.85) (width 0.25) (layer "F.Cu") (net 209))
  (segment (start 144.75 137.35) (end 145.25 137.85) (width 0.25) (layer "F.Cu") (net 209))
  (segment (start 136.115 138.315) (end 135.65 137.85) (width 0.2) (layer "F.Cu") (net 209))
  (via (at 138.85 137.85) (size 0.6) (drill 0.25) (layers "F.Cu" "B.Cu") (net 209))
  (via (at 135.65 137.85) (size 0.6) (drill 0.25) (layers "F.Cu" "B.Cu") (net 209))
  (via (at 148.45 137.85) (size 0.6) (drill 0.25) (layers "F.Cu" "B.Cu") (net 209))
  (via (at 142 131.450006) (size 0.6) (drill 0.25) (layers "F.Cu" "B.Cu") (net 209))
  (via (at 142.05 137.85) (size 0.6) (drill 0.25) (layers "F.Cu" "B.Cu") (net 209))
  (via (at 145.25 137.85) (size 0.6) (drill 0.25) (layers "F.Cu" "B.Cu") (net 209))
  (segment (start 141.3 132.150006) (end 141.3 137.1) (width 0.25) (layer "In2.Cu") (net 209))
  (segment (start 141.3 137.1) (end 142.05 137.85) (width 0.25) (layer "In2.Cu") (net 209))
  (segment (start 142 131.450006) (end 141.3 132.150006) (width 0.25) (layer "In2.Cu") (net 209))
  (segment (start 142.05 137.85) (end 148.45 137.85) (width 0.25) (layer "In3.Cu") (net 209))
  (segment (start 142.05 137.85) (end 138.85 137.85) (width 0.25) (layer "In3.Cu") (net 209))
  (segment (start 138.85 137.85) (end 135.65 137.85) (width 0.25) (layer "In3.Cu") (net 209))
  (segment (start 134.6 137.6) (end 134.85 137.85) (width 0.2) (layer "B.Cu") (net 209))
  (segment (start 134.85 137.85) (end 135.65 137.85) (width 0.2) (layer "B.Cu") (net 209))
  (segment (start 142.05 137.85) (end 142.05 137.05) (width 0.2) (layer "B.Cu") (net 209))
  (segment (start 134.6 136.35) (end 134.6 137.6) (width 0.2) (layer "B.Cu") (net 209))
  (segment (start 114.5 143.04) (end 114.45 142.99) (width 0.25) (layer "F.Cu") (net 210))
  (segment (start 114.45 142.99) (end 114.45 141.75) (width 0.25) (layer "F.Cu") (net 210))
  (segment (start 116.75 144.74) (end 116.75 146.1) (width 0.25) (layer "F.Cu") (net 210))
  (segment (start 114.25 144.74) (end 114.25 145.45) (width 0.25) (layer "F.Cu") (net 210))
  (segment (start 117 143.04) (end 117 142.3) (width 0.25) (layer "F.Cu") (net 210))
  (via (at 111.9 148.5) (size 0.6) (drill 0.25) (layers "F.Cu" "B.Cu") (net 210))
  (via (at 112.7 148.5) (size 0.6) (drill 0.25) (layers "F.Cu" "B.Cu") (net 210))
  (via (at 114.45 141.75) (size 0.6) (drill 0.25) (layers "F.Cu" "B.Cu") (net 210))
  (via (at 116.5 147.5) (size 0.6) (drill 0.25) (layers "F.Cu" "B.Cu") (net 210))
  (via (at 116.5 148.5) (size 0.6) (drill 0.25) (layers "F.Cu" "B.Cu") (net 210))
  (via (at 116.75 146.1) (size 0.6) (drill 0.25) (layers "F.Cu" "B.Cu") (net 210))
  (via (at 107.2 144.9) (size 0.6) (drill 0.25) (layers "F.Cu" "B.Cu") (net 210))
  (via (at 107.8 145.5) (size 0.6) (drill 0.25) (layers "F.Cu" "B.Cu") (net 210))
  (via (at 107.8 146.1) (size 0.6) (drill 0.25) (layers "F.Cu" "B.Cu") (net 210))
  (via (at 107.2 146.1) (size 0.6) (drill 0.25) (layers "F.Cu" "B.Cu") (net 210))
  (via (at 107.2 145.5) (size 0.6) (drill 0.25) (layers "F.Cu" "B.Cu") (net 210))
  (via (at 117.5 147.5) (size 0.6) (drill 0.25) (layers "F.Cu" "B.Cu") (net 210))
  (via (at 117 142.3) (size 0.6) (drill 0.25) (layers "F.Cu" "B.Cu") (net 210))
  (via (at 114.25 145.45) (size 0.6) (drill 0.25) (layers "F.Cu" "B.Cu") (net 210))
  (segment (start 109.84 141.04201) (end 109.84 140.65799) (width 0.155) (layer "F.Cu") (net 211))
  (segment (start 114.55799 141.04) (end 114.89 140.70799) (width 0.155) (layer "F.Cu") (net 211))
  (segment (start 114 142.514999) (end 113.89 142.404999) (width 0.155) (layer "F.Cu") (net 211))
  (segment (start 113.54201 140.74) (end 113.84201 141.04) (width 0.155) (layer "F.Cu") (net 211))
  (segment (start 110.34201 140.44) (end 110.64201 140.74) (width 0.155) (layer "F.Cu") (net 211))
  (segment (start 114.89 140.3225) (end 115.1125 140.1) (width 0.155) (layer "F.Cu") (net 211))
  (segment (start 110.05799 141.26) (end 113.45799 141.26) (width 0.155) (layer "F.Cu") (net 211))
  (segment (start 113.84201 141.04) (end 114.55799 141.04) (width 0.155) (layer "F.Cu") (net 211))
  (segment (start 113.45799 141.26) (end 113.89 141.69201) (width 0.155) (layer "F.Cu") (net 211))
  (segment (start 110.05799 140.44) (end 110.34201 140.44) (width 0.155) (layer "F.Cu") (net 211))
  (segment (start 110.05799 141.26) (end 109.84 141.04201) (width 0.155) (layer "F.Cu") (net 211))
  (segment (start 110.64201 140.74) (end 113.54201 140.74) (width 0.155) (layer "F.Cu") (net 211))
  (segment (start 114 143.04) (end 114 142.514999) (width 0.155) (layer "F.Cu") (net 211))
  (segment (start 114.89 140.70799) (end 114.89 140.3225) (width 0.155) (layer "F.Cu") (net 211))
  (segment (start 109.84 140.65799) (end 110.05799 140.44) (width 0.155) (layer "F.Cu") (net 211))
  (segment (start 113.89 142.404999) (end 113.89 141.69201) (width 0.155) (layer "F.Cu") (net 211))
  (via (at 115.1125 140.1) (size 0.6) (drill 0.25) (layers "F.Cu" "B.Cu") (net 211))
  (segment (start 115.1125 140.1) (end 115.1125 139.5725) (width 0.155) (layer "B.Cu") (net 211))
  (segment (start 114.89 138.105) (end 114.89 137.50799) (width 0.155) (layer "B.Cu") (net 212))
  (segment (start 115.5 135.600001) (end 115.5 134.85) (width 0.155) (layer "B.Cu") (net 212))
  (segment (start 115.39 137.00799) (end 115.39 135.710001) (width 0.155) (layer "B.Cu") (net 212))
  (segment (start 115.25 138.465) (end 114.89 138.105) (width 0.155) (layer "B.Cu") (net 212))
  (segment (start 115.39 135.710001) (end 115.5 135.600001) (width 0.155) (layer "B.Cu") (net 212))
  (segment (start 114.89 137.50799) (end 115.39 137.00799) (width 0.155) (layer "B.Cu") (net 212))
  (segment (start 117.34201 139.26) (end 118.25799 139.26) (width 0.155) (layer "F.Cu") (net 213))
  (segment (start 119.83057 140.252687) (end 119.861231 140.340313) (width 0.155) (layer "F.Cu") (net 213))
  (segment (start 119.549302 140.028384) (end 119.636928 140.059045) (width 0.155) (layer "F.Cu") (net 213))
  (segment (start 118.25799 139.26) (end 118.74 139.74201) (width 0.155) (layer "F.Cu") (net 213))
  (segment (start 119.861231 140.340313) (end 119.871625 140.432565) (width 0.155) (layer "F.Cu") (net 213))
  (segment (start 119.781178 140.741898) (end 119.715534 140.807542) (width 0.155) (layer "F.Cu") (net 213))
  (segment (start 118.830579 140.913834) (end 118.800242 140.932896) (width 0.155) (layer "F.Cu") (net 213))
  (segment (start 118.774907 139.957748) (end 118.800242 139.983083) (width 0.155) (layer "F.Cu") (net 213))
  (segment (start 117.89 142.73) (end 118 142.84) (width 0.155) (layer "F.Cu") (net 213))
  (segment (start 117.117299 140.650843) (end 116.86 140.393544) (width 0.155) (layer "F.Cu") (net 213))
  (segment (start 118.755845 140.988568) (end 118.744012 141.022386) (width 0.155) (layer "F.Cu") (net 213))
  (segment (start 118.74 141.878923) (end 118.478923 142.14) (width 0.155) (layer "F.Cu") (net 213))
  (segment (start 117.117299 140.965507) (end 117.117299 140.650843) (width 0.155) (layer "F.Cu") (net 213))
  (segment (start 118.478923 142.14) (end 118.15799 142.14) (width 0.155) (layer "F.Cu") (net 213))
  (segment (start 118.800242 139.983083) (end 118.830579 140.002145) (width 0.155) (layer "F.Cu") (net 213))
  (segment (start 118.800242 140.932896) (end 118.774907 140.958231) (width 0.155) (layer "F.Cu") (net 213))
  (segment (start 119.83057 140.663292) (end 119.781178 140.741898) (width 0.155) (layer "F.Cu") (net 213))
  (segment (start 118.74 141.05799) (end 118.74 141.878923) (width 0.155) (layer "F.Cu") (net 213))
  (segment (start 119.45705 140.89799) (end 118.9 140.89799) (width 0.155) (layer "F.Cu") (net 213))
  (segment (start 116.86 140.393544) (end 116.86 139.74201) (width 0.155) (layer "F.Cu") (net 213))
  (segment (start 119.636928 140.059045) (end 119.715534 140.108437) (width 0.155) (layer "F.Cu") (net 213))
  (segment (start 118.9 140.89799) (end 118.864397 140.902001) (width 0.155) (layer "F.Cu") (net 213))
  (segment (start 118.9 140.01799) (end 119.45705 140.01799) (width 0.155) (layer "F.Cu") (net 213))
  (segment (start 119.715534 140.807542) (end 119.636928 140.856934) (width 0.155) (layer "F.Cu") (net 213))
  (segment (start 116.86 139.74201) (end 117.34201 139.26) (width 0.155) (layer "F.Cu") (net 213))
  (segment (start 119.871625 140.483414) (end 119.861231 140.575666) (width 0.155) (layer "F.Cu") (net 213))
  (segment (start 118.755845 139.927411) (end 118.774907 139.957748) (width 0.155) (layer "F.Cu") (net 213))
  (segment (start 118.864397 140.902001) (end 118.830579 140.913834) (width 0.155) (layer "F.Cu") (net 213))
  (segment (start 118.864397 140.013978) (end 118.9 140.01799) (width 0.155) (layer "F.Cu") (net 213))
  (segment (start 118.15799 142.14) (end 117.89 142.40799) (width 0.155) (layer "F.Cu") (net 213))
  (segment (start 119.549302 140.887595) (end 119.45705 140.89799) (width 0.155) (layer "F.Cu") (net 213))
  (segment (start 118.74 139.74201) (end 118.74 139.85799) (width 0.155) (layer "F.Cu") (net 213))
  (segment (start 119.781178 140.174081) (end 119.83057 140.252687) (width 0.155) (layer "F.Cu") (net 213))
  (segment (start 118.74 139.85799) (end 118.744012 139.893593) (width 0.155) (layer "F.Cu") (net 213))
  (segment (start 119.861231 140.575666) (end 119.83057 140.663292) (width 0.155) (layer "F.Cu") (net 213))
  (segment (start 118.774907 140.958231) (end 118.755845 140.988568) (width 0.155) (layer "F.Cu") (net 213))
  (segment (start 119.636928 140.856934) (end 119.549302 140.887595) (width 0.155) (layer "F.Cu") (net 213))
  (segment (start 118.830579 140.002145) (end 118.864397 140.013978) (width 0.155) (layer "F.Cu") (net 213))
  (segment (start 117.89 142.40799) (end 117.89 142.73) (width 0.155) (layer "F.Cu") (net 213))
  (segment (start 118.744012 141.022386) (end 118.74 141.05799) (width 0.155) (layer "F.Cu") (net 213))
  (segment (start 119.45705 140.01799) (end 119.549302 140.028384) (width 0.155) (layer "F.Cu") (net 213))
  (segment (start 118.744012 139.893593) (end 118.755845 139.927411) (width 0.155) (layer "F.Cu") (net 213))
  (segment (start 119.715534 140.108437) (end 119.781178 140.174081) (width 0.155) (layer "F.Cu") (net 213))
  (segment (start 119.871625 140.432565) (end 119.871625 140.483414) (width 0.155) (layer "F.Cu") (net 213))
  (via (at 117.117299 140.965507) (size 0.6) (drill 0.25) (layers "F.Cu" "B.Cu") (net 213))
  (segment (start 116.25 139.435) (end 116.61 139.795) (width 0.155) (layer "B.Cu") (net 213))
  (segment (start 117.117299 140.650843) (end 117.117299 140.965507) (width 0.155) (layer "B.Cu") (net 213))
  (segment (start 116.61 139.795) (end 116.61 140.143544) (width 0.155) (layer "B.Cu") (net 213))
  (segment (start 116.61 140.143544) (end 117.117299 140.650843) (width 0.155) (layer "B.Cu") (net 213))
  (segment (start 116.61 137.50799) (end 116.61 138.105) (width 0.155) (layer "B.Cu") (net 214))
  (segment (start 116 134.85) (end 116 135.600001) (width 0.155) (layer "B.Cu") (net 214))
  (segment (start 116 135.600001) (end 116.11 135.710001) (width 0.155) (layer "B.Cu") (net 214))
  (segment (start 116.11 135.710001) (end 116.11 137.00799) (width 0.155) (layer "B.Cu") (net 214))
  (segment (start 116.11 137.00799) (end 116.61 137.50799) (width 0.155) (layer "B.Cu") (net 214))
  (segment (start 116.61 138.105) (end 116.25 138.465) (width 0.155) (layer "B.Cu") (net 214))
  (segment (start 113.61 142.404999) (end 113.61 141.80799) (width 0.155) (layer "F.Cu") (net 215))
  (segment (start 114.61 140.3225) (end 114.3875 140.1) (width 0.155) (layer "F.Cu") (net 215))
  (segment (start 109.94201 141.54) (end 113.34201 141.54) (width 0.155) (layer "F.Cu") (net 215))
  (segment (start 113.34201 141.54) (end 113.61 141.80799) (width 0.155) (layer "F.Cu") (net 215))
  (segment (start 113.5 142.514999) (end 113.61 142.404999) (width 0.155) (layer "F.Cu") (net 215))
  (segment (start 113.65799 140.46) (end 113.95799 140.76) (width 0.155) (layer "F.Cu") (net 215))
  (segment (start 109.94201 141.54) (end 109.56 141.15799) (width 0.155) (layer "F.Cu") (net 215))
  (segment (start 109.56 140.54201) (end 109.94201 140.16) (width 0.155) (layer "F.Cu") (net 215))
  (segment (start 110.45799 140.16) (end 110.75799 140.46) (width 0.155) (layer "F.Cu") (net 215))
  (segment (start 114.61 140.59201) (end 114.61 140.3225) (width 0.155) (layer "F.Cu") (net 215))
  (segment (start 114.44201 140.76) (end 114.61 140.59201) (width 0.155) (layer "F.Cu") (net 215))
  (segment (start 113.95799 140.76) (end 114.44201 140.76) (width 0.155) (layer "F.Cu") (net 215))
  (segment (start 109.56 141.15799) (end 109.56 140.54201) (width 0.155) (layer "F.Cu") (net 215))
  (segment (start 113.5 143.04) (end 113.5 142.514999) (width 0.155) (layer "F.Cu") (net 215))
  (segment (start 109.94201 140.16) (end 110.45799 140.16) (width 0.155) (layer "F.Cu") (net 215))
  (segment (start 110.75799 140.46) (end 113.65799 140.46) (width 0.155) (layer "F.Cu") (net 215))
  (via (at 114.3875 140.1) (size 0.6) (drill 0.25) (layers "F.Cu" "B.Cu") (net 215))
  (segment (start 114.3875 140.1) (end 114.3875 139.5725) (width 0.155) (layer "B.Cu") (net 215))
  (segment (start 114.25 138.465) (end 114.61 138.105) (width 0.155) (layer "B.Cu") (net 216))
  (segment (start 115.11 136.89201) (end 115.11 135.710001) (width 0.155) (layer "B.Cu") (net 216))
  (segment (start 115.11 135.710001) (end 115 135.600001) (width 0.155) (layer "B.Cu") (net 216))
  (segment (start 115 135.600001) (end 115 134.85) (width 0.155) (layer "B.Cu") (net 216))
  (segment (start 114.61 137.39201) (end 115.11 136.89201) (width 0.155) (layer "B.Cu") (net 216))
  (segment (start 114.61 138.105) (end 114.61 137.39201) (width 0.155) (layer "B.Cu") (net 216))
  (segment (start 117.61 142.73) (end 117.5 142.84) (width 0.155) (layer "F.Cu") (net 217))
  (segment (start 118.14201 139.54) (end 118.46 139.85799) (width 0.155) (layer "F.Cu") (net 217))
  (segment (start 118.46 141.032565) (end 118.46 141.762943) (width 0.155) (layer "F.Cu") (net 217))
  (segment (start 118.694698 140.256934) (end 118.782324 140.287595) (width 0.155) (layer "F.Cu") (net 217))
  (segment (start 118.501056 140.852687) (end 118.470395 140.940313) (width 0.155) (layer "F.Cu") (net 217))
  (segment (start 119.431625 140.61799) (end 118.874576 140.61799) (width 0.155) (layer "F.Cu") (net 217))
  (segment (start 118.470395 139.975666) (end 118.501056 140.063292) (width 0.155) (layer "F.Cu") (net 217))
  (segment (start 118.470395 140.940313) (end 118.46 141.032565) (width 0.155) (layer "F.Cu") (net 217))
  (segment (start 119.531384 140.332896) (end 119.556719 140.358231) (width 0.155) (layer "F.Cu") (net 217))
  (segment (start 118.616092 140.207542) (end 118.694698 140.256934) (width 0.155) (layer "F.Cu") (net 217))
  (segment (start 118.694698 140.659045) (end 118.616092 140.708437) (width 0.155) (layer "F.Cu") (net 217))
  (segment (start 118.782324 140.628384) (end 118.694698 140.659045) (width 0.155) (layer "F.Cu") (net 217))
  (segment (start 119.431625 140.29799) (end 119.467229 140.302001) (width 0.155) (layer "F.Cu") (net 217))
  (segment (start 119.591625 140.45799) (end 119.587614 140.493593) (width 0.155) (layer "F.Cu") (net 217))
  (segment (start 119.575781 140.527411) (end 119.556719 140.557748) (width 0.155) (layer "F.Cu") (net 217))
  (segment (start 119.575781 140.388568) (end 119.587614 140.422386) (width 0.155) (layer "F.Cu") (net 217))
  (segment (start 119.501047 140.602145) (end 119.467229 140.613978) (width 0.155) (layer "F.Cu") (net 217))
  (segment (start 118.782324 140.287595) (end 118.874576 140.29799) (width 0.155) (layer "F.Cu") (net 217))
  (segment (start 117.315289 140.452853) (end 117.14 140.277564) (width 0.155) (layer "F.Cu") (net 217))
  (segment (start 119.587614 140.422386) (end 119.591625 140.45799) (width 0.155) (layer "F.Cu") (net 217))
  (segment (start 118.362943 141.86) (end 118.04201 141.86) (width 0.155) (layer "F.Cu") (net 217))
  (segment (start 118.501056 140.063292) (end 118.550448 140.141898) (width 0.155) (layer "F.Cu") (net 217))
  (segment (start 117.14 140.277564) (end 117.14 139.85799) (width 0.155) (layer "F.Cu") (net 217))
  (segment (start 119.556719 140.358231) (end 119.575781 140.388568) (width 0.155) (layer "F.Cu") (net 217))
  (segment (start 118.550448 140.141898) (end 118.616092 140.207542) (width 0.155) (layer "F.Cu") (net 217))
  (segment (start 117.14 139.85799) (end 117.45799 139.54) (width 0.155) (layer "F.Cu") (net 217))
  (segment (start 118.46 141.762943) (end 118.362943 141.86) (width 0.155) (layer "F.Cu") (net 217))
  (segment (start 118.616092 140.708437) (end 118.550448 140.774081) (width 0.155) (layer "F.Cu") (net 217))
  (segment (start 119.531384 140.583083) (end 119.501047 140.602145) (width 0.155) (layer "F.Cu") (net 217))
  (segment (start 119.467229 140.302001) (end 119.501047 140.313834) (width 0.155) (layer "F.Cu") (net 217))
  (segment (start 119.467229 140.613978) (end 119.431625 140.61799) (width 0.155) (layer "F.Cu") (net 217))
  (segment (start 117.45799 139.54) (end 118.14201 139.54) (width 0.155) (layer "F.Cu") (net 217))
  (segment (start 118.46 139.85799) (end 118.46 139.883414) (width 0.155) (layer "F.Cu") (net 217))
  (segment (start 119.556719 140.557748) (end 119.531384 140.583083) (width 0.155) (layer "F.Cu") (net 217))
  (segment (start 118.550448 140.774081) (end 118.501056 140.852687) (width 0.155) (layer "F.Cu") (net 217))
  (segment (start 117.629953 140.452853) (end 117.315289 140.452853) (width 0.155) (layer "F.Cu") (net 217))
  (segment (start 118.46 139.883414) (end 118.470395 139.975666) (width 0.155) (layer "F.Cu") (net 217))
  (segment (start 118.04201 141.86) (end 117.61 142.29201) (width 0.155) (layer "F.Cu") (net 217))
  (segment (start 118.874576 140.61799) (end 118.782324 140.628384) (width 0.155) (layer "F.Cu") (net 217))
  (segment (start 118.874576 140.29799) (end 119.431625 140.29799) (width 0.155) (layer "F.Cu") (net 217))
  (segment (start 119.587614 140.493593) (end 119.575781 140.527411) (width 0.155) (layer "F.Cu") (net 217))
  (segment (start 117.61 142.29201) (end 117.61 142.73) (width 0.155) (layer "F.Cu") (net 217))
  (segment (start 119.501047 140.313834) (end 119.531384 140.332896) (width 0.155) (layer "F.Cu") (net 217))
  (via (at 117.629953 140.452853) (size 0.6) (drill 0.25) (layers "F.Cu" "B.Cu") (net 217))
  (segment (start 117.315289 140.452853) (end 117.629953 140.452853) (width 0.155) (layer "B.Cu") (net 217))
  (segment (start 117.25 139.435) (end 116.89 139.795) (width 0.155) (layer "B.Cu") (net 217))
  (segment (start 116.89 140.027564) (end 117.315289 140.452853) (width 0.155) (layer "B.Cu") (net 217))
  (segment (start 116.89 139.795) (end 116.89 140.027564) (width 0.155) (layer "B.Cu") (net 217))
  (segment (start 116.39 136.89201) (end 116.89 137.39201) (width 0.155) (layer "B.Cu") (net 218))
  (segment (start 116.39 135.710001) (end 116.39 136.89201) (width 0.155) (layer "B.Cu") (net 218))
  (segment (start 116.89 137.39201) (end 116.89 138.105) (width 0.155) (layer "B.Cu") (net 218))
  (segment (start 116.5 135.600001) (end 116.39 135.710001) (width 0.155) (layer "B.Cu") (net 218))
  (segment (start 116.89 138.105) (end 117.25 138.465) (width 0.155) (layer "B.Cu") (net 218))
  (segment (start 116.5 134.85) (end 116.5 135.600001) (width 0.155) (layer "B.Cu") (net 218))
  (segment (start 112.89 137.70799) (end 114.39 136.20799) (width 0.155) (layer "B.Cu") (net 219))
  (segment (start 112.89 138.105) (end 112.89 137.70799) (width 0.155) (layer "B.Cu") (net 219))
  (segment (start 113.25 138.465) (end 112.89 138.105) (width 0.155) (layer "B.Cu") (net 219))
  (segment (start 114.39 135.710001) (end 114.5 135.600001) (width 0.155) (layer "B.Cu") (net 219))
  (segment (start 114.39 136.20799) (end 114.39 135.710001) (width 0.155) (layer "B.Cu") (net 219))
  (segment (start 114.5 135.600001) (end 114.5 134.85) (width 0.155) (layer "B.Cu") (net 219))
  (segment (start 113.75 145.265001) (end 113.64 145.375001) (width 0.155) (layer "F.Cu") (net 220))
  (segment (start 113.64 145.375001) (end 113.64 145.75799) (width 0.155) (layer "F.Cu") (net 220))
  (segment (start 112.853693 146.247913) (end 112.631193 146.470413) (width 0.155) (layer "F.Cu") (net 220))
  (segment (start 113.75 144.74) (end 113.75 145.265001) (width 0.155) (layer "F.Cu") (net 220))
  (segment (start 113.64 145.75799) (end 113.150077 146.247913) (width 0.155) (layer "F.Cu") (net 220))
  (segment (start 113.150077 146.247913) (end 112.853693 146.247913) (width 0.155) (layer "F.Cu") (net 220))
  (via (at 112.631193 146.470413) (size 0.6) (drill 0.25) (layers "F.Cu" "B.Cu") (net 220))
  (segment (start 113.674906 143.939758) (end 113.655844 143.909421) (width 0.155) (layer "B.Cu") (net 220))
  (segment (start 114.682449 144.465424) (end 114.682449 144.414575) (width 0.155) (layer "B.Cu") (net 220))
  (segment (start 113.64 143.84) (end 113.64 142.94201) (width 0.155) (layer "B.Cu") (net 220))
  (segment (start 113.764396 143.995988) (end 113.730578 143.984155) (width 0.155) (layer "B.Cu") (net 220))
  (segment (start 113.8 144) (end 113.764396 143.995988) (width 0.155) (layer "B.Cu") (net 220))
  (segment (start 114.592001 144.156091) (end 114.526357 144.090447) (width 0.155) (layer "B.Cu") (net 220))
  (segment (start 113.730578 144.895844) (end 113.764396 144.884011) (width 0.155) (layer "B.Cu") (net 220))
  (segment (start 113.8 144.88) (end 114.267873 144.88) (width 0.155) (layer "B.Cu") (net 220))
  (segment (start 112.853693 146.247913) (end 113.150077 146.247913) (width 0.155) (layer "B.Cu") (net 220))
  (segment (start 113.150077 146.247913) (end 113.64 145.75799) (width 0.155) (layer "B.Cu") (net 220))
  (segment (start 114.526357 144.789552) (end 114.592001 144.723908) (width 0.155) (layer "B.Cu") (net 220))
  (segment (start 113.655844 144.970578) (end 113.674906 144.940241) (width 0.155) (layer "B.Cu") (net 220))
  (segment (start 114.360125 144.010394) (end 114.267873 144) (width 0.155) (layer "B.Cu") (net 220))
  (segment (start 114.641393 144.645302) (end 114.672054 144.557676) (width 0.155) (layer "B.Cu") (net 220))
  (segment (start 114.447751 144.838944) (end 114.526357 144.789552) (width 0.155) (layer "B.Cu") (net 220))
  (segment (start 112.89 142.19201) (end 112.89 139.795) (width 0.155) (layer "B.Cu") (net 220))
  (segment (start 114.267873 144.88) (end 114.360125 144.869605) (width 0.155) (layer "B.Cu") (net 220))
  (segment (start 113.700241 144.914906) (end 113.730578 144.895844) (width 0.155) (layer "B.Cu") (net 220))
  (segment (start 112.89 139.795) (end 113.25 139.435) (width 0.155) (layer "B.Cu") (net 220))
  (segment (start 114.447751 144.041055) (end 114.360125 144.010394) (width 0.155) (layer "B.Cu") (net 220))
  (segment (start 113.644011 145.004396) (end 113.655844 144.970578) (width 0.155) (layer "B.Cu") (net 220))
  (segment (start 112.631193 146.470413) (end 112.853693 146.247913) (width 0.155) (layer "B.Cu") (net 220))
  (segment (start 113.700241 143.965093) (end 113.674906 143.939758) (width 0.155) (layer "B.Cu") (net 220))
  (segment (start 114.682449 144.414575) (end 114.672054 144.322323) (width 0.155) (layer "B.Cu") (net 220))
  (segment (start 113.730578 143.984155) (end 113.700241 143.965093) (width 0.155) (layer "B.Cu") (net 220))
  (segment (start 114.526357 144.090447) (end 114.447751 144.041055) (width 0.155) (layer "B.Cu") (net 220))
  (segment (start 113.644011 143.875603) (end 113.64 143.84) (width 0.155) (layer "B.Cu") (net 220))
  (segment (start 114.592001 144.723908) (end 114.641393 144.645302) (width 0.155) (layer "B.Cu") (net 220))
  (segment (start 113.764396 144.884011) (end 113.8 144.88) (width 0.155) (layer "B.Cu") (net 220))
  (segment (start 114.641393 144.234697) (end 114.592001 144.156091) (width 0.155) (layer "B.Cu") (net 220))
  (segment (start 113.674906 144.940241) (end 113.700241 144.914906) (width 0.155) (layer "B.Cu") (net 220))
  (segment (start 113.64 145.75799) (end 113.64 145.04) (width 0.155) (layer "B.Cu") (net 220))
  (segment (start 114.672054 144.322323) (end 114.641393 144.234697) (width 0.155) (layer "B.Cu") (net 220))
  (segment (start 113.655844 143.909421) (end 113.644011 143.875603) (width 0.155) (layer "B.Cu") (net 220))
  (segment (start 114.360125 144.869605) (end 114.447751 144.838944) (width 0.155) (layer "B.Cu") (net 220))
  (segment (start 113.64 142.94201) (end 112.89 142.19201) (width 0.155) (layer "B.Cu") (net 220))
  (segment (start 114.267873 144) (end 113.8 144) (width 0.155) (layer "B.Cu") (net 220))
  (segment (start 114.672054 144.557676) (end 114.682449 144.465424) (width 0.155) (layer "B.Cu") (net 220))
  (segment (start 113.64 145.04) (end 113.644011 145.004396) (width 0.155) (layer "B.Cu") (net 220))
  (segment (start 117.11 136.20799) (end 118.61 137.70799) (width 0.155) (layer "B.Cu") (net 221))
  (segment (start 117 134.85) (end 117 135.600001) (width 0.155) (layer "B.Cu") (net 221))
  (segment (start 118.61 137.70799) (end 118.61 138.105) (width 0.155) (layer "B.Cu") (net 221))
  (segment (start 117 135.600001) (end 117.11 135.710001) (width 0.155) (layer "B.Cu") (net 221))
  (segment (start 118.61 138.105) (end 118.25 138.465) (width 0.155) (layer "B.Cu") (net 221))
  (segment (start 117.11 135.710001) (end 117.11 136.20799) (width 0.155) (layer "B.Cu") (net 221))
  (segment (start 118.12285 146.302716) (end 118.34535 146.080216) (width 0.155) (layer "F.Cu") (net 222))
  (segment (start 117.75 145.265001) (end 117.64 145.375001) (width 0.155) (layer "F.Cu") (net 222))
  (segment (start 117.64 145.94201) (end 118.000706 146.302716) (width 0.155) (layer "F.Cu") (net 222))
  (segment (start 118.000706 146.302716) (end 118.12285 146.302716) (width 0.155) (layer "F.Cu") (net 222))
  (segment (start 117.75 144.74) (end 117.75 145.265001) (width 0.155) (layer "F.Cu") (net 222))
  (segment (start 117.64 145.375001) (end 117.64 145.94201) (width 0.155) (layer "F.Cu") (net 222))
  (via (at 118.34535 146.080216) (size 0.6) (drill 0.25) (layers "F.Cu" "B.Cu") (net 222))
  (segment (start 118.96 145.65799) (end 118.26 144.95799) (width 0.155) (layer "B.Cu") (net 222))
  (segment (start 118.172252 144.720349) (end 118.139491 144.708886) (width 0.155) (layer "B.Cu") (net 222))
  (segment (start 118.105 144.395) (end 118.139491 144.391113) (width 0.155) (layer "B.Cu") (net 222))
  (segment (start 118.105 144.705) (end 118.04896 144.705) (width 0.155) (layer "B.Cu") (net 222))
  (segment (start 117.981709 144.410349) (end 118.01447 144.398886) (width 0.155) (layer "B.Cu") (net 222))
  (segment (start 117.95232 144.671183) (end 117.927777 144.64664) (width 0.155) (layer "B.Cu") (net 222))
  (segment (start 119.36 142.44201) (end 119.36 141.15799) (width 0.155) (layer "B.Cu") (net 222))
  (segment (start 117.897847 143.96449) (end 117.89396 143.93) (width 0.155) (layer "B.Cu") (net 222))
  (segment (start 118.56785 146.302716) (end 118.799294 146.302716) (width 0.155) (layer "B.Cu") (net 222))
  (segment (start 118.799294 146.302716) (end 118.96 146.14201) (width 0.155) (layer "B.Cu") (net 222))
  (segment (start 118.172252 144.37965) (end 118.201641 144.361183) (width 0.155) (layer "B.Cu") (net 222))
  (segment (start 117.981709 144.68965) (end 117.95232 144.671183) (width 0.155) (layer "B.Cu") (net 222))
  (segment (start 118.01447 143.778886) (end 118.04896 143.775) (width 0.155) (layer "B.Cu") (net 222))
  (segment (start 118.139491 144.708886) (end 118.105 144.705) (width 0.155) (layer "B.Cu") (net 222))
  (segment (start 118.201641 144.738816) (end 118.172252 144.720349) (width 0.155) (layer "B.Cu") (net 222))
  (segment (start 118.26 144.95799) (end 118.26 144.86) (width 0.155) (layer "B.Cu") (net 222))
  (segment (start 118.172252 144.100349) (end 118.139491 144.088886) (width 0.155) (layer "B.Cu") (net 222))
  (segment (start 118.04896 143.775) (end 118.105 143.775) (width 0.155) (layer "B.Cu") (net 222))
  (segment (start 118.139491 144.088886) (end 118.105 144.085) (width 0.155) (layer "B.Cu") (net 222))
  (segment (start 117.95232 143.808816) (end 117.981709 143.790349) (width 0.155) (layer "B.Cu") (net 222))
  (segment (start 118.244651 144.792748) (end 118.226184 144.763359) (width 0.155) (layer "B.Cu") (net 222))
  (segment (start 117.927777 144.02664) (end 117.90931 143.997251) (width 0.155) (layer "B.Cu") (net 222))
  (segment (start 118.105 143.775) (end 118.139491 143.771113) (width 0.155) (layer "B.Cu") (net 222))
  (segment (start 118.201641 144.118816) (end 118.172252 144.100349) (width 0.155) (layer "B.Cu") (net 222))
  (segment (start 119.36 141.15799) (end 118.61 140.40799) (width 0.155) (layer "B.Cu") (net 222))
  (segment (start 118.226184 144.763359) (end 118.201641 144.738816) (width 0.155) (layer "B.Cu") (net 222))
  (segment (start 117.927777 144.453359) (end 117.95232 144.428816) (width 0.155) (layer "B.Cu") (net 222))
  (segment (start 118.256114 143.65449) (end 118.26 143.62) (width 0.155) (layer "B.Cu") (net 222))
  (segment (start 117.897847 144.515509) (end 117.90931 144.482748) (width 0.155) (layer "B.Cu") (net 222))
  (segment (start 118.26 143.14201) (end 118.74201 142.66) (width 0.155) (layer "B.Cu") (net 222))
  (segment (start 118.26 143.62) (end 118.26 143.14201) (width 0.155) (layer "B.Cu") (net 222))
  (segment (start 117.90931 144.482748) (end 117.927777 144.453359) (width 0.155) (layer "B.Cu") (net 222))
  (segment (start 118.01447 144.398886) (end 118.04896 144.395) (width 0.155) (layer "B.Cu") (net 222))
  (segment (start 118.96 146.14201) (end 118.96 145.65799) (width 0.155) (layer "B.Cu") (net 222))
  (segment (start 117.927777 144.64664) (end 117.90931 144.617251) (width 0.155) (layer "B.Cu") (net 222))
  (segment (start 118.26 144.86) (end 118.256114 144.825509) (width 0.155) (layer "B.Cu") (net 222))
  (segment (start 118.244651 144.307251) (end 118.256114 144.27449) (width 0.155) (layer "B.Cu") (net 222))
  (segment (start 117.95232 144.051183) (end 117.927777 144.02664) (width 0.155) (layer "B.Cu") (net 222))
  (segment (start 118.26 144.24) (end 118.256114 144.205509) (width 0.155) (layer "B.Cu") (net 222))
  (segment (start 118.01447 144.081113) (end 117.981709 144.06965) (width 0.155) (layer "B.Cu") (net 222))
  (segment (start 118.244651 144.172748) (end 118.226184 144.143359) (width 0.155) (layer "B.Cu") (net 222))
  (segment (start 118.01447 144.701113) (end 117.981709 144.68965) (width 0.155) (layer "B.Cu") (net 222))
  (segment (start 118.04896 144.705) (end 118.01447 144.701113) (width 0.155) (layer "B.Cu") (net 222))
  (segment (start 117.95232 144.428816) (end 117.981709 144.410349) (width 0.155) (layer "B.Cu") (net 222))
  (segment (start 117.897847 144.58449) (end 117.89396 144.55) (width 0.155) (layer "B.Cu") (net 222))
  (segment (start 118.256114 144.825509) (end 118.244651 144.792748) (width 0.155) (layer "B.Cu") (net 222))
  (segment (start 118.226184 144.33664) (end 118.244651 144.307251) (width 0.155) (layer "B.Cu") (net 222))
  (segment (start 117.90931 144.617251) (end 117.897847 144.58449) (width 0.155) (layer "B.Cu") (net 222))
  (segment (start 118.105 144.085) (end 118.04896 144.085) (width 0.155) (layer "B.Cu") (net 222))
  (segment (start 117.897847 143.895509) (end 117.90931 143.862748) (width 0.155) (layer "B.Cu") (net 222))
  (segment (start 118.226184 144.143359) (end 118.201641 144.118816) (width 0.155) (layer "B.Cu") (net 222))
  (segment (start 118.04896 144.085) (end 118.01447 144.081113) (width 0.155) (layer "B.Cu") (net 222))
  (segment (start 118.201641 143.741183) (end 118.226184 143.71664) (width 0.155) (layer "B.Cu") (net 222))
  (segment (start 118.139491 143.771113) (end 118.172252 143.75965) (width 0.155) (layer "B.Cu") (net 222))
  (segment (start 117.981709 144.06965) (end 117.95232 144.051183) (width 0.155) (layer "B.Cu") (net 222))
  (segment (start 117.927777 143.833359) (end 117.95232 143.808816) (width 0.155) (layer "B.Cu") (net 222))
  (segment (start 117.90931 143.862748) (end 117.927777 143.833359) (width 0.155) (layer "B.Cu") (net 222))
  (segment (start 117.89396 143.93) (end 117.897847 143.895509) (width 0.155) (layer "B.Cu") (net 222))
  (segment (start 118.172252 143.75965) (end 118.201641 143.741183) (width 0.155) (layer "B.Cu") (net 222))
  (segment (start 117.981709 143.790349) (end 118.01447 143.778886) (width 0.155) (layer "B.Cu") (net 222))
  (segment (start 118.34535 146.080216) (end 118.56785 146.302716) (width 0.155) (layer "B.Cu") (net 222))
  (segment (start 118.61 139.795) (end 118.25 139.435) (width 0.155) (layer "B.Cu") (net 222))
  (segment (start 118.04896 144.395) (end 118.105 144.395) (width 0.155) (layer "B.Cu") (net 222))
  (segment (start 119.14201 142.66) (end 119.36 142.44201) (width 0.155) (layer "B.Cu") (net 222))
  (segment (start 118.256114 144.205509) (end 118.244651 144.172748) (width 0.155) (layer "B.Cu") (net 222))
  (segment (start 118.139491 144.391113) (end 118.172252 144.37965) (width 0.155) (layer "B.Cu") (net 222))
  (segment (start 118.244651 143.687251) (end 118.256114 143.65449) (width 0.155) (layer "B.Cu") (net 222))
  (segment (start 118.226184 143.71664) (end 118.244651 143.687251) (width 0.155) (layer "B.Cu") (net 222))
  (segment (start 117.89396 144.55) (end 117.897847 144.515509) (width 0.155) (layer "B.Cu") (net 222))
  (segment (start 118.61 140.40799) (end 118.61 139.795) (width 0.155) (layer "B.Cu") (net 222))
  (segment (start 118.74201 142.66) (end 119.14201 142.66) (width 0.155) (layer "B.Cu") (net 222))
  (segment (start 118.201641 144.361183) (end 118.226184 144.33664) (width 0.155) (layer "B.Cu") (net 222))
  (segment (start 118.256114 144.27449) (end 118.26 144.24) (width 0.155) (layer "B.Cu") (net 222))
  (segment (start 117.90931 143.997251) (end 117.897847 143.96449) (width 0.155) (layer "B.Cu") (net 222))
  (segment (start 112.25 138.465) (end 112.61 138.105) (width 0.155) (layer "B.Cu") (net 223))
  (segment (start 114.11 136.09201) (end 114.11 135.710001) (width 0.155) (layer "B.Cu") (net 223))
  (segment (start 112.61 137.59201) (end 114.11 136.09201) (width 0.155) (layer "B.Cu") (net 223))
  (segment (start 112.61 138.105) (end 112.61 137.59201) (width 0.155) (layer "B.Cu") (net 223))
  (segment (start 114.11 135.710001) (end 114 135.600001) (width 0.155) (layer "B.Cu") (net 223))
  (segment (start 114 135.600001) (end 114 134.85) (width 0.155) (layer "B.Cu") (net 223))
  (segment (start 112.853693 145.967913) (end 112.631193 145.745413) (width 0.155) (layer "F.Cu") (net 224))
  (segment (start 113.25 144.74) (end 113.25 145.265001) (width 0.155) (layer "F.Cu") (net 224))
  (segment (start 113.25 145.265001) (end 113.36 145.375001) (width 0.155) (layer "F.Cu") (net 224))
  (segment (start 113.36 145.64201) (end 113.034097 145.967913) (width 0.155) (layer "F.Cu") (net 224))
  (segment (start 113.034097 145.967913) (end 112.853693 145.967913) (width 0.155) (layer "F.Cu") (net 224))
  (segment (start 113.36 145.375001) (end 113.36 145.64201) (width 0.155) (layer "F.Cu") (net 224))
  (via (at 112.631193 145.745413) (size 0.6) (drill 0.25) (layers "F.Cu" "B.Cu") (net 224))
  (segment (start 113.233044 143.013567) (end 113.199205 143.021289) (width 0.155) (layer "B.Cu") (net 224))
  (segment (start 114.342207 144.314906) (end 114.31187 144.295844) (width 0.155) (layer "B.Cu") (net 224))
  (segment (start 113.301591 143.021289) (end 113.267752 143.013566) (width 0.155) (layer "B.Cu") (net 224))
  (segment (start 113.167933 143.036349) (end 113.140796 143.05799) (width 0.155) (layer "B.Cu") (net 224))
  (segment (start 112.696307 143.069567) (end 112.717948 143.04243) (width 0.155) (layer "B.Cu") (net 224))
  (segment (start 114.367542 144.340241) (end 114.342207 144.314906) (width 0.155) (layer "B.Cu") (net 224))
  (segment (start 113.332863 143.036349) (end 113.301591 143.021289) (width 0.155) (layer "B.Cu") (net 224))
  (segment (start 112.966017 142.71183) (end 112.958292 142.67799) (width 0.155) (layer "B.Cu") (net 224))
  (segment (start 112.943234 142.646719) (end 112.921593 142.619583) (width 0.155) (layer "B.Cu") (net 224))
  (segment (start 113.370394 143.957676) (end 113.36 143.865424) (width 0.155) (layer "B.Cu") (net 224))
  (segment (start 113.36 145.014575) (end 113.370394 144.922323) (width 0.155) (layer "B.Cu") (net 224))
  (segment (start 113.682323 144.610394) (end 113.774575 144.6) (width 0.155) (layer "B.Cu") (net 224))
  (segment (start 113.199205 143.021289) (end 113.167933 143.036349) (width 0.155) (layer "B.Cu") (net 224))
  (segment (start 113.774575 144.28) (end 113.682323 144.269605) (width 0.155) (layer "B.Cu") (net 224))
  (segment (start 114.31187 144.295844) (end 114.278052 144.284011) (width 0.155) (layer "B.Cu") (net 224))
  (segment (start 113.36 145.64201) (end 113.36 145.014575) (width 0.155) (layer "B.Cu") (net 224))
  (segment (start 112.853693 145.967913) (end 113.034097 145.967913) (width 0.155) (layer "B.Cu") (net 224))
  (segment (start 112.61 139.795) (end 112.25 139.435) (width 0.155) (layer "B.Cu") (net 224))
  (segment (start 112.937152 143.261635) (end 112.910015 143.283276) (width 0.155) (layer "B.Cu") (net 224))
  (segment (start 114.278052 144.284011) (end 114.242449 144.28) (width 0.155) (layer "B.Cu") (net 224))
  (segment (start 112.673525 143.134678) (end 112.681247 143.100839) (width 0.155) (layer "B.Cu") (net 224))
  (segment (start 112.717948 143.04243) (end 112.921593 142.838786) (width 0.155) (layer "B.Cu") (net 224))
  (segment (start 112.631193 145.745413) (end 112.853693 145.967913) (width 0.155) (layer "B.Cu") (net 224))
  (segment (start 112.921593 142.619583) (end 112.61 142.30799) (width 0.155) (layer "B.Cu") (net 224))
  (segment (start 113.370394 144.922323) (end 113.401055 144.834697) (width 0.155) (layer "B.Cu") (net 224))
  (segment (start 112.61 142.30799) (end 112.61 139.795) (width 0.155) (layer "B.Cu") (net 224))
  (segment (start 113.401055 144.045302) (end 113.370394 143.957676) (width 0.155) (layer "B.Cu") (net 224))
  (segment (start 113.034097 145.967913) (end 113.36 145.64201) (width 0.155) (layer "B.Cu") (net 224))
  (segment (start 112.696307 143.234497) (end 112.681247 143.203225) (width 0.155) (layer "B.Cu") (net 224))
  (segment (start 113.450447 144.756091) (end 113.516091 144.690447) (width 0.155) (layer "B.Cu") (net 224))
  (segment (start 113.516091 144.690447) (end 113.594697 144.641055) (width 0.155) (layer "B.Cu") (net 224))
  (segment (start 112.745085 143.283276) (end 112.717948 143.261634) (width 0.155) (layer "B.Cu") (net 224))
  (segment (start 113.594697 144.641055) (end 113.682323 144.610394) (width 0.155) (layer "B.Cu") (net 224))
  (segment (start 113.401055 144.834697) (end 113.450447 144.756091) (width 0.155) (layer "B.Cu") (net 224))
  (segment (start 112.717948 143.261634) (end 112.696307 143.234497) (width 0.155) (layer "B.Cu") (net 224))
  (segment (start 112.681247 143.100839) (end 112.696307 143.069567) (width 0.155) (layer "B.Cu") (net 224))
  (segment (start 113.682323 144.269605) (end 113.594697 144.238944) (width 0.155) (layer "B.Cu") (net 224))
  (segment (start 114.398437 144.404396) (end 114.386604 144.370578) (width 0.155) (layer "B.Cu") (net 224))
  (segment (start 113.594697 144.238944) (end 113.516091 144.189552) (width 0.155) (layer "B.Cu") (net 224))
  (segment (start 113.36 143.865424) (end 113.36 143.05799) (width 0.155) (layer "B.Cu") (net 224))
  (segment (start 112.776356 143.298334) (end 112.745085 143.283276) (width 0.155) (layer "B.Cu") (net 224))
  (segment (start 114.242449 144.28) (end 113.774575 144.28) (width 0.155) (layer "B.Cu") (net 224))
  (segment (start 114.402449 144.44) (end 114.398437 144.404396) (width 0.155) (layer "B.Cu") (net 224))
  (segment (start 114.342207 144.565093) (end 114.367542 144.539758) (width 0.155) (layer "B.Cu") (net 224))
  (segment (start 114.278052 144.595988) (end 114.31187 144.584155) (width 0.155) (layer "B.Cu") (net 224))
  (segment (start 112.910015 143.283276) (end 112.878744 143.298335) (width 0.155) (layer "B.Cu") (net 224))
  (segment (start 112.958293 142.780378) (end 112.966016 142.746538) (width 0.155) (layer "B.Cu") (net 224))
  (segment (start 112.966016 142.746538) (end 112.966017 142.71183) (width 0.155) (layer "B.Cu") (net 224))
  (segment (start 112.943234 142.811649) (end 112.958293 142.780378) (width 0.155) (layer "B.Cu") (net 224))
  (segment (start 114.242449 144.6) (end 114.278052 144.595988) (width 0.155) (layer "B.Cu") (net 224))
  (segment (start 112.844904 143.306058) (end 112.810196 143.306059) (width 0.155) (layer "B.Cu") (net 224))
  (segment (start 114.31187 144.584155) (end 114.342207 144.565093) (width 0.155) (layer "B.Cu") (net 224))
  (segment (start 113.774575 144.6) (end 114.242449 144.6) (width 0.155) (layer "B.Cu") (net 224))
  (segment (start 113.267752 143.013566) (end 113.233044 143.013567) (width 0.155) (layer "B.Cu") (net 224))
  (segment (start 114.386604 144.370578) (end 114.367542 144.340241) (width 0.155) (layer "B.Cu") (net 224))
  (segment (start 113.36 143.05799) (end 113.332863 143.036349) (width 0.155) (layer "B.Cu") (net 224))
  (segment (start 114.386604 144.509421) (end 114.398437 144.475603) (width 0.155) (layer "B.Cu") (net 224))
  (segment (start 113.450447 144.123908) (end 113.401055 144.045302) (width 0.155) (layer "B.Cu") (net 224))
  (segment (start 112.810196 143.306059) (end 112.776356 143.298334) (width 0.155) (layer "B.Cu") (net 224))
  (segment (start 112.673524 143.169386) (end 112.673525 143.134678) (width 0.155) (layer "B.Cu") (net 224))
  (segment (start 114.398437 144.475603) (end 114.402449 144.44) (width 0.155) (layer "B.Cu") (net 224))
  (segment (start 113.140796 143.05799) (end 112.937152 143.261635) (width 0.155) (layer "B.Cu") (net 224))
  (segment (start 112.958292 142.67799) (end 112.943234 142.646719) (width 0.155) (layer "B.Cu") (net 224))
  (segment (start 114.367542 144.539758) (end 114.386604 144.509421) (width 0.155) (layer "B.Cu") (net 224))
  (segment (start 112.681247 143.203225) (end 112.673524 143.169386) (width 0.155) (layer "B.Cu") (net 224))
  (segment (start 113.516091 144.189552) (end 113.450447 144.123908) (width 0.155) (layer "B.Cu") (net 224))
  (segment (start 112.921593 142.838786) (end 112.943234 142.811649) (width 0.155) (layer "B.Cu") (net 224))
  (segment (start 112.878744 143.298335) (end 112.844904 143.306058) (width 0.155) (layer "B.Cu") (net 224))
  (segment (start 117.39 135.710001) (end 117.39 136.09201) (width 0.155) (layer "B.Cu") (net 225))
  (segment (start 117.5 135.600001) (end 117.39 135.710001) (width 0.155) (layer "B.Cu") (net 225))
  (segment (start 117.39 136.09201) (end 118.89 137.59201) (width 0.155) (layer "B.Cu") (net 225))
  (segment (start 117.5 134.85) (end 117.5 135.600001) (width 0.155) (layer "B.Cu") (net 225))
  (segment (start 118.89 138.105) (end 119.25 138.465) (width 0.155) (layer "B.Cu") (net 225))
  (segment (start 118.89 137.59201) (end 118.89 138.105) (width 0.155) (layer "B.Cu") (net 225))
  (segment (start 117.25 145.265001) (end 117.36 145.375001) (width 0.155) (layer "F.Cu") (net 226))
  (segment (start 117.884726 146.582716) (end 118.12285 146.582716) (width 0.155) (layer "F.Cu") (net 226))
  (segment (start 118.12285 146.582716) (end 118.34535 146.805216) (width 0.155) (layer "F.Cu") (net 226))
  (segment (start 117.25 144.74) (end 117.25 145.265001) (width 0.155) (layer "F.Cu") (net 226))
  (segment (start 117.36 146.05799) (end 117.884726 146.582716) (width 0.155) (layer "F.Cu") (net 226))
  (segment (start 117.36 145.375001) (end 117.36 146.05799) (width 0.155) (layer "F.Cu") (net 226))
  (via (at 118.34535 146.805216) (size 0.6) (drill 0.25) (layers "F.Cu" "B.Cu") (net 226))
  (segment (start 118.56785 146.582716) (end 118.915274 146.582716) (width 0.155) (layer "B.Cu") (net 226))
  (segment (start 118.54 143.25799) (end 118.85799 142.94) (width 0.155) (layer "B.Cu") (net 226))
  (segment (start 118.89 140.29201) (end 118.89 139.795) (width 0.155) (layer "B.Cu") (net 226))
  (segment (start 119.64 142.55799) (end 119.64 141.04201) (width 0.155) (layer "B.Cu") (net 226))
  (segment (start 119.24 145.54201) (end 118.54 144.84201) (width 0.155) (layer "B.Cu") (net 226))
  (segment (start 119.64 141.04201) (end 118.89 140.29201) (width 0.155) (layer "B.Cu") (net 226))
  (segment (start 118.34535 146.805216) (end 118.56785 146.582716) (width 0.155) (layer "B.Cu") (net 226))
  (segment (start 118.54 144.84201) (end 118.54 143.25799) (width 0.155) (layer "B.Cu") (net 226))
  (segment (start 118.915274 146.582716) (end 119.24 146.25799) (width 0.155) (layer "B.Cu") (net 226))
  (segment (start 119.25799 142.94) (end 119.64 142.55799) (width 0.155) (layer "B.Cu") (net 226))
  (segment (start 118.89 139.795) (end 119.25 139.435) (width 0.155) (layer "B.Cu") (net 226))
  (segment (start 118.85799 142.94) (end 119.25799 142.94) (width 0.155) (layer "B.Cu") (net 226))
  (segment (start 119.24 146.25799) (end 119.24 145.54201) (width 0.155) (layer "B.Cu") (net 226))
  (segment (start 130.385 100.315) (end 129.35 100.315) (width 0.182) (layer "B.Cu") (net 227))
  (segment (start 130.725 99.975) (end 130.385 100.315) (width 0.182) (layer "B.Cu") (net 227))
  (segment (start 130.725 98.725) (end 130.725 99.975) (width 0.182) (layer "B.Cu") (net 227))
  (segment (start 129.35 101.085) (end 129.35 100.315) (width 0.182) (layer "B.Cu") (net 227))
  (segment (start 132.415 137.985) (end 132.4 138) (width 0.2) (layer "F.Cu") (net 228))
  (segment (start 132.415 137.3) (end 132.415 137.985) (width 0.2) (layer "F.Cu") (net 228))
  (segment (start 131.225 137.175) (end 132.29 137.175) (width 0.2) (layer "F.Cu") (net 228))
  (via (at 132.4 138) (size 0.6) (drill 0.25) (layers "F.Cu" "B.Cu") (net 228))
  (via (at 125.1 136.7) (size 0.6) (drill 0.25) (layers "F.Cu" "B.Cu") (net 228))
  (via (at 125.3 140) (size 0.6) (drill 0.25) (layers "F.Cu" "B.Cu") (net 228))
  (via (at 124.4 136.7) (size 0.6) (drill 0.25) (layers "F.Cu" "B.Cu") (net 228))
  (segment (start 124.4 140) (end 123.8 140.6) (width 0.15) (layer "B.Cu") (net 228))
  (segment (start 125.3 140) (end 124.4 140) (width 0.15) (layer "B.Cu") (net 228))
  (segment (start 129.89 140.146249) (end 129.89 139.647501) (width 0.155) (layer "F.Cu") (net 229))
  (segment (start 129.89 139.647501) (end 130 139.537501) (width 0.155) (layer "F.Cu") (net 229))
  (segment (start 130 139.537501) (end 130 138.9) (width 0.215) (layer "F.Cu") (net 229))
  (segment (start 130 140.6125) (end 130 140.256249) (width 0.215) (layer "F.Cu") (net 229))
  (segment (start 130 140.256249) (end 129.89 140.146249) (width 0.155) (layer "F.Cu") (net 229))
  (segment (start 130 140.6625) (end 130 141.4375) (width 0.215) (layer "F.Cu") (net 229))
  (segment (start 129.36 145.3275) (end 129.1375 145.55) (width 0.155) (layer "F.Cu") (net 229))
  (segment (start 129.89 142.0275) (end 130.1125 142.25) (width 0.155) (layer "F.Cu") (net 229))
  (segment (start 130 141.4375) (end 130 141.793751) (width 0.155) (layer "F.Cu") (net 229))
  (segment (start 130 141.793751) (end 129.89 141.903751) (width 0.155) (layer "F.Cu") (net 229))
  (segment (start 129.25 144.94) (end 129.36 145.05) (width 0.155) (layer "F.Cu") (net 229))
  (segment (start 129.36 145.05) (end 129.36 145.3275) (width 0.155) (layer "F.Cu") (net 229))
  (segment (start 130 142.84) (end 129.89 142.73) (width 0.155) (layer "F.Cu") (net 229))
  (segment (start 129.89 142.73) (end 129.89 142.4725) (width 0.155) (layer "F.Cu") (net 229))
  (segment (start 129.89 142.4725) (end 130.1125 142.25) (width 0.155) (layer "F.Cu") (net 229))
  (segment (start 129.89 141.903751) (end 129.89 142.0275) (width 0.155) (layer "F.Cu") (net 229))
  (via (at 129.1375 145.55) (size 0.6) (drill 0.25) (layers "F.Cu" "B.Cu") (net 229))
  (via (at 130.1125 142.25) (size 0.6) (drill 0.25) (layers "F.Cu" "B.Cu") (net 229))
  (segment (start 130.1125 142.2) (end 130.865 142.2) (width 0.155) (layer "B.Cu") (net 229))
  (segment (start 129.89 142.4225) (end 130.1125 142.2) (width 0.155) (layer "B.Cu") (net 229))
  (segment (start 129.89 142.64201) (end 129.89 142.4225) (width 0.155) (layer "B.Cu") (net 229))
  (segment (start 129.89 142.4725) (end 130.1125 142.25) (width 0.155) (layer "B.Cu") (net 229))
  (segment (start 129.36 145.7725) (end 129.36 146.15799) (width 0.155) (layer "B.Cu") (net 229))
  (segment (start 129.89 142.69201) (end 129.89 142.4725) (width 0.155) (layer "B.Cu") (net 229))
  (segment (start 129.679851 146.477841) (end 130.220149 146.477841) (width 0.155) (layer "B.Cu") (net 229))
  (segment (start 129.1375 145.55) (end 129.36 145.7725) (width 0.155) (layer "B.Cu") (net 229))
  (segment (start 130.220149 146.477841) (end 130.59 146.10799) (width 0.155) (layer "B.Cu") (net 229))
  (segment (start 129.36 146.15799) (end 129.679851 146.477841) (width 0.155) (layer "B.Cu") (net 229))
  (segment (start 130.59 143.39201) (end 129.89 142.69201) (width 0.155) (layer "B.Cu") (net 229))
  (segment (start 130.59 146.10799) (end 130.59 143.39201) (width 0.155) (layer "B.Cu") (net 229))
  (segment (start 129.61 140.146249) (end 129.61 139.647501) (width 0.155) (layer "F.Cu") (net 230))
  (segment (start 129.61 139.647501) (end 129.5 139.537501) (width 0.155) (layer "F.Cu") (net 230))
  (segment (start 129.5 139.537501) (end 129.5 138.9) (width 0.215) (layer "F.Cu") (net 230))
  (segment (start 129.5 140.6125) (end 129.5 140.256249) (width 0.215) (layer "F.Cu") (net 230))
  (segment (start 129.5 140.256249) (end 129.61 140.146249) (width 0.155) (layer "F.Cu") (net 230))
  (segment (start 129.5 140.6625) (end 129.5 141.4375) (width 0.215) (layer "F.Cu") (net 230))
  (segment (start 129.64 145.3275) (end 129.8625 145.55) (width 0.155) (layer "F.Cu") (net 230))
  (segment (start 129.5 142.84) (end 129.61 142.73) (width 0.155) (layer "F.Cu") (net 230))
  (segment (start 129.61 142.73) (end 129.61 142.4725) (width 0.155) (layer "F.Cu") (net 230))
  (segment (start 129.61 141.903751) (end 129.61 142.0275) (width 0.155) (layer "F.Cu") (net 230))
  (segment (start 129.61 142.0275) (end 129.3875 142.25) (width 0.155) (layer "F.Cu") (net 230))
  (segment (start 129.5 141.4375) (end 129.5 141.793751) (width 0.155) (layer "F.Cu") (net 230))
  (segment (start 129.5 141.793751) (end 129.61 141.903751) (width 0.155) (layer "F.Cu") (net 230))
  (segment (start 129.61 142.4725) (end 129.3875 142.25) (width 0.155) (layer "F.Cu") (net 230))
  (segment (start 129.75 144.94) (end 129.64 145.05) (width 0.155) (layer "F.Cu") (net 230))
  (segment (start 129.64 145.05) (end 129.64 145.3275) (width 0.155) (layer "F.Cu") (net 230))
  (via (at 129.3875 142.25) (size 0.6) (drill 0.25) (layers "F.Cu" "B.Cu") (net 230))
  (via (at 129.8625 145.55) (size 0.6) (drill 0.25) (layers "F.Cu" "B.Cu") (net 230))
  (segment (start 129.3875 142.2) (end 128.635 142.2) (width 0.155) (layer "B.Cu") (net 230))
  (segment (start 129.61 142.4225) (end 129.3875 142.2) (width 0.155) (layer "B.Cu") (net 230))
  (segment (start 130.31 145.99201) (end 130.31 143.50799) (width 0.155) (layer "B.Cu") (net 230))
  (segment (start 129.64 145.7725) (end 129.64 146.04201) (width 0.155) (layer "B.Cu") (net 230))
  (segment (start 129.8625 145.55) (end 129.64 145.7725) (width 0.155) (layer "B.Cu") (net 230))
  (segment (start 129.61 142.4725) (end 129.3875 142.25) (width 0.155) (layer "B.Cu") (net 230))
  (segment (start 129.795831 146.197841) (end 130.104169 146.197841) (width 0.155) (layer "B.Cu") (net 230))
  (segment (start 129.61 142.80799) (end 129.61 142.4725) (width 0.155) (layer "B.Cu") (net 230))
  (segment (start 129.64 146.04201) (end 129.795831 146.197841) (width 0.155) (layer "B.Cu") (net 230))
  (segment (start 130.31 143.50799) (end 129.61 142.80799) (width 0.155) (layer "B.Cu") (net 230))
  (segment (start 130.104169 146.197841) (end 130.31 145.99201) (width 0.155) (layer "B.Cu") (net 230))
  (segment (start 110.8 91.365) (end 113.3 91.365) (width 0.2) (layer "F.Cu") (net 231))
  (segment (start 114.095 94.05) (end 114.39 94.05) (width 0.2) (layer "F.Cu") (net 231))
  (segment (start 111.315 94.05) (end 111.55 94.285) (width 0.2) (layer "F.Cu") (net 231))
  (segment (start 111.55 94.285) (end 111.55 95.4) (width 0.2) (layer "F.Cu") (net 231))
  (segment (start 116.265 93.315) (end 116.3 93.35) (width 0.2) (layer "F.Cu") (net 231))
  (segment (start 114.3 91.365) (end 114.915 91.365) (width 0.2) (layer "F.Cu") (net 231))
  (segment (start 115.7 92.15) (end 116.3 92.15) (width 0.2) (layer "F.Cu") (net 231))
  (segment (start 115.125 93.315) (end 116.265 93.315) (width 0.2) (layer "F.Cu") (net 231))
  (segment (start 110.595 94.05) (end 111.315 94.05) (width 0.2) (layer "F.Cu") (net 231))
  (segment (start 113.3 91.365) (end 114.3 91.365) (width 0.2) (layer "F.Cu") (net 231))
  (segment (start 109.8 91.365) (end 110.8 91.365) (width 0.2) (layer "F.Cu") (net 231))
  (segment (start 114.915 91.365) (end 115.7 92.15) (width 0.2) (layer "F.Cu") (net 231))
  (segment (start 114.39 94.05) (end 115.125 93.315) (width 0.2) (layer "F.Cu") (net 231))
  (via (at 116.3 92.15) (size 0.6) (drill 0.25) (layers "F.Cu" "B.Cu") (net 231))
  (via (at 116.3 92.75) (size 0.6) (drill 0.25) (layers "F.Cu" "B.Cu") (net 231))
  (via (at 116.3 93.35) (size 0.6) (drill 0.25) (layers "F.Cu" "B.Cu") (net 231))
  (via (at 111.55 95.4) (size 0.6) (drill 0.25) (layers "F.Cu" "B.Cu") (net 231))
  (segment (start 111.55 95.4) (end 112.850001 93.649999) (width 0.2) (layer "In3.Cu") (net 231))
  (segment (start 112.850001 93.649999) (end 116.000001 93.649999) (width 0.2) (layer "In3.Cu") (net 231))
  (segment (start 116.000001 93.649999) (end 116.3 93.35) (width 0.2) (layer "In3.Cu") (net 231))
  (segment (start 116.3 92.75) (end 117.3992 92.75) (width 0.15) (layer "B.Cu") (net 231))
  (segment (start 141.7 139.9375) (end 141.7 139.1625) (width 0.125) (layer "F.Cu") (net 232))
  (segment (start 141.575 140.375002) (end 141.8125 140.612502) (width 0.125) (layer "F.Cu") (net 232))
  (segment (start 141.7 139.943751) (end 141.575 140.068751) (width 0.125) (layer "F.Cu") (net 232))
  (segment (start 141.575 140.068751) (end 141.575 140.375002) (width 0.125) (layer "F.Cu") (net 232))
  (segment (start 142.85 145.020658) (end 142.50751 144.678168) (width 0.125) (layer "F.Cu") (net 232))
  (segment (start 141.8125 142.4875) (end 141.8 142.5) (width 0.15) (layer "F.Cu") (net 232))
  (segment (start 142.50751 144.678168) (end 142.50751 143.49249) (width 0.125) (layer "F.Cu") (net 232))
  (segment (start 138.480344 130.5) (end 137.383811 130.5) (width 0.125) (layer "F.Cu") (net 232))
  (segment (start 142 142.5) (end 141.8125 142.3125) (width 0.15) (layer "F.Cu") (net 232))
  (segment (start 141.8125 142.3125) (end 141.8125 142.4875) (width 0.15) (layer "F.Cu") (net 232))
  (segment (start 141.5 142.5) (end 141.2 142.5) (width 0.15) (layer "F.Cu") (net 232))
  (segment (start 142.3 142.5) (end 142.1 142.5) (width 0.15) (layer "F.Cu") (net 232))
  (segment (start 142.1 142.5) (end 141.8 142.5) (width 0.15) (layer "F.Cu") (net 232))
  (segment (start 141.625 142.5) (end 141.8125 142.3125) (width 0.15) (layer "F.Cu") (net 232))
  (segment (start 141.5 142.5) (end 141.625 142.5) (width 0.15) (layer "F.Cu") (net 232))
  (segment (start 141.8125 141.8875) (end 141.8125 140.612502) (width 0.125) (layer "F.Cu") (net 232))
  (segment (start 141.7 139.1625) (end 141.7 138.7) (width 0.125) (layer "F.Cu") (net 232))
  (segment (start 142.50751 142.70751) (end 142.3 142.5) (width 0.15) (layer "F.Cu") (net 232))
  (segment (start 142.50751 143.49249) (end 142.50751 142.70751) (width 0.15) (layer "F.Cu") (net 232))
  (segment (start 141.8125 141.8875) (end 141.8125 142.3125) (width 0.125) (layer "F.Cu") (net 232))
  (segment (start 139.57322 128.5) (end 139.57322 129.407124) (width 0.125) (layer "F.Cu") (net 232))
  (segment (start 141.8 142.5) (end 141.5 142.5) (width 0.15) (layer "F.Cu") (net 232))
  (segment (start 139.57322 129.407124) (end 138.480344 130.5) (width 0.125) (layer "F.Cu") (net 232))
  (segment (start 142.1 142.5) (end 142 142.5) (width 0.15) (layer "F.Cu") (net 232))
  (segment (start 142.85 145.525) (end 142.85 145.020658) (width 0.125) (layer "F.Cu") (net 232))
  (segment (start 136.249358 131.634453) (end 137.383811 130.5) (width 0.125) (layer "F.Cu") (net 232))
  (segment (start 140.485 142.5) (end 141.2 142.5) (width 0.15) (layer "F.Cu") (net 232))
  (segment (start 141.7 138.7) (end 141.4 138.4) (width 0.125) (layer "F.Cu") (net 232))
  (via (at 136.249358 131.634453) (size 0.6) (drill 0.25) (layers "F.Cu" "B.Cu") (net 232))
  (via (at 141.4 138.4) (size 0.6) (drill 0.25) (layers "F.Cu" "B.Cu") (net 232))
  (segment (start 140.6 133.6) (end 140.2 133.2) (width 0.125) (layer "In2.Cu") (net 232))
  (segment (start 137.6 133.2) (end 136.249358 131.849358) (width 0.125) (layer "In2.Cu") (net 232))
  (segment (start 141.4 138.4) (end 140.6 137.6) (width 0.125) (layer "In2.Cu") (net 232))
  (segment (start 136.249358 131.849358) (end 136.249358 131.634453) (width 0.125) (layer "In2.Cu") (net 232))
  (segment (start 140.2 133.2) (end 137.6 133.2) (width 0.125) (layer "In2.Cu") (net 232))
  (segment (start 140.6 137.6) (end 140.6 133.6) (width 0.125) (layer "In2.Cu") (net 232))
  (segment (start 136.834453 131.634453) (end 137.2 132) (width 0.15) (layer "B.Cu") (net 232))
  (segment (start 136.249358 131.634453) (end 136.834453 131.634453) (width 0.15) (layer "B.Cu") (net 232))
  (segment (start 142.7 139.9375) (end 142.7 139.1625) (width 0.125) (layer "F.Cu") (net 233))
  (segment (start 142.7 141) (end 142.9 141.2) (width 0.15) (layer "F.Cu") (net 233))
  (segment (start 142.7 139.9375) (end 142.7 141) (width 0.15) (layer "F.Cu") (net 233))
  (segment (start 143.25 145.525) (end 143.25 144.699156) (width 0.125) (layer "F.Cu") (net 233))
  (segment (start 142.9 141.2) (end 142.9 144.349156) (width 0.15) (layer "F.Cu") (net 233))
  (segment (start 142.9 144.349156) (end 143.1625 144.611656) (width 0.15) (layer "F.Cu") (net 233))
  (segment (start 143.25 144.699156) (end 143.1625 144.611656) (width 0.125) (layer "F.Cu") (net 233))
  (via (at 143.1625 144.611656) (size 0.6) (drill 0.25) (layers "F.Cu" "B.Cu") (net 233))
  (via (at 140 145.6) (size 0.6) (drill 0.25) (layers "F.Cu" "B.Cu") (net 233))
  (segment (start 140.988344 144.611656) (end 140 145.6) (width 0.15) (layer "In3.Cu") (net 233))
  (segment (start 143.1625 144.611656) (end 140.988344 144.611656) (width 0.15) (layer "In3.Cu") (net 233))
  (segment (start 137.45 147) (end 139.235 147) (width 0.15) (layer "B.Cu") (net 233))
  (segment (start 139.25 146.035) (end 139.565 146.035) (width 0.15) (layer "B.Cu") (net 233))
  (segment (start 139.565 146.035) (end 140 145.6) (width 0.15) (layer "B.Cu") (net 233))
  (segment (start 139.25 146.035) (end 139.25 147.015) (width 0.15) (layer "B.Cu") (net 233))
  (segment (start 143.2 139.9375) (end 143.2 139.1625) (width 0.125) (layer "F.Cu") (net 234))
  (segment (start 144 141.6) (end 143.3125 140.9125) (width 0.15) (layer "F.Cu") (net 234))
  (segment (start 143.3125 140.9125) (end 143.3125 140.612502) (width 0.15) (layer "F.Cu") (net 234))
  (segment (start 146.9 141.6) (end 144 141.6) (width 0.15) (layer "F.Cu") (net 234))
  (segment (start 143.2 139.943751) (end 143.075 140.068751) (width 0.125) (layer "F.Cu") (net 234))
  (segment (start 143.075 140.375002) (end 143.3125 140.612502) (width 0.125) (layer "F.Cu") (net 234))
  (segment (start 143.075 140.068751) (end 143.075 140.375002) (width 0.125) (layer "F.Cu") (net 234))
  (segment (start 146.05 145.525) (end 146.05 144.25) (width 0.15) (layer "F.Cu") (net 234))
  (segment (start 148.3 143.015) (end 147.315 144) (width 0.15) (layer "F.Cu") (net 234))
  (segment (start 146.3 144) (end 147.315 144) (width 0.15) (layer "F.Cu") (net 234))
  (segment (start 147.315 142.015) (end 146.9 141.6) (width 0.15) (layer "F.Cu") (net 234))
  (segment (start 147.315 144) (end 147.315 142.015) (width 0.15) (layer "F.Cu") (net 234))
  (segment (start 146.05 144.25) (end 146.3 144) (width 0.15) (layer "F.Cu") (net 234))
  (via (at 143.3125 140.612502) (size 0.6) (drill 0.25) (layers "F.Cu" "B.Cu") (net 234))
  (segment (start 143.3 141.2008) (end 143.3 140.625002) (width 0.2) (layer "B.Cu") (net 234))
  (segment (start 143.3 140.625002) (end 143.3125 140.612502) (width 0.2) (layer "B.Cu") (net 234))
  (segment (start 141.325 140.375002) (end 141.0875 140.612502) (width 0.125) (layer "F.Cu") (net 235))
  (segment (start 141.325 140.068751) (end 141.325 140.375002) (width 0.125) (layer "F.Cu") (net 235))
  (segment (start 141.2 139.943751) (end 141.325 140.068751) (width 0.125) (layer "F.Cu") (net 235))
  (segment (start 140.485 141.215002) (end 141.0875 140.612502) (width 0.125) (layer "F.Cu") (net 235))
  (segment (start 141.2 139.9375) (end 141.2 139.1625) (width 0.125) (layer "F.Cu") (net 235))
  (segment (start 140.485 141.5) (end 140.485 141.215002) (width 0.125) (layer "F.Cu") (net 235))
  (segment (start 139.17322 128.5) (end 139.17322 129.42678) (width 0.125) (layer "F.Cu") (net 235))
  (segment (start 139.17322 129.42678) (end 138.42498 130.17502) (width 0.125) (layer "F.Cu") (net 235))
  (segment (start 136.1 130.925003) (end 136.474997 130.925003) (width 0.125) (layer "F.Cu") (net 235))
  (segment (start 142.65 146.75) (end 142.45 146.75) (width 0.15) (layer "F.Cu") (net 235))
  (segment (start 142.45 146.75) (end 142.2 147) (width 0.15) (layer "F.Cu") (net 235))
  (segment (start 141.2 139.117062) (end 140.712203 138.629265) (width 0.125) (layer "F.Cu") (net 235))
  (segment (start 138.42498 130.17502) (end 137.22498 130.17502) (width 0.125) (layer "F.Cu") (net 235))
  (segment (start 136.474997 130.925003) (end 137.22498 130.17502) (width 0.125) (layer "F.Cu") (net 235))
  (segment (start 142.2 147) (end 142.2 148.1) (width 0.15) (layer "F.Cu") (net 235))
  (via (at 141.0875 140.612502) (size 0.6) (drill 0.25) (layers "F.Cu" "B.Cu") (net 235))
  (via (at 136.1 130.925003) (size 0.6) (drill 0.25) (layers "F.Cu" "B.Cu") (net 235))
  (via (at 142.2 148.1) (size 0.6) (drill 0.25) (layers "F.Cu" "B.Cu") (net 235))
  (via (at 140.712203 138.629265) (size 0.6) (drill 0.25) (layers "F.Cu" "B.Cu") (net 235))
  (segment (start 139.953299 133.553299) (end 137.446701 133.553299) (width 0.125) (layer "In2.Cu") (net 235))
  (segment (start 135.874997 130.925003) (end 136.1 130.925003) (width 0.125) (layer "In2.Cu") (net 235))
  (segment (start 142.2 141.725002) (end 141.0875 140.612502) (width 0.15) (layer "In2.Cu") (net 235))
  (segment (start 140.2 133.8) (end 139.953299 133.553299) (width 0.125) (layer "In2.Cu") (net 235))
  (segment (start 135.6 131.706597) (end 135.6 131.2) (width 0.125) (layer "In2.Cu") (net 235))
  (segment (start 140.2 138.117062) (end 140.2 133.8) (width 0.125) (layer "In2.Cu") (net 235))
  (segment (start 135.6 131.2) (end 135.874997 130.925003) (width 0.125) (layer "In2.Cu") (net 235))
  (segment (start 140.712203 138.629265) (end 140.2 138.117062) (width 0.125) (layer "In2.Cu") (net 235))
  (segment (start 137.446701 133.553299) (end 135.6 131.706597) (width 0.125) (layer "In2.Cu") (net 235))
  (segment (start 142.2 148.1) (end 142.2 141.725002) (width 0.15) (layer "In2.Cu") (net 235))
  (segment (start 136.1 130.925003) (end 137.125797 130.925003) (width 0.15) (layer "B.Cu") (net 235))
  (segment (start 143.7 142.825) (end 143.4625 143.0625) (width 0.125) (layer "F.Cu") (net 236))
  (segment (start 139.35 139.943751) (end 139.475 140.068751) (width 0.125) (layer "F.Cu") (net 236))
  (segment (start 139.475 140.375002) (end 139.2375 140.612502) (width 0.125) (layer "F.Cu") (net 236))
  (segment (start 139.475 138.448222) (end 140.325 137.598222) (width 0.125) (layer "F.Cu") (net 236))
  (segment (start 139.475 140.068751) (end 139.475 140.375002) (width 0.125) (layer "F.Cu") (net 236))
  (segment (start 140.325 137.598222) (end 140.325 137.440001) (width 0.125) (layer "F.Cu") (net 236))
  (segment (start 140.325 137.440001) (end 140.21 137.325001) (width 0.125) (layer "F.Cu") (net 236))
  (segment (start 140.21 137.325001) (end 140.21 137.1) (width 0.125) (layer "F.Cu") (net 236))
  (segment (start 139.35 139.1625) (end 139.35 139.9375) (width 0.125) (layer "F.Cu") (net 236))
  (segment (start 139.475 139.0375) (end 139.475 138.448222) (width 0.125) (layer "F.Cu") (net 236))
  (segment (start 139.35 139.1625) (end 139.475 139.0375) (width 0.125) (layer "F.Cu") (net 236))
  (segment (start 144.05 145.525) (end 144.05 144.887499) (width 0.125) (layer "F.Cu") (net 236))
  (segment (start 143.998222 142.825) (end 143.7 142.825) (width 0.125) (layer "F.Cu") (net 236))
  (segment (start 144.125 142.951778) (end 143.998222 142.825) (width 0.125) (layer "F.Cu") (net 236))
  (segment (start 144.125 144.812499) (end 144.125 142.951778) (width 0.125) (layer "F.Cu") (net 236))
  (segment (start 144.05 144.887499) (end 144.125 144.812499) (width 0.125) (layer "F.Cu") (net 236))
  (via (at 139.2375 140.612502) (size 0.6) (drill 0.25) (layers "F.Cu" "B.Cu") (net 236))
  (via (at 143.4625 143.0625) (size 0.6) (drill 0.25) (layers "F.Cu" "B.Cu") (net 236))
  (segment (start 143.4625 143.0625) (end 143.225 142.825) (width 0.125) (layer "B.Cu") (net 236))
  (segment (start 143.225 142.825) (end 139.948222 142.825) (width 0.125) (layer "B.Cu") (net 236))
  (segment (start 139.475 140.850002) (end 139.2375 140.612502) (width 0.125) (layer "B.Cu") (net 236))
  (segment (start 139.475 142.351778) (end 139.475 140.850002) (width 0.125) (layer "B.Cu") (net 236))
  (segment (start 139.948222 142.825) (end 139.475 142.351778) (width 0.125) (layer "B.Cu") (net 236))
  (segment (start 137.375 137.598222) (end 137.375 137.440001) (width 0.125) (layer "F.Cu") (net 237))
  (segment (start 137.375 137.440001) (end 137.49 137.325001) (width 0.125) (layer "F.Cu") (net 237))
  (segment (start 138.225 140.068751) (end 138.225 140.375002) (width 0.125) (layer "F.Cu") (net 237))
  (segment (start 138.225 140.375002) (end 138.4625 140.612502) (width 0.125) (layer "F.Cu") (net 237))
  (segment (start 138.35 139.943751) (end 138.225 140.068751) (width 0.125) (layer "F.Cu") (net 237))
  (segment (start 137.49 137.325001) (end 137.49 137.1) (width 0.125) (layer "F.Cu") (net 237))
  (segment (start 138.225 138.448222) (end 137.375 137.598222) (width 0.125) (layer "F.Cu") (net 237))
  (segment (start 138.225 139.0375) (end 138.225 138.448222) (width 0.125) (layer "F.Cu") (net 237))
  (segment (start 143.85 147.500001) (end 143.775 147.575001) (width 0.125) (layer "F.Cu") (net 237))
  (segment (start 143.603827 148.526791) (end 143.603827 148.862668) (width 0.125) (layer "F.Cu") (net 237))
  (segment (start 143.775 147.575001) (end 143.775 148.355618) (width 0.125) (layer "F.Cu") (net 237))
  (segment (start 143.85 146.75) (end 143.85 147.500001) (width 0.125) (layer "F.Cu") (net 237))
  (segment (start 138.225 139.0375) (end 138.35 139.1625) (width 0.125) (layer "F.Cu") (net 237))
  (segment (start 143.775 148.355618) (end 143.603827 148.526791) (width 0.125) (layer "F.Cu") (net 237))
  (segment (start 138.35 139.1625) (end 138.35 139.9375) (width 0.125) (layer "F.Cu") (net 237))
  (via (at 138.4625 140.612502) (size 0.6) (drill 0.25) (layers "F.Cu" "B.Cu") (net 237))
  (via (at 143.603827 148.862668) (size 0.6) (drill 0.25) (layers "F.Cu" "B.Cu") (net 237))
  (segment (start 142.651778 145.075) (end 140.651778 145.075) (width 0.125) (layer "B.Cu") (net 237))
  (segment (start 140.651778 145.075) (end 138.225 142.648222) (width 0.125) (layer "B.Cu") (net 237))
  (segment (start 143.775 146.198222) (end 142.651778 145.075) (width 0.125) (layer "B.Cu") (net 237))
  (segment (start 143.603827 148.526791) (end 143.775 148.355618) (width 0.125) (layer "B.Cu") (net 237))
  (segment (start 138.225 142.648222) (end 138.225 140.850002) (width 0.125) (layer "B.Cu") (net 237))
  (segment (start 143.775 148.355618) (end 143.775 146.198222) (width 0.125) (layer "B.Cu") (net 237))
  (segment (start 143.603827 148.862668) (end 143.603827 148.526791) (width 0.125) (layer "B.Cu") (net 237))
  (segment (start 138.225 140.850002) (end 138.4625 140.612502) (width 0.125) (layer "B.Cu") (net 237))
  (segment (start 137.125 137.440001) (end 137.01 137.325001) (width 0.125) (layer "F.Cu") (net 238))
  (segment (start 137.01 137.325001) (end 137.01 137.1) (width 0.125) (layer "F.Cu") (net 238))
  (segment (start 137.125 137.701778) (end 137.125 137.440001) (width 0.125) (layer "F.Cu") (net 238))
  (segment (start 137.85 139.1625) (end 137.975 139.0375) (width 0.125) (layer "F.Cu") (net 238))
  (segment (start 137.975 138.551778) (end 137.125 137.701778) (width 0.125) (layer "F.Cu") (net 238))
  (segment (start 137.975 139.0375) (end 137.975 138.551778) (width 0.125) (layer "F.Cu") (net 238))
  (segment (start 137.975 140.375002) (end 137.7375 140.612502) (width 0.125) (layer "F.Cu") (net 238))
  (segment (start 137.85 139.943751) (end 137.975 140.068751) (width 0.125) (layer "F.Cu") (net 238))
  (segment (start 137.975 140.068751) (end 137.975 140.375002) (width 0.125) (layer "F.Cu") (net 238))
  (segment (start 137.85 139.9375) (end 137.85 139.1625) (width 0.125) (layer "F.Cu") (net 238))
  (segment (start 143.525 147.575001) (end 143.525 148.252064) (width 0.125) (layer "F.Cu") (net 238))
  (segment (start 143.45 147.500001) (end 143.525 147.575001) (width 0.125) (layer "F.Cu") (net 238))
  (segment (start 143.45 146.75) (end 143.45 147.500001) (width 0.125) (layer "F.Cu") (net 238))
  (segment (start 143.525 148.252064) (end 143.42705 148.350014) (width 0.125) (layer "F.Cu") (net 238))
  (segment (start 143.42705 148.350014) (end 143.091173 148.350014) (width 0.125) (layer "F.Cu") (net 238))
  (via (at 137.7375 140.612502) (size 0.6) (drill 0.25) (layers "F.Cu" "B.Cu") (net 238))
  (via (at 143.091173 148.350014) (size 0.6) (drill 0.25) (layers "F.Cu" "B.Cu") (net 238))
  (segment (start 143.525 148.252064) (end 143.525 146.301778) (width 0.125) (layer "B.Cu") (net 238))
  (segment (start 137.975 142.751778) (end 137.975 140.850002) (width 0.125) (layer "B.Cu") (net 238))
  (segment (start 143.525 146.301778) (end 142.548222 145.325) (width 0.125) (layer "B.Cu") (net 238))
  (segment (start 143.42705 148.350014) (end 143.525 148.252064) (width 0.125) (layer "B.Cu") (net 238))
  (segment (start 140.548222 145.325) (end 137.975 142.751778) (width 0.125) (layer "B.Cu") (net 238))
  (segment (start 137.975 140.850002) (end 137.7375 140.612502) (width 0.125) (layer "B.Cu") (net 238))
  (segment (start 142.548222 145.325) (end 140.548222 145.325) (width 0.125) (layer "B.Cu") (net 238))
  (segment (start 143.091173 148.350014) (end 143.42705 148.350014) (width 0.125) (layer "B.Cu") (net 238))
  (segment (start 143.7 142.575) (end 143.4625 142.3375) (width 0.125) (layer "F.Cu") (net 239))
  (segment (start 139.85 139.943751) (end 139.725 140.068751) (width 0.125) (layer "F.Cu") (net 239))
  (segment (start 139.725 140.068751) (end 139.725 140.375002) (width 0.125) (layer "F.Cu") (net 239))
  (segment (start 139.725 140.375002) (end 139.9625 140.612502) (width 0.125) (layer "F.Cu") (net 239))
  (segment (start 140.69 137.325001) (end 140.69 137.1) (width 0.125) (layer "F.Cu") (net 239))
  (segment (start 140.575 137.440001) (end 140.69 137.325001) (width 0.125) (layer "F.Cu") (net 239))
  (segment (start 139.725 139.0375) (end 139.725 138.551778) (width 0.125) (layer "F.Cu") (net 239))
  (segment (start 140.575 137.701778) (end 140.575 137.440001) (width 0.125) (layer "F.Cu") (net 239))
  (segment (start 139.85 139.1625) (end 139.725 139.0375) (width 0.125) (layer "F.Cu") (net 239))
  (segment (start 139.85 139.1625) (end 139.85 139.9375) (width 0.125) (layer "F.Cu") (net 239))
  (segment (start 139.725 138.551778) (end 140.575 137.701778) (width 0.125) (layer "F.Cu") (net 239))
  (segment (start 144.45 145.525) (end 144.45 144.887499) (width 0.125) (layer "F.Cu") (net 239))
  (segment (start 144.375 142.848222) (end 144.101778 142.575) (width 0.125) (layer "F.Cu") (net 239))
  (segment (start 144.101778 142.575) (end 143.7 142.575) (width 0.125) (layer "F.Cu") (net 239))
  (segment (start 144.375 144.812499) (end 144.375 142.848222) (width 0.125) (layer "F.Cu") (net 239))
  (segment (start 144.45 144.887499) (end 144.375 144.812499) (width 0.125) (layer "F.Cu") (net 239))
  (via (at 139.9625 140.612502) (size 0.6) (drill 0.25) (layers "F.Cu" "B.Cu") (net 239))
  (via (at 143.4625 142.3375) (size 0.6) (drill 0.25) (layers "F.Cu" "B.Cu") (net 239))
  (segment (start 140.051778 142.575) (end 139.725 142.248222) (width 0.125) (layer "B.Cu") (net 239))
  (segment (start 143.225 142.575) (end 140.051778 142.575) (width 0.125) (layer "B.Cu") (net 239))
  (segment (start 143.4625 142.3375) (end 143.225 142.575) (width 0.125) (layer "B.Cu") (net 239))
  (segment (start 139.725 140.850002) (end 139.9625 140.612502) (width 0.125) (layer "B.Cu") (net 239))
  (segment (start 139.725 142.248222) (end 139.725 140.850002) (width 0.125) (layer "B.Cu") (net 239))
  (segment (start 145.75 139.943751) (end 145.875 140.068751) (width 0.125) (layer "F.Cu") (net 240))
  (segment (start 145.875 140.375002) (end 145.6375 140.612502) (width 0.125) (layer "F.Cu") (net 240))
  (segment (start 146.725 137.598222) (end 146.725 137.440001) (width 0.125) (layer "F.Cu") (net 240))
  (segment (start 145.875 140.068751) (end 145.875 140.375002) (width 0.125) (layer "F.Cu") (net 240))
  (segment (start 145.75 139.1625) (end 145.875 139.0375) (width 0.125) (layer "F.Cu") (net 240))
  (segment (start 145.875 139.0375) (end 145.875 138.448222) (width 0.125) (layer "F.Cu") (net 240))
  (segment (start 145.875 138.448222) (end 146.725 137.598222) (width 0.125) (layer "F.Cu") (net 240))
  (segment (start 146.725 137.440001) (end 146.61 137.325001) (width 0.125) (layer "F.Cu") (net 240))
  (segment (start 146.61 137.325001) (end 146.61 137.1) (width 0.125) (layer "F.Cu") (net 240))
  (segment (start 145.75 139.9375) (end 145.75 139.1625) (width 0.125) (layer "F.Cu") (net 240))
  (segment (start 145.6375 142.8) (end 145.875 143.0375) (width 0.125) (layer "F.Cu") (net 240))
  (segment (start 145.25 144.887499) (end 145.25 145.525) (width 0.125) (layer "F.Cu") (net 240))
  (segment (start 145.875 143.0375) (end 145.875 143.148222) (width 0.125) (layer "F.Cu") (net 240))
  (segment (start 145.325 143.698222) (end 145.325 144.812499) (width 0.125) (layer "F.Cu") (net 240))
  (segment (start 145.875 143.148222) (end 145.325 143.698222) (width 0.125) (layer "F.Cu") (net 240))
  (segment (start 145.325 144.812499) (end 145.25 144.887499) (width 0.125) (layer "F.Cu") (net 240))
  (via (at 145.6375 140.612502) (size 0.6) (drill 0.25) (layers "F.Cu" "B.Cu") (net 240))
  (via (at 145.6375 142.8) (size 0.6) (drill 0.25) (layers "F.Cu" "B.Cu") (net 240))
  (segment (start 145.875 142.5625) (end 145.6375 142.8) (width 0.125) (layer "B.Cu") (net 240))
  (segment (start 145.6375 140.612502) (end 145.875 140.850002) (width 0.125) (layer "B.Cu") (net 240))
  (segment (start 145.875 140.850002) (end 145.875 142.5625) (width 0.125) (layer "B.Cu") (net 240))
  (segment (start 144.625 139.0375) (end 144.625 138.448222) (width 0.125) (layer "F.Cu") (net 241))
  (segment (start 143.775 137.598222) (end 143.775 137.440001) (width 0.125) (layer "F.Cu") (net 241))
  (segment (start 144.75 139.9375) (end 144.75 139.1625) (width 0.125) (layer "F.Cu") (net 241))
  (segment (start 144.75 139.943751) (end 144.625 140.068751) (width 0.125) (layer "F.Cu") (net 241))
  (segment (start 144.625 140.068751) (end 144.625 140.375002) (width 0.125) (layer "F.Cu") (net 241))
  (segment (start 144.625 140.375002) (end 144.8625 140.612502) (width 0.125) (layer "F.Cu") (net 241))
  (segment (start 143.775 137.440001) (end 143.89 137.325001) (width 0.125) (layer "F.Cu") (net 241))
  (segment (start 144.75 139.1625) (end 144.625 139.0375) (width 0.125) (layer "F.Cu") (net 241))
  (segment (start 143.89 137.325001) (end 143.89 137.1) (width 0.125) (layer "F.Cu") (net 241))
  (segment (start 144.625 138.448222) (end 143.775 137.598222) (width 0.125) (layer "F.Cu") (net 241))
  (segment (start 145.22045 148.343673) (end 145.556327 148.343673) (width 0.125) (layer "F.Cu") (net 241))
  (segment (start 145.05 147.500001) (end 144.975 147.575001) (width 0.125) (layer "F.Cu") (net 241))
  (segment (start 144.975 147.575001) (end 144.975 148.098223) (width 0.125) (layer "F.Cu") (net 241))
  (segment (start 145.05 146.75) (end 145.05 147.500001) (width 0.125) (layer "F.Cu") (net 241))
  (segment (start 144.975 148.098223) (end 145.22045 148.343673) (width 0.125) (layer "F.Cu") (net 241))
  (via (at 144.8625 140.612502) (size 0.6) (drill 0.25) (layers "F.Cu" "B.Cu") (net 241))
  (via (at 145.556327 148.343673) (size 0.6) (drill 0.25) (layers "F.Cu" "B.Cu") (net 241))
  (segment (start 144.625 142.651778) (end 144.325 142.951778) (width 0.125) (layer "B.Cu") (net 241))
  (segment (start 144.325 143.548222) (end 144.975 144.198222) (width 0.125) (layer "B.Cu") (net 241))
  (segment (start 145.556327 148.343673) (end 145.22045 148.343673) (width 0.125) (layer "B.Cu") (net 241))
  (segment (start 144.8625 140.612502) (end 144.625 140.850002) (width 0.125) (layer "B.Cu") (net 241))
  (segment (start 144.325 142.951778) (end 144.325 143.548222) (width 0.125) (layer "B.Cu") (net 241))
  (segment (start 145.22045 148.343673) (end 144.975 148.098223) (width 0.125) (layer "B.Cu") (net 241))
  (segment (start 144.625 140.850002) (end 144.625 142.651778) (width 0.125) (layer "B.Cu") (net 241))
  (segment (start 144.975 148.098223) (end 144.975 144.198222) (width 0.125) (layer "B.Cu") (net 241))
  (segment (start 144.25 139.1625) (end 144.375 139.0375) (width 0.125) (layer "F.Cu") (net 242))
  (segment (start 144.25 139.9375) (end 144.25 139.1625) (width 0.125) (layer "F.Cu") (net 242))
  (segment (start 144.375 139.0375) (end 144.375 138.551778) (width 0.125) (layer "F.Cu") (net 242))
  (segment (start 143.525 137.440001) (end 143.41 137.325001) (width 0.125) (layer "F.Cu") (net 242))
  (segment (start 143.525 137.701778) (end 143.525 137.440001) (width 0.125) (layer "F.Cu") (net 242))
  (segment (start 143.41 137.325001) (end 143.41 137.1) (width 0.125) (layer "F.Cu") (net 242))
  (segment (start 144.375 140.068751) (end 144.375 140.375002) (width 0.125) (layer "F.Cu") (net 242))
  (segment (start 144.25 139.943751) (end 144.375 140.068751) (width 0.125) (layer "F.Cu") (net 242))
  (segment (start 144.375 138.551778) (end 143.525 137.701778) (width 0.125) (layer "F.Cu") (net 242))
  (segment (start 144.375 140.375002) (end 144.1375 140.612502) (width 0.125) (layer "F.Cu") (net 242))
  (segment (start 145.043673 148.52045) (end 145.043673 148.856327) (width 0.125) (layer "F.Cu") (net 242))
  (segment (start 144.725 147.575001) (end 144.725 148.201777) (width 0.125) (layer "F.Cu") (net 242))
  (segment (start 144.725 148.201777) (end 145.043673 148.52045) (width 0.125) (layer "F.Cu") (net 242))
  (segment (start 144.65 147.500001) (end 144.725 147.575001) (width 0.125) (layer "F.Cu") (net 242))
  (segment (start 144.65 146.75) (end 144.65 147.500001) (width 0.125) (layer "F.Cu") (net 242))
  (via (at 144.1375 140.612502) (size 0.6) (drill 0.25) (layers "F.Cu" "B.Cu") (net 242))
  (via (at 145.043673 148.856327) (size 0.6) (drill 0.25) (layers "F.Cu" "B.Cu") (net 242))
  (segment (start 144.075 143.651778) (end 144.725 144.301778) (width 0.125) (layer "B.Cu") (net 242))
  (segment (start 144.375 142.548222) (end 144.075 142.848222) (width 0.125) (layer "B.Cu") (net 242))
  (segment (start 144.075 142.848222) (end 144.075 143.651778) (width 0.125) (layer "B.Cu") (net 242))
  (segment (start 144.375 140.850002) (end 144.375 142.548222) (width 0.125) (layer "B.Cu") (net 242))
  (segment (start 144.725 148.201777) (end 144.725 144.301778) (width 0.125) (layer "B.Cu") (net 242))
  (segment (start 145.043673 148.52045) (end 144.725 148.201777) (width 0.125) (layer "B.Cu") (net 242))
  (segment (start 145.043673 148.856327) (end 145.043673 148.52045) (width 0.125) (layer "B.Cu") (net 242))
  (segment (start 144.1375 140.612502) (end 144.375 140.850002) (width 0.125) (layer "B.Cu") (net 242))
  (segment (start 146.25 139.9375) (end 146.25 139.1625) (width 0.125) (layer "F.Cu") (net 243))
  (segment (start 146.125 140.068751) (end 146.125 140.375002) (width 0.125) (layer "F.Cu") (net 243))
  (segment (start 146.125 140.375002) (end 146.3625 140.612502) (width 0.125) (layer "F.Cu") (net 243))
  (segment (start 146.25 139.943751) (end 146.125 140.068751) (width 0.125) (layer "F.Cu") (net 243))
  (segment (start 146.25 139.1625) (end 146.125 139.0375) (width 0.125) (layer "F.Cu") (net 243))
  (segment (start 146.125 139.0375) (end 146.125 138.551778) (width 0.125) (layer "F.Cu") (net 243))
  (segment (start 146.125 138.551778) (end 146.975 137.701778) (width 0.125) (layer "F.Cu") (net 243))
  (segment (start 147.09 137.325001) (end 147.09 137.1) (width 0.125) (layer "F.Cu") (net 243))
  (segment (start 146.975 137.440001) (end 147.09 137.325001) (width 0.125) (layer "F.Cu") (net 243))
  (segment (start 146.975 137.701778) (end 146.975 137.440001) (width 0.125) (layer "F.Cu") (net 243))
  (segment (start 146.125 143.251778) (end 145.575 143.801778) (width 0.125) (layer "F.Cu") (net 243))
  (segment (start 145.575 144.812499) (end 145.65 144.887499) (width 0.125) (layer "F.Cu") (net 243))
  (segment (start 146.125 143.0375) (end 146.125 143.251778) (width 0.125) (layer "F.Cu") (net 243))
  (segment (start 146.3625 142.8) (end 146.125 143.0375) (width 0.125) (layer "F.Cu") (net 243))
  (segment (start 145.575 143.801778) (end 145.575 144.812499) (width 0.125) (layer "F.Cu") (net 243))
  (segment (start 145.65 144.887499) (end 145.65 145.525) (width 0.125) (layer "F.Cu") (net 243))
  (via (at 146.3625 140.612502) (size 0.6) (drill 0.25) (layers "F.Cu" "B.Cu") (net 243))
  (via (at 146.3625 142.8) (size 0.6) (drill 0.25) (layers "F.Cu" "B.Cu") (net 243))
  (segment (start 146.125 142.5625) (end 146.3625 142.8) (width 0.125) (layer "B.Cu") (net 243))
  (segment (start 146.3625 140.612502) (end 146.125 140.850002) (width 0.125) (layer "B.Cu") (net 243))
  (segment (start 146.125 140.850002) (end 146.125 142.5625) (width 0.125) (layer "B.Cu") (net 243))
  (segment (start 138.8 146.05) (end 137.45 146.05) (width 0.3) (layer "F.Cu") (net 244))
  (segment (start 141.7 145.1) (end 141.7 144.085) (width 0.25) (layer "F.Cu") (net 245))
  (segment (start 140.185 144.085) (end 139.435 144.085) (width 0.2) (layer "F.Cu") (net 245))
  (segment (start 142.45 145.525) (end 142.125 145.525) (width 0.25) (layer "F.Cu") (net 245))
  (segment (start 140.185 144.085) (end 138.935 144.085) (width 0.2) (layer "F.Cu") (net 245))
  (segment (start 141.7 144.085) (end 140.185 144.085) (width 0.2) (layer "F.Cu") (net 245))
  (segment (start 138.935 144.085) (end 141.7 144.085) (width 0.3) (layer "F.Cu") (net 245))
  (segment (start 142.125 145.525) (end 141.7 145.1) (width 0.25) (layer "F.Cu") (net 245))
  (segment (start 122.59299 95.19299) (end 122.59299 98.49299) (width 0.182) (layer "F.Cu") (net 246))
  (segment (start 123.08598 98.98598) (end 127.436014 98.98598) (width 0.182) (layer "F.Cu") (net 246))
  (segment (start 134.133999 101.233999) (end 134.6 101.7) (width 0.182) (layer "F.Cu") (net 246))
  (segment (start 132.629683 101.233999) (end 134.133999 101.233999) (width 0.182) (layer "F.Cu") (net 246))
  (segment (start 132.247681 101.616001) (end 132.629683 101.233999) (width 0.182) (layer "F.Cu") (net 246))
  (segment (start 127.436014 98.98598) (end 130.066034 101.616001) (width 0.182) (layer "F.Cu") (net 246))
  (segment (start 130.066034 101.616001) (end 132.247681 101.616001) (width 0.182) (layer "F.Cu") (net 246))
  (segment (start 121.9 94.5) (end 122.59299 95.19299) (width 0.182) (layer "F.Cu") (net 246))
  (segment (start 121.9 94.285) (end 121.9 94.5) (width 0.182) (layer "F.Cu") (net 246))
  (segment (start 122.59299 98.49299) (end 123.08598 98.98598) (width 0.182) (layer "F.Cu") (net 246))
  (via (at 134.6 101.7) (size 0.6) (drill 0.25) (layers "F.Cu" "B.Cu") (net 246))
  (segment (start 133.625 88.225) (end 124.425 88.225) (width 0.182) (layer "B.Cu") (net 246))
  (segment (start 134.5 101.6) (end 134.5 100.3625) (width 0.182) (layer "B.Cu") (net 246))
  (segment (start 134.5 100.3625) (end 134.646 100.2165) (width 0.182) (layer "B.Cu") (net 246))
  (segment (start 134.646 100.2165) (end 134.646 89.246) (width 0.182) (layer "B.Cu") (net 246))
  (segment (start 134.6 101.7) (end 134.5 101.6) (width 0.182) (layer "B.Cu") (net 246))
  (segment (start 134.646 89.246) (end 133.625 88.225) (width 0.182) (layer "B.Cu") (net 246))
  (segment (start 121.997623 99.622282) (end 122.040285 99.649087) (width 0.182) (layer "F.Cu") (net 247))
  (segment (start 123.480641 99.774932) (end 123.497282 99.727376) (width 0.182) (layer "F.Cu") (net 247))
  (segment (start 123.030641 100.146475) (end 123.047282 100.194031) (width 0.182) (layer "F.Cu") (net 247))
  (segment (start 123.025 99.825) (end 123.025 100.096408) (width 0.182) (layer "F.Cu") (net 247))
  (segment (start 123.025 100.096408) (end 123.030641 100.146475) (width 0.182) (layer "F.Cu") (net 247))
  (segment (start 123.390285 100.27232) (end 123.425912 100.236693) (width 0.182) (layer "F.Cu") (net 247))
  (segment (start 122.575 99.825) (end 122.580641 99.774932) (width 0.182) (layer "F.Cu") (net 247))
  (segment (start 122.975912 99.684714) (end 123.002717 99.727376) (width 0.182) (layer "F.Cu") (net 247))
  (segment (start 122.299932 100.315766) (end 122.35 100.321408) (width 0.182) (layer "F.Cu") (net 247))
  (segment (start 122.040285 99.649087) (end 122.075912 99.684714) (width 0.182) (layer "F.Cu") (net 247))
  (segment (start 122.125 100.096408) (end 122.130641 100.146475) (width 0.182) (layer "F.Cu") (net 247))
  (segment (start 129.811701 102.230021) (end 132.355522 102.230021) (width 0.182) (layer "F.Cu") (net 247))
  (segment (start 123.347623 100.299125) (end 123.390285 100.27232) (width 0.182) (layer "F.Cu") (net 247))
  (segment (start 122.897623 99.622282) (end 122.940285 99.649087) (width 0.182) (layer "F.Cu") (net 247))
  (segment (start 123.452717 100.194031) (end 123.469358 100.146475) (width 0.182) (layer "F.Cu") (net 247))
  (segment (start 132.355522 102.230021) (end 132.625501 102.5) (width 0.182) (layer "F.Cu") (net 247))
  (segment (start 123.047282 100.194031) (end 123.074087 100.236693) (width 0.182) (layer "F.Cu") (net 247))
  (segment (start 123.425912 100.236693) (end 123.452717 100.194031) (width 0.182) (layer "F.Cu") (net 247))
  (segment (start 122.580641 99.774932) (end 122.597282 99.727376) (width 0.182) (layer "F.Cu") (net 247))
  (segment (start 123.497282 99.727376) (end 123.524087 99.684714) (width 0.182) (layer "F.Cu") (net 247))
  (segment (start 123.300067 100.315766) (end 123.347623 100.299125) (width 0.182) (layer "F.Cu") (net 247))
  (segment (start 122.552717 100.194031) (end 122.569358 100.146475) (width 0.182) (layer "F.Cu") (net 247))
  (segment (start 122.075912 99.684714) (end 122.102717 99.727376) (width 0.182) (layer "F.Cu") (net 247))
  (segment (start 120.59299 99.09299) (end 121.1 99.6) (width 0.182) (layer "F.Cu") (net 247))
  (segment (start 122.252376 100.299125) (end 122.299932 100.315766) (width 0.182) (layer "F.Cu") (net 247))
  (segment (start 127.18168 99.6) (end 129.811701 102.230021) (width 0.182) (layer "F.Cu") (net 247))
  (segment (start 122.749932 99.605641) (end 122.8 99.6) (width 0.182) (layer "F.Cu") (net 247))
  (segment (start 132.625501 102.5) (end 133.7 102.5) (width 0.182) (layer "F.Cu") (net 247))
  (segment (start 122.659714 99.649087) (end 122.702376 99.622282) (width 0.182) (layer "F.Cu") (net 247))
  (segment (start 122.624087 99.684714) (end 122.659714 99.649087) (width 0.182) (layer "F.Cu") (net 247))
  (segment (start 122.569358 100.146475) (end 122.575 100.096408) (width 0.182) (layer "F.Cu") (net 247))
  (segment (start 123.152376 100.299125) (end 123.199932 100.315766) (width 0.182) (layer "F.Cu") (net 247))
  (segment (start 123.475 100.096408) (end 123.475 99.825) (width 0.182) (layer "F.Cu") (net 247))
  (segment (start 120.59299 94.97799) (end 120.59299 99.09299) (width 0.182) (layer "F.Cu") (net 247))
  (segment (start 122.209714 100.27232) (end 122.252376 100.299125) (width 0.182) (layer "F.Cu") (net 247))
  (segment (start 122.597282 99.727376) (end 122.624087 99.684714) (width 0.182) (layer "F.Cu") (net 247))
  (segment (start 123.469358 100.146475) (end 123.475 100.096408) (width 0.182) (layer "F.Cu") (net 247))
  (segment (start 122.850067 99.605641) (end 122.897623 99.622282) (width 0.182) (layer "F.Cu") (net 247))
  (segment (start 123.002717 99.727376) (end 123.019358 99.774932) (width 0.182) (layer "F.Cu") (net 247))
  (segment (start 122.147282 100.194031) (end 122.174087 100.236693) (width 0.182) (layer "F.Cu") (net 247))
  (segment (start 122.575 100.096408) (end 122.575 99.825) (width 0.182) (layer "F.Cu") (net 247))
  (segment (start 122.35 100.321408) (end 122.400067 100.315766) (width 0.182) (layer "F.Cu") (net 247))
  (segment (start 122.525912 100.236693) (end 122.552717 100.194031) (width 0.182) (layer "F.Cu") (net 247))
  (segment (start 122.174087 100.236693) (end 122.209714 100.27232) (width 0.182) (layer "F.Cu") (net 247))
  (segment (start 123.7 99.6) (end 127.18168 99.6) (width 0.182) (layer "F.Cu") (net 247))
  (segment (start 122.400067 100.315766) (end 122.447623 100.299125) (width 0.182) (layer "F.Cu") (net 247))
  (segment (start 119.9 94.285) (end 120.59299 94.97799) (width 0.182) (layer "F.Cu") (net 247))
  (segment (start 123.475 99.825) (end 123.480641 99.774932) (width 0.182) (layer "F.Cu") (net 247))
  (segment (start 123.524087 99.684714) (end 123.559714 99.649087) (width 0.182) (layer "F.Cu") (net 247))
  (segment (start 123.25 100.321408) (end 123.300067 100.315766) (width 0.182) (layer "F.Cu") (net 247))
  (segment (start 123.109714 100.27232) (end 123.152376 100.299125) (width 0.182) (layer "F.Cu") (net 247))
  (segment (start 121.950067 99.605641) (end 121.997623 99.622282) (width 0.182) (layer "F.Cu") (net 247))
  (segment (start 122.702376 99.622282) (end 122.749932 99.605641) (width 0.182) (layer "F.Cu") (net 247))
  (segment (start 122.8 99.6) (end 122.850067 99.605641) (width 0.182) (layer "F.Cu") (net 247))
  (segment (start 121.1 99.6) (end 121.9 99.6) (width 0.182) (layer "F.Cu") (net 247))
  (segment (start 123.602376 99.622282) (end 123.649932 99.605641) (width 0.182) (layer "F.Cu") (net 247))
  (segment (start 122.119358 99.774932) (end 122.125 99.825) (width 0.182) (layer "F.Cu") (net 247))
  (segment (start 123.559714 99.649087) (end 123.602376 99.622282) (width 0.182) (layer "F.Cu") (net 247))
  (segment (start 122.102717 99.727376) (end 122.119358 99.774932) (width 0.182) (layer "F.Cu") (net 247))
  (segment (start 122.130641 100.146475) (end 122.147282 100.194031) (width 0.182) (layer "F.Cu") (net 247))
  (segment (start 122.490285 100.27232) (end 122.525912 100.236693) (width 0.182) (layer "F.Cu") (net 247))
  (segment (start 121.9 99.6) (end 121.950067 99.605641) (width 0.182) (layer "F.Cu") (net 247))
  (segment (start 122.125 99.825) (end 122.125 100.096408) (width 0.182) (layer "F.Cu") (net 247))
  (segment (start 122.447623 100.299125) (end 122.490285 100.27232) (width 0.182) (layer "F.Cu") (net 247))
  (segment (start 123.199932 100.315766) (end 123.25 100.321408) (width 0.182) (layer "F.Cu") (net 247))
  (segment (start 122.940285 99.649087) (end 122.975912 99.684714) (width 0.182) (layer "F.Cu") (net 247))
  (segment (start 123.649932 99.605641) (end 123.7 99.6) (width 0.182) (layer "F.Cu") (net 247))
  (segment (start 123.019358 99.774932) (end 123.025 99.825) (width 0.182) (layer "F.Cu") (net 247))
  (segment (start 123.074087 100.236693) (end 123.109714 100.27232) (width 0.182) (layer "F.Cu") (net 247))
  (via (at 133.7 102.5) (size 0.6) (drill 0.25) (layers "F.Cu" "B.Cu") (net 247))
  (segment (start 133.7 102.5) (end 134.016001 102.183999) (width 0.182) (layer "B.Cu") (net 247))
  (segment (start 134.016001 102.183999) (end 134.016001 98.733999) (width 0.182) (layer "B.Cu") (net 247))
  (segment (start 123.125 96.025) (end 123.074933 96.019358) (width 0.182) (layer "F.Cu") (net 248))
  (segment (start 123.827718 97.052376) (end 123.800913 97.009714) (width 0.182) (layer "F.Cu") (net 248))
  (segment (start 122.949088 96.559714) (end 122.984715 96.524087) (width 0.182) (layer "F.Cu") (net 248))
  (segment (start 122.905642 95.749932) (end 122.922283 95.702376) (width 0.182) (layer "F.Cu") (net 248))
  (segment (start 123.675068 95.130641) (end 123.625 95.125) (width 0.182) (layer "F.Cu") (net 248))
  (segment (start 128.654096 99.738373) (end 128.608702 99.716513) (width 0.182) (layer "F.Cu") (net 248))
  (segment (start 129.614315 99.474886) (end 129.603104 99.425765) (width 0.182) (layer "F.Cu") (net 248))
  (segment (start 130.186225 99.977375) (end 130.146833 99.945961) (width 0.182) (layer "F.Cu") (net 248))
  (segment (start 129.549829 99.340979) (end 129.510437 99.309565) (width 0.182) (layer "F.Cu") (net 248))
  (segment (start 123.722624 97.352717) (end 123.765286 97.325912) (width 0.182) (layer "F.Cu") (net 248))
  (segment (start 122.949088 95.659714) (end 122.984715 95.624087) (width 0.182) (layer "F.Cu") (net 248))
  (segment (start 123.844359 95.400067) (end 123.85 95.35) (width 0.182) (layer "F.Cu") (net 248))
  (segment (start 123.827718 95.252376) (end 123.800913 95.209714) (width 0.182) (layer "F.Cu") (net 248))
  (segment (start 129.581243 99.380371) (end 129.549829 99.340979) (width 0.182) (layer "F.Cu") (net 248))
  (segment (start 129.842104 100.957894) (end 129.81069 100.918502) (width 0.182) (layer "F.Cu") (net 248))
  (segment (start 129.81069 100.679087) (end 129.842104 100.639695) (width 0.182) (layer "F.Cu") (net 248))
  (segment (start 130.186225 100.295573) (end 130.217639 100.256181) (width 0.182) (layer "F.Cu") (net 248))
  (segment (start 129.842104 100.639695) (end 130.186225 100.295573) (width 0.182) (layer "F.Cu") (net 248))
  (segment (start 129.365537 99.276492) (end 129.316417 99.287704) (width 0.182) (layer "F.Cu") (net 248))
  (segment (start 122.905642 96.750067) (end 122.9 96.7) (width 0.182) (layer "F.Cu") (net 248))
  (segment (start 129.174294 100.042691) (end 129.205708 100.003299) (width 0.182) (layer "F.Cu") (net 248))
  (segment (start 129.339613 100.385981) (end 129.290492 100.374769) (width 0.182) (layer "F.Cu") (net 248))
  (segment (start 129.952813 99.9241) (end 129.907418 99.945961) (width 0.182) (layer "F.Cu") (net 248))
  (segment (start 122.922283 95.897623) (end 122.905642 95.850067) (width 0.182) (layer "F.Cu") (net 248))
  (segment (start 122.9 95.8) (end 122.905642 95.749932) (width 0.182) (layer "F.Cu") (net 248))
  (segment (start 123.125 97.375) (end 123.625 97.375) (width 0.182) (layer "F.Cu") (net 248))
  (segment (start 129.389997 100.385981) (end 129.339613 100.385981) (width 0.182) (layer "F.Cu") (net 248))
  (segment (start 123.827718 97.247623) (end 123.844359 97.200067) (width 0.182) (layer "F.Cu") (net 248))
  (segment (start 130.217639 100.016767) (end 130.186225 99.977375) (width 0.182) (layer "F.Cu") (net 248))
  (segment (start 122.922283 96.602376) (end 122.949088 96.559714) (width 0.182) (layer "F.Cu") (net 248))
  (segment (start 129.614315 99.52527) (end 129.614315 99.474886) (width 0.182) (layer "F.Cu") (net 248))
  (segment (start 128.887508 99.685099) (end 128.848116 99.716513) (width 0.182) (layer "F.Cu") (net 248))
  (segment (start 129.316417 99.287704) (end 129.271022 99.309565) (width 0.182) (layer "F.Cu") (net 248))
  (segment (start 131.391009 101.308991) (end 130.1932 101.308991) (width 0.182) (layer "F.Cu") (net 248))
  (segment (start 129.152433 100.088086) (end 129.174294 100.042691) (width 0.182) (layer "F.Cu") (net 248))
  (segment (start 129.777617 100.823986) (end 129.777617 100.773602) (width 0.182) (layer "F.Cu") (net 248))
  (segment (start 129.174294 100.282106) (end 129.152433 100.236711) (width 0.182) (layer "F.Cu") (net 248))
  (segment (start 123.027377 96.497282) (end 123.074933 96.480641) (width 0.182) (layer "F.Cu") (net 248))
  (segment (start 123.800913 95.209714) (end 123.765286 95.174087) (width 0.182) (layer "F.Cu") (net 248))
  (segment (start 123.722624 96.947282) (end 123.675068 96.930641) (width 0.182) (layer "F.Cu") (net 248))
  (segment (start 123.844359 97.099932) (end 123.827718 97.052376) (width 0.182) (layer "F.Cu") (net 248))
  (segment (start 129.510437 99.309565) (end 129.465042 99.287704) (width 0.182) (layer "F.Cu") (net 248))
  (segment (start 129.245098 100.352909) (end 129.205708 100.321498) (width 0.182) (layer "F.Cu") (net 248))
  (segment (start 130.2395 100.062161) (end 130.217639 100.016767) (width 0.182) (layer "F.Cu") (net 248))
  (segment (start 122.905642 97.549932) (end 122.922283 97.502376) (width 0.182) (layer "F.Cu") (net 248))
  (segment (start 129.523904 100.321495) (end 129.484512 100.352909) (width 0.182) (layer "F.Cu") (net 248))
  (segment (start 123.125 95.125) (end 123.074933 95.119358) (width 0.182) (layer "F.Cu") (net 248))
  (segment (start 123.765286 95.174087) (end 123.722624 95.147282) (width 0.182) (layer "F.Cu") (net 248))
  (segment (start 123.800913 97.290285) (end 123.827718 97.247623) (width 0.182) (layer "F.Cu") (net 248))
  (segment (start 129.205708 100.003299) (end 129.549829 99.659177) (width 0.182) (layer "F.Cu") (net 248))
  (segment (start 129.603104 99.574391) (end 129.614315 99.52527) (width 0.182) (layer "F.Cu") (net 248))
  (segment (start 128.753601 99.749585) (end 128.703217 99.749585) (width 0.182) (layer "F.Cu") (net 248))
  (segment (start 123.625 97.375) (end 123.675068 97.369358) (width 0.182) (layer "F.Cu") (net 248))
  (segment (start 123.800913 97.009714) (end 123.765286 96.974087) (width 0.182) (layer "F.Cu") (net 248))
  (segment (start 123.800913 96.390285) (end 123.827718 96.347623) (width 0.182) (layer "F.Cu") (net 248))
  (segment (start 130.101438 99.9241) (end 130.052317 99.912888) (width 0.182) (layer "F.Cu") (net 248))
  (segment (start 122.922283 95.702376) (end 122.949088 95.659714) (width 0.182) (layer "F.Cu") (net 248))
  (segment (start 130.2395 100.210787) (end 130.250711 100.161666) (width 0.182) (layer "F.Cu") (net 248))
  (segment (start 122.922283 96.797623) (end 122.905642 96.750067) (width 0.182) (layer "F.Cu") (net 248))
  (segment (start 122.984715 95.624087) (end 123.027377 95.597282) (width 0.182) (layer "F.Cu") (net 248))
  (segment (start 123.844359 97.200067) (end 123.85 97.15) (width 0.182) (layer "F.Cu") (net 248))
  (segment (start 123.827718 95.447623) (end 123.844359 95.400067) (width 0.182) (layer "F.Cu") (net 248))
  (segment (start 129.141221 100.137206) (end 129.152433 100.088086) (width 0.182) (layer "F.Cu") (net 248))
  (segment (start 123.625 95.575) (end 123.675068 95.569358) (width 0.182) (layer "F.Cu") (net 248))
  (segment (start 123.625 96.925) (end 123.125 96.925) (width 0.182) (layer "F.Cu") (net 248))
  (segment (start 128.848116 99.716513) (end 128.802722 99.738373) (width 0.182) (layer "F.Cu") (net 248))
  (segment (start 129.81069 100.918502) (end 129.788829 100.873107) (width 0.182) (layer "F.Cu") (net 248))
  (segment (start 129.205708 100.321498) (end 129.174294 100.282106) (width 0.182) (layer "F.Cu") (net 248))
  (segment (start 122.984715 95.975912) (end 122.949088 95.940285) (width 0.182) (layer "F.Cu") (net 248))
  (segment (start 123.765286 96.425912) (end 123.800913 96.390285) (width 0.182) (layer "F.Cu") (net 248))
  (segment (start 123.722624 96.047282) (end 123.675068 96.030641) (width 0.182) (layer "F.Cu") (net 248))
  (segment (start 122.922283 94.997623) (end 122.905642 94.950067) (width 0.182) (layer "F.Cu") (net 248))
  (segment (start 123.722624 95.552717) (end 123.765286 95.525912) (width 0.182) (layer "F.Cu") (net 248))
  (segment (start 123.125 96.475) (end 123.625 96.475) (width 0.182) (layer "F.Cu") (net 248))
  (segment (start 122.9 98.3) (end 122.9 97.6) (width 0.182) (layer "F.Cu") (net 248))
  (segment (start 123.675068 95.569358) (end 123.722624 95.552717) (width 0.182) (layer "F.Cu") (net 248))
  (segment (start 123.85 97.15) (end 123.844359 97.099932) (width 0.182) (layer "F.Cu") (net 248))
  (segment (start 129.549829 99.659177) (end 129.581243 99.619785) (width 0.182) (layer "F.Cu") (net 248))
  (segment (start 122.905642 94.950067) (end 122.9 94.9) (width 0.182) (layer "F.Cu") (net 248))
  (segment (start 123.844359 95.299932) (end 123.827718 95.252376) (width 0.182) (layer "F.Cu") (net 248))
  (segment (start 123.765286 96.974087) (end 123.722624 96.947282) (width 0.182) (layer "F.Cu") (net 248))
  (segment (start 130.146833 99.945961) (end 130.101438 99.9241) (width 0.182) (layer "F.Cu") (net 248))
  (segment (start 123.675068 97.369358) (end 123.722624 97.352717) (width 0.182) (layer "F.Cu") (net 248))
  (segment (start 123.125 96.925) (end 123.074933 96.919358) (width 0.182) (layer "F.Cu") (net 248))
  (segment (start 127.563181 98.67897) (end 123.27897 98.67897) (width 0.182) (layer "F.Cu") (net 248))
  (segment (start 123.675068 96.930641) (end 123.625 96.925) (width 0.182) (layer "F.Cu") (net 248))
  (segment (start 123.765286 97.325912) (end 123.800913 97.290285) (width 0.182) (layer "F.Cu") (net 248))
  (segment (start 123.675068 96.469358) (end 123.722624 96.452717) (width 0.182) (layer "F.Cu") (net 248))
  (segment (start 123.827718 96.347623) (end 123.844359 96.300067) (width 0.182) (layer "F.Cu") (net 248))
  (segment (start 129.271022 99.309565) (end 129.23163 99.340978) (width 0.182) (layer "F.Cu") (net 248))
  (segment (start 123.765286 95.525912) (end 123.800913 95.490285) (width 0.182) (layer "F.Cu") (net 248))
  (segment (start 131.6 101.1) (end 131.391009 101.308991) (width 0.182) (layer "F.Cu") (net 248))
  (segment (start 123.844359 96.199932) (end 123.827718 96.152376) (width 0.182) (layer "F.Cu") (net 248))
  (segment (start 123.125 95.575) (end 123.625 95.575) (width 0.182) (layer "F.Cu") (net 248))
  (segment (start 129.23163 99.340978) (end 128.887508 99.685099) (width 0.182) (layer "F.Cu") (net 248))
  (segment (start 130.052317 99.912888) (end 130.001933 99.912888) (width 0.182) (layer "F.Cu") (net 248))
  (segment (start 129.415921 99.276492) (end 129.365537 99.276492) (width 0.182) (layer "F.Cu") (net 248))
  (segment (start 122.984715 97.424087) (end 123.027377 97.397282) (width 0.182) (layer "F.Cu") (net 248))
  (segment (start 123.027377 95.102717) (end 122.984715 95.075912) (width 0.182) (layer "F.Cu") (net 248))
  (segment (start 122.984715 95.075912) (end 122.949088 95.040285) (width 0.182) (layer "F.Cu") (net 248))
  (segment (start 130.217639 100.256181) (end 130.2395 100.210787) (width 0.182) (layer "F.Cu") (net 248))
  (segment (start 122.9 97.6) (end 122.905642 97.549932) (width 0.182) (layer "F.Cu") (net 248))
  (segment (start 129.484512 100.352909) (end 129.439118 100.374769) (width 0.182) (layer "F.Cu") (net 248))
  (segment (start 129.465042 99.287704) (end 129.415921 99.276492) (width 0.182) (layer "F.Cu") (net 248))
  (segment (start 129.777617 100.773602) (end 129.788829 100.724482) (width 0.182) (layer "F.Cu") (net 248))
  (segment (start 122.949088 95.040285) (end 122.922283 94.997623) (width 0.182) (layer "F.Cu") (net 248))
  (segment (start 128.608702 99.716513) (end 128.569312 99.685101) (width 0.182) (layer "F.Cu") (net 248))
  (segment (start 123.074933 97.380641) (end 123.125 97.375) (width 0.182) (layer "F.Cu") (net 248))
  (segment (start 123.800913 95.490285) (end 123.827718 95.447623) (width 0.182) (layer "F.Cu") (net 248))
  (segment (start 129.152433 100.236711) (end 129.141221 100.18759) (width 0.182) (layer "F.Cu") (net 248))
  (segment (start 122.949088 96.840285) (end 122.922283 96.797623) (width 0.182) (layer "F.Cu") (net 248))
  (segment (start 123.027377 95.597282) (end 123.074933 95.580641) (width 0.182) (layer "F.Cu") (net 248))
  (segment (start 122.984715 96.875912) (end 122.949088 96.840285) (width 0.182) (layer "F.Cu") (net 248))
  (segment (start 129.439118 100.374769) (end 129.389997 100.385981) (width 0.182) (layer "F.Cu") (net 248))
  (segment (start 123.827718 96.152376) (end 123.800913 96.109714) (width 0.182) (layer "F.Cu") (net 248))
  (segment (start 123.722624 95.147282) (end 123.675068 95.130641) (width 0.182) (layer "F.Cu") (net 248))
  (segment (start 122.984715 96.524087) (end 123.027377 96.497282) (width 0.182) (layer "F.Cu") (net 248))
  (segment (start 123.074933 95.119358) (end 123.027377 95.102717) (width 0.182) (layer "F.Cu") (net 248))
  (segment (start 129.581243 99.619785) (end 129.603104 99.574391) (width 0.182) (layer "F.Cu") (net 248))
  (segment (start 128.703217 99.749585) (end 128.654096 99.738373) (width 0.182) (layer "F.Cu") (net 248))
  (segment (start 130.250711 100.111282) (end 130.2395 100.062161) (width 0.182) (layer "F.Cu") (net 248))
  (segment (start 123.844359 96.300067) (end 123.85 96.25) (width 0.182) (layer "F.Cu") (net 248))
  (segment (start 123.625 95.125) (end 123.125 95.125) (width 0.182) (layer "F.Cu") (net 248))
  (segment (start 129.141221 100.18759) (end 129.141221 100.137206) (width 0.182) (layer "F.Cu") (net 248))
  (segment (start 123.722624 96.452717) (end 123.765286 96.425912) (width 0.182) (layer "F.Cu") (net 248))
  (segment (start 128.802722 99.738373) (end 128.753601 99.749585) (width 0.182) (layer "F.Cu") (net 248))
  (segment (start 129.788829 100.873107) (end 129.777617 100.823986) (width 0.182) (layer "F.Cu") (net 248))
  (segment (start 130.1932 101.308991) (end 129.842104 100.957894) (width 0.182) (layer "F.Cu") (net 248))
  (segment (start 128.569312 99.685101) (end 127.563181 98.67897) (width 0.182) (layer "F.Cu") (net 248))
  (segment (start 129.290492 100.374769) (end 129.245098 100.352909) (width 0.182) (layer "F.Cu") (net 248))
  (segment (start 123.027377 96.902717) (end 122.984715 96.875912) (width 0.182) (layer "F.Cu") (net 248))
  (segment (start 123.85 96.25) (end 123.844359 96.199932) (width 0.182) (layer "F.Cu") (net 248))
  (segment (start 122.905642 95.850067) (end 122.9 95.8) (width 0.182) (layer "F.Cu") (net 248))
  (segment (start 123.800913 96.109714) (end 123.765286 96.074087) (width 0.182) (layer "F.Cu") (net 248))
  (segment (start 123.027377 97.397282) (end 123.074933 97.380641) (width 0.182) (layer "F.Cu") (net 248))
  (segment (start 123.074933 96.919358) (end 123.027377 96.902717) (width 0.182) (layer "F.Cu") (net 248))
  (segment (start 130.001933 99.912888) (end 129.952813 99.9241) (width 0.182) (layer "F.Cu") (net 248))
  (segment (start 122.905642 96.649932) (end 122.922283 96.602376) (width 0.182) (layer "F.Cu") (net 248))
  (segment (start 123.675068 96.030641) (end 123.625 96.025) (width 0.182) (layer "F.Cu") (net 248))
  (segment (start 123.625 96.475) (end 123.675068 96.469358) (width 0.182) (layer "F.Cu") (net 248))
  (segment (start 123.027377 96.002717) (end 122.984715 95.975912) (width 0.182) (layer "F.Cu") (net 248))
  (segment (start 123.074933 95.580641) (end 123.125 95.575) (width 0.182) (layer "F.Cu") (net 248))
  (segment (start 130.250711 100.161666) (end 130.250711 100.111282) (width 0.182) (layer "F.Cu") (net 248))
  (segment (start 122.9 96.7) (end 122.905642 96.649932) (width 0.182) (layer "F.Cu") (net 248))
  (segment (start 123.074933 96.480641) (end 123.125 96.475) (width 0.182) (layer "F.Cu") (net 248))
  (segment (start 123.074933 96.019358) (end 123.027377 96.002717) (width 0.182) (layer "F.Cu") (net 248))
  (segment (start 129.868026 99.977374) (end 129.523904 100.321495) (width 0.182) (layer "F.Cu") (net 248))
  (segment (start 129.603104 99.425765) (end 129.581243 99.380371) (width 0.182) (layer "F.Cu") (net 248))
  (segment (start 123.765286 96.074087) (end 123.722624 96.047282) (width 0.182) (layer "F.Cu") (net 248))
  (segment (start 122.949088 97.459714) (end 122.984715 97.424087) (width 0.182) (layer "F.Cu") (net 248))
  (segment (start 129.907418 99.945961) (end 129.868026 99.977374) (width 0.182) (layer "F.Cu") (net 248))
  (segment (start 129.788829 100.724482) (end 129.81069 100.679087) (width 0.182) (layer "F.Cu") (net 248))
  (segment (start 122.9 94.9) (end 122.9 94.285) (width 0.182) (layer "F.Cu") (net 248))
  (segment (start 122.922283 97.502376) (end 122.949088 97.459714) (width 0.182) (layer "F.Cu") (net 248))
  (segment (start 122.949088 95.940285) (end 122.922283 95.897623) (width 0.182) (layer "F.Cu") (net 248))
  (segment (start 123.85 95.35) (end 123.844359 95.299932) (width 0.182) (layer "F.Cu") (net 248))
  (segment (start 123.625 96.025) (end 123.125 96.025) (width 0.182) (layer "F.Cu") (net 248))
  (segment (start 123.27897 98.67897) (end 122.9 98.3) (width 0.182) (layer "F.Cu") (net 248))
  (via (at 131.6 101.1) (size 0.6) (drill 0.25) (layers "F.Cu" "B.Cu") (net 248))
  (segment (start 132.1 101.6) (end 132.329319 101.6) (width 0.182) (layer "B.Cu") (net 248))
  (segment (start 132.5 101.429319) (end 132.5 99.85) (width 0.182) (layer "B.Cu") (net 248))
  (segment (start 132.329319 101.6) (end 132.5 101.429319) (width 0.182) (layer "B.Cu") (net 248))
  (segment (start 131.6 101.1) (end 132.1 101.6) (width 0.182) (layer "B.Cu") (net 248))
  (segment (start 132.5 99.85) (end 131.825 99.175) (width 0.182) (layer "B.Cu") (net 248))
  (segment (start 121.017187 96.469499) (end 120.977938 96.49416) (width 0.182) (layer "F.Cu") (net 249))
  (segment (start 121.017187 95.641499) (end 120.977938 95.66616) (width 0.182) (layer "F.Cu") (net 249))
  (segment (start 120.9205 95.917813) (end 120.945161 95.957062) (width 0.182) (layer "F.Cu") (net 249))
  (segment (start 121.662255 95.367938) (end 121.667444 95.414) (width 0.182) (layer "F.Cu") (net 249))
  (segment (start 120.977938 97.32216) (end 120.945161 97.354937) (width 0.182) (layer "F.Cu") (net 249))
  (segment (start 121.646945 96.152186) (end 121.662255 96.195938) (width 0.182) (layer "F.Cu") (net 249))
  (segment (start 120.977938 96.49416) (end 120.945161 96.526937) (width 0.182) (layer "F.Cu") (net 249))
  (segment (start 121.060939 96.85781) (end 121.107 96.863) (width 0.182) (layer "F.Cu") (net 249))
  (segment (start 121.506506 98.09981) (end 121.460444 98.105) (width 0.182) (layer "F.Cu") (net 249))
  (segment (start 121.646945 96.980186) (end 121.662255 97.023938) (width 0.182) (layer "F.Cu") (net 249))
  (segment (start 121.017187 96.0145) (end 121.060939 96.02981) (width 0.182) (layer "F.Cu") (net 249))
  (segment (start 121.662255 97.851938) (end 121.667444 97.898) (width 0.182) (layer "F.Cu") (net 249))
  (segment (start 120.9 97.484) (end 120.90519 97.530061) (width 0.182) (layer "F.Cu") (net 249))
  (segment (start 120.945161 95.698937) (end 120.9205 95.738186) (width 0.182) (layer "F.Cu") (net 249))
  (segment (start 120.977938 95.161839) (end 121.017187 95.1865) (width 0.182) (layer "F.Cu") (net 249))
  (segment (start 120.9 95) (end 120.90519 95.046061) (width 0.182) (layer "F.Cu") (net 249))
  (segment (start 120.945161 96.785062) (end 120.977938 96.817839) (width 0.182) (layer "F.Cu") (net 249))
  (segment (start 121.667444 96.242) (end 121.662255 96.288061) (width 0.182) (layer "F.Cu") (net 249))
  (segment (start 121.107 95.621) (end 121.060939 95.626189) (width 0.182) (layer "F.Cu") (net 249))
  (segment (start 121.460444 96.449) (end 121.107 96.449) (width 0.182) (layer "F.Cu") (net 249))
  (segment (start 121.662255 95.460061) (end 121.646945 95.503813) (width 0.182) (layer "F.Cu") (net 249))
  (segment (start 121.460444 95.207) (end 121.506506 95.212189) (width 0.182) (layer "F.Cu") (net 249))
  (segment (start 120.90519 95.874061) (end 120.9205 95.917813) (width 0.182) (layer "F.Cu") (net 249))
  (segment (start 121.646945 95.503813) (end 121.622284 95.543062) (width 0.182) (layer "F.Cu") (net 249))
  (segment (start 120.9 94.285) (end 120.9 95) (width 0.182) (layer "F.Cu") (net 249))
  (segment (start 121.060939 97.282189) (end 121.017187 97.297499) (width 0.182) (layer "F.Cu") (net 249))
  (segment (start 120.977938 95.66616) (end 120.945161 95.698937) (width 0.182) (layer "F.Cu") (net 249))
  (segment (start 121.460444 97.691) (end 121.506506 97.696189) (width 0.182) (layer "F.Cu") (net 249))
  (segment (start 121.589507 97.231839) (end 121.550258 97.2565) (width 0.182) (layer "F.Cu") (net 249))
  (segment (start 121.622284 97.768937) (end 121.646945 97.808186) (width 0.182) (layer "F.Cu") (net 249))
  (segment (start 121.550258 95.6005) (end 121.506506 95.61581) (width 0.182) (layer "F.Cu") (net 249))
  (segment (start 120.9 98.312) (end 120.9 98.8) (width 0.182) (layer "F.Cu") (net 249))
  (segment (start 121.589507 95.575839) (end 121.550258 95.6005) (width 0.182) (layer "F.Cu") (net 249))
  (segment (start 121.667444 97.07) (end 121.662255 97.116061) (width 0.182) (layer "F.Cu") (net 249))
  (segment (start 121.460444 98.105) (end 121.107 98.105) (width 0.182) (layer "F.Cu") (net 249))
  (segment (start 120.90519 97.437938) (end 120.9 97.484) (width 0.182) (layer "F.Cu") (net 249))
  (segment (start 121.107 97.691) (end 121.460444 97.691) (width 0.182) (layer "F.Cu") (net 249))
  (segment (start 120.9205 96.566186) (end 120.90519 96.609938) (width 0.182) (layer "F.Cu") (net 249))
  (segment (start 120.9205 95.089813) (end 120.945161 95.129062) (width 0.182) (layer "F.Cu") (net 249))
  (segment (start 120.945161 95.957062) (end 120.977938 95.989839) (width 0.182) (layer "F.Cu") (net 249))
  (segment (start 121.460444 96.035) (end 121.506506 96.040189) (width 0.182) (layer "F.Cu") (net 249))
  (segment (start 121.550258 97.2565) (end 121.506506 97.27181) (width 0.182) (layer "F.Cu") (net 249))
  (segment (start 121.017187 95.1865) (end 121.060939 95.20181) (width 0.182) (layer "F.Cu") (net 249))
  (segment (start 121.107 95.207) (end 121.460444 95.207) (width 0.182) (layer "F.Cu") (net 249))
  (segment (start 121.622284 96.112937) (end 121.646945 96.152186) (width 0.182) (layer "F.Cu") (net 249))
  (segment (start 132.76999 101.923011) (end 132.791092 101.901909) (width 0.182) (layer "F.Cu") (net 249))
  (segment (start 120.90519 95.046061) (end 120.9205 95.089813) (width 0.182) (layer "F.Cu") (net 249))
  (segment (start 121.017187 96.8425) (end 121.060939 96.85781) (width 0.182) (layer "F.Cu") (net 249))
  (segment (start 121.107 96.035) (end 121.460444 96.035) (width 0.182) (layer "F.Cu") (net 249))
  (segment (start 121.060939 96.02981) (end 121.107 96.035) (width 0.182) (layer "F.Cu") (net 249))
  (segment (start 121.060939 96.454189) (end 121.017187 96.469499) (width 0.182) (layer "F.Cu") (net 249))
  (segment (start 120.9205 95.738186) (end 120.90519 95.781938) (width 0.182) (layer "F.Cu") (net 249))
  (segment (start 120.9 98.8) (end 121.39299 99.29299) (width 0.182) (layer "F.Cu") (net 249))
  (segment (start 129.938867 101.923011) (end 132.76999 101.923011) (width 0.182) (layer "F.Cu") (net 249))
  (segment (start 121.589507 96.90816) (end 121.622284 96.940937) (width 0.182) (layer "F.Cu") (net 249))
  (segment (start 121.589507 96.08016) (end 121.622284 96.112937) (width 0.182) (layer "F.Cu") (net 249))
  (segment (start 121.622284 95.284937) (end 121.646945 95.324186) (width 0.182) (layer "F.Cu") (net 249))
  (segment (start 120.9205 98.222186) (end 120.90519 98.265938) (width 0.182) (layer "F.Cu") (net 249))
  (segment (start 121.589507 97.73616) (end 121.622284 97.768937) (width 0.182) (layer "F.Cu") (net 249))
  (segment (start 120.9 95.828) (end 120.90519 95.874061) (width 0.182) (layer "F.Cu") (net 249))
  (segment (start 120.90519 96.609938) (end 120.9 96.656) (width 0.182) (layer "F.Cu") (net 249))
  (segment (start 120.945161 95.129062) (end 120.977938 95.161839) (width 0.182) (layer "F.Cu") (net 249))
  (segment (start 121.550258 98.0845) (end 121.506506 98.09981) (width 0.182) (layer "F.Cu") (net 249))
  (segment (start 120.945161 96.526937) (end 120.9205 96.566186) (width 0.182) (layer "F.Cu") (net 249))
  (segment (start 121.060939 95.626189) (end 121.017187 95.641499) (width 0.182) (layer "F.Cu") (net 249))
  (segment (start 121.107 96.449) (end 121.060939 96.454189) (width 0.182) (layer "F.Cu") (net 249))
  (segment (start 120.90519 95.781938) (end 120.9 95.828) (width 0.182) (layer "F.Cu") (net 249))
  (segment (start 121.662255 97.116061) (end 121.646945 97.159813) (width 0.182) (layer "F.Cu") (net 249))
  (segment (start 121.662255 97.023938) (end 121.667444 97.07) (width 0.182) (layer "F.Cu") (net 249))
  (segment (start 121.506506 96.44381) (end 121.460444 96.449) (width 0.182) (layer "F.Cu") (net 249))
  (segment (start 121.460444 97.277) (end 121.107 97.277) (width 0.182) (layer "F.Cu") (net 249))
  (segment (start 121.622284 97.199062) (end 121.589507 97.231839) (width 0.182) (layer "F.Cu") (net 249))
  (segment (start 120.90519 98.265938) (end 120.9 98.312) (width 0.182) (layer "F.Cu") (net 249))
  (segment (start 121.506506 96.868189) (end 121.550258 96.883499) (width 0.182) (layer "F.Cu") (net 249))
  (segment (start 121.646945 97.987813) (end 121.622284 98.027062) (width 0.182) (layer "F.Cu") (net 249))
  (segment (start 120.9205 96.745813) (end 120.945161 96.785062) (width 0.182) (layer "F.Cu") (net 249))
  (segment (start 121.017187 98.125499) (end 120.977938 98.15016) (width 0.182) (layer "F.Cu") (net 249))
  (segment (start 121.646945 97.159813) (end 121.622284 97.199062) (width 0.182) (layer "F.Cu") (net 249))
  (segment (start 121.589507 96.403839) (end 121.550258 96.4285) (width 0.182) (layer "F.Cu") (net 249))
  (segment (start 121.622284 96.371062) (end 121.589507 96.403839) (width 0.182) (layer "F.Cu") (net 249))
  (segment (start 121.662255 96.195938) (end 121.667444 96.242) (width 0.182) (layer "F.Cu") (net 249))
  (segment (start 120.977938 98.15016) (end 120.945161 98.182937) (width 0.182) (layer "F.Cu") (net 249))
  (segment (start 121.107 97.277) (end 121.060939 97.282189) (width 0.182) (layer "F.Cu") (net 249))
  (segment (start 121.589507 95.25216) (end 121.622284 95.284937) (width 0.182) (layer "F.Cu") (net 249))
  (segment (start 121.506506 95.61581) (end 121.460444 95.621) (width 0.182) (layer "F.Cu") (net 249))
  (segment (start 121.506506 96.040189) (end 121.550258 96.055499) (width 0.182) (layer "F.Cu") (net 249))
  (segment (start 121.646945 95.324186) (end 121.662255 95.367938) (width 0.182) (layer "F.Cu") (net 249))
  (segment (start 121.060939 98.110189) (end 121.017187 98.125499) (width 0.182) (layer "F.Cu") (net 249))
  (segment (start 121.646945 97.808186) (end 121.662255 97.851938) (width 0.182) (layer "F.Cu") (net 249))
  (segment (start 121.550258 97.711499) (end 121.589507 97.73616) (width 0.182) (layer "F.Cu") (net 249))
  (segment (start 120.977938 96.817839) (end 121.017187 96.8425) (width 0.182) (layer "F.Cu") (net 249))
  (segment (start 120.9 96.656) (end 120.90519 96.702061) (width 0.182) (layer "F.Cu") (net 249))
  (segment (start 121.506506 97.27181) (end 121.460444 97.277) (width 0.182) (layer "F.Cu") (net 249))
  (segment (start 121.107 98.105) (end 121.060939 98.110189) (width 0.182) (layer "F.Cu") (net 249))
  (segment (start 121.550258 96.055499) (end 121.589507 96.08016) (width 0.182) (layer "F.Cu") (net 249))
  (segment (start 121.667444 97.898) (end 121.662255 97.944061) (width 0.182) (layer "F.Cu") (net 249))
  (segment (start 121.550258 95.227499) (end 121.589507 95.25216) (width 0.182) (layer "F.Cu") (net 249))
  (segment (start 121.107 96.863) (end 121.460444 96.863) (width 0.182) (layer "F.Cu") (net 249))
  (segment (start 121.622284 96.940937) (end 121.646945 96.980186) (width 0.182) (layer "F.Cu") (net 249))
  (segment (start 121.060939 95.20181) (end 121.107 95.207) (width 0.182) (layer "F.Cu") (net 249))
  (segment (start 120.977938 95.989839) (end 121.017187 96.0145) (width 0.182) (layer "F.Cu") (net 249))
  (segment (start 120.945161 97.613062) (end 120.977938 97.645839) (width 0.182) (layer "F.Cu") (net 249))
  (segment (start 121.622284 95.543062) (end 121.589507 95.575839) (width 0.182) (layer "F.Cu") (net 249))
  (segment (start 121.060939 97.68581) (end 121.107 97.691) (width 0.182) (layer "F.Cu") (net 249))
  (segment (start 121.017187 97.6705) (end 121.060939 97.68581) (width 0.182) (layer "F.Cu") (net 249))
  (segment (start 120.9205 97.573813) (end 120.945161 97.613062) (width 0.182) (layer "F.Cu") (net 249))
  (segment (start 121.460444 96.863) (end 121.506506 96.868189) (width 0.182) (layer "F.Cu") (net 249))
  (segment (start 121.460444 95.621) (end 121.107 95.621) (width 0.182) (layer "F.Cu") (net 249))
  (segment (start 121.017187 97.297499) (end 120.977938 97.32216) (width 0.182) (layer "F.Cu") (net 249))
  (segment (start 121.667444 95.414) (end 121.662255 95.460061) (width 0.182) (layer "F.Cu") (net 249))
  (segment (start 121.646945 96.331813) (end 121.622284 96.371062) (width 0.182) (layer "F.Cu") (net 249))
  (segment (start 127.308847 99.29299) (end 129.938867 101.923011) (width 0.182) (layer "F.Cu") (net 249))
  (segment (start 121.506506 97.696189) (end 121.550258 97.711499) (width 0.182) (layer "F.Cu") (net 249))
  (segment (start 121.506506 95.212189) (end 121.550258 95.227499) (width 0.182) (layer "F.Cu") (net 249))
  (segment (start 121.550258 96.4285) (end 121.506506 96.44381) (width 0.182) (layer "F.Cu") (net 249))
  (segment (start 121.550258 96.883499) (end 121.589507 96.90816) (width 0.182) (layer "F.Cu") (net 249))
  (segment (start 121.662255 97.944061) (end 121.646945 97.987813) (width 0.182) (layer "F.Cu") (net 249))
  (segment (start 120.9205 97.394186) (end 120.90519 97.437938) (width 0.182) (layer "F.Cu") (net 249))
  (segment (start 120.90519 97.530061) (end 120.9205 97.573813) (width 0.182) (layer "F.Cu") (net 249))
  (segment (start 120.90519 96.702061) (end 120.9205 96.745813) (width 0.182) (layer "F.Cu") (net 249))
  (segment (start 121.622284 98.027062) (end 121.589507 98.059839) (width 0.182) (layer "F.Cu") (net 249))
  (segment (start 120.977938 97.645839) (end 121.017187 97.6705) (width 0.182) (layer "F.Cu") (net 249))
  (segment (start 121.39299 99.29299) (end 127.308847 99.29299) (width 0.182) (layer "F.Cu") (net 249))
  (segment (start 121.662255 96.288061) (end 121.646945 96.331813) (width 0.182) (layer "F.Cu") (net 249))
  (segment (start 120.945161 98.182937) (end 120.9205 98.222186) (width 0.182) (layer "F.Cu") (net 249))
  (segment (start 121.589507 98.059839) (end 121.550258 98.0845) (width 0.182) (layer "F.Cu") (net 249))
  (segment (start 120.945161 97.354937) (end 120.9205 97.394186) (width 0.182) (layer "F.Cu") (net 249))
  (via (at 132.791092 101.901909) (size 0.6) (drill 0.25) (layers "F.Cu" "B.Cu") (net 249))
  (segment (start 132.791092 101.808908) (end 133 101.6) (width 0.182) (layer "B.Cu") (net 249))
  (segment (start 132.791092 101.901909) (end 132.791092 101.808908) (width 0.182) (layer "B.Cu") (net 249))
  (segment (start 133 101.6) (end 133 98.8) (width 0.182) (layer "B.Cu") (net 249))
  (segment (start 123.6 102.8) (end 123 103.4) (width 0.182) (layer "B.Cu") (net 250))
  (segment (start 129 101.707) (end 129 102.4) (width 0.182) (layer "B.Cu") (net 250))
  (segment (start 128.85 101.557) (end 129 101.707) (width 0.182) (layer "B.Cu") (net 250))
  (segment (start 120.3 103.4) (end 119.9 103) (width 0.182) (layer "B.Cu") (net 250))
  (segment (start 128.6 102.8) (end 123.6 102.8) (width 0.182) (layer "B.Cu") (net 250))
  (segment (start 129 102.4) (end 128.6 102.8) (width 0.182) (layer "B.Cu") (net 250))
  (segment (start 128.85 99.94) (end 128.85 101.557) (width 0.182) (layer "B.Cu") (net 250))
  (segment (start 119.9 103) (end 119.9 94.285) (width 0.182) (layer "B.Cu") (net 250))
  (segment (start 129.625 99.165) (end 128.85 99.94) (width 0.182) (layer "B.Cu") (net 250))
  (segment (start 123 103.4) (end 120.3 103.4) (width 0.182) (layer "B.Cu") (net 250))
  (segment (start 122.575222 96.17) (end 123.224778 96.17) (width 0.182) (layer "B.Cu") (net 251))
  (segment (start 122.496256 97.607976) (end 122.534724 97.621436) (width 0.182) (layer "B.Cu") (net 251))
  (segment (start 122.918023 95.338966) (end 122.939706 95.373475) (width 0.182) (layer "B.Cu") (net 251))
  (segment (start 123.082 98.718) (end 123.041501 98.722563) (width 0.182) (layer "B.Cu") (net 251))
  (segment (start 123.303744 95.460023) (end 123.338253 95.481706) (width 0.182) (layer "B.Cu") (net 251))
  (segment (start 123.224778 98.718) (end 123.082 98.718) (width 0.182) (layer "B.Cu") (net 251))
  (segment (start 122.968524 98.757706) (end 122.939706 98.786524) (width 0.182) (layer "B.Cu") (net 251))
  (segment (start 122.534724 97.621436) (end 122.575222 97.626) (width 0.182) (layer "B.Cu") (net 251))
  (segment (start 123.388754 97.729033) (end 123.402214 97.767501) (width 0.182) (layer "B.Cu") (net 251))
  (segment (start 123.367071 97.193475) (end 123.338253 97.222293) (width 0.182) (layer "B.Cu") (net 251))
  (segment (start 122.575222 98.354) (end 123.224778 98.354) (width 0.182) (layer "B.Cu") (net 251))
  (segment (start 122.432929 96.101475) (end 122.461747 96.130293) (width 0.182) (layer "B.Cu") (net 251))
  (segment (start 123.367071 96.966524) (end 123.388754 97.001033) (width 0.182) (layer "B.Cu") (net 251))
  (segment (start 123.265276 96.174563) (end 123.303744 96.188023) (width 0.182) (layer "B.Cu") (net 251))
  (segment (start 122.461747 96.858293) (end 122.496256 96.879976) (width 0.182) (layer "B.Cu") (net 251))
  (segment (start 122.534724 96.538563) (end 122.496256 96.552023) (width 0.182) (layer "B.Cu") (net 251))
  (segment (start 123.406778 97.08) (end 123.402214 97.120498) (width 0.182) (layer "B.Cu") (net 251))
  (segment (start 123.303744 97.644023) (end 123.338253 97.665706) (width 0.182) (layer "B.Cu") (net 251))
  (segment (start 123.388754 96.430966) (end 123.367071 96.465475) (width 0.182) (layer "B.Cu") (net 251))
  (segment (start 123.265276 96.529436) (end 123.224778 96.534) (width 0.182) (layer "B.Cu") (net 251))
  (segment (start 122.534724 96.165436) (end 122.575222 96.17) (width 0.182) (layer "B.Cu") (net 251))
  (segment (start 122.397786 98.212498) (end 122.411246 98.250966) (width 0.182) (layer "B.Cu") (net 251))
  (segment (start 122.496256 97.280023) (end 122.461747 97.301706) (width 0.182) (layer "B.Cu") (net 251))
  (segment (start 123.338253 97.950293) (end 123.303744 97.971976) (width 0.182) (layer "B.Cu") (net 251))
  (segment (start 122.496256 95.824023) (end 122.461747 95.845706) (width 0.182) (layer "B.Cu") (net 251))
  (segment (start 123.388754 96.273033) (end 123.402214 96.311501) (width 0.182) (layer "B.Cu") (net 251))
  (segment (start 123.338253 97.665706) (end 123.367071 97.694524) (width 0.182) (layer "B.Cu") (net 251))
  (segment (start 122.496256 96.151976) (end 122.534724 96.165436) (width 0.182) (layer "B.Cu") (net 251))
  (segment (start 123.388754 97.158966) (end 123.367071 97.193475) (width 0.182) (layer "B.Cu") (net 251))
  (segment (start 122.939706 95.373475) (end 122.968524 95.402293) (width 0.182) (layer "B.Cu") (net 251))
  (segment (start 123.224778 96.534) (end 122.575222 96.534) (width 0.182) (layer "B.Cu") (net 251))
  (segment (start 123.402214 97.848498) (end 123.388754 97.886966) (width 0.182) (layer "B.Cu") (net 251))
  (segment (start 123.003033 98.736023) (end 122.968524 98.757706) (width 0.182) (layer "B.Cu") (net 251))
  (segment (start 122.397786 97.403501) (end 122.393222 97.444) (width 0.182) (layer "B.Cu") (net 251))
  (segment (start 123.338253 95.766293) (end 123.303744 95.787976) (width 0.182) (layer "B.Cu") (net 251))
  (segment (start 123.265276 98.358563) (end 123.303744 98.372023) (width 0.182) (layer "B.Cu") (net 251))
  (segment (start 123.406778 95.624) (end 123.402214 95.664498) (width 0.182) (layer "B.Cu") (net 251))
  (segment (start 122.411246 97.522966) (end 122.432929 97.557475) (width 0.182) (layer "B.Cu") (net 251))
  (segment (start 122.904563 98.859501) (end 122.9 98.9) (width 0.182) (layer "B.Cu") (net 251))
  (segment (start 123.041501 95.437436) (end 123.082 95.442) (width 0.182) (layer "B.Cu") (net 251))
  (segment (start 123.402214 96.392498) (end 123.388754 96.430966) (width 0.182) (layer "B.Cu") (net 251))
  (segment (start 123.406778 96.352) (end 123.402214 96.392498) (width 0.182) (layer "B.Cu") (net 251))
  (segment (start 123.303744 95.787976) (end 123.265276 95.801436) (width 0.182) (layer "B.Cu") (net 251))
  (segment (start 122.461747 97.586293) (end 122.496256 97.607976) (width 0.182) (layer "B.Cu") (net 251))
  (segment (start 122.461747 98.029706) (end 122.432929 98.058524) (width 0.182) (layer "B.Cu") (net 251))
  (segment (start 122.496256 98.008023) (end 122.461747 98.029706) (width 0.182) (layer "B.Cu") (net 251))
  (segment (start 123.224778 95.806) (end 122.575222 95.806) (width 0.182) (layer "B.Cu") (net 251))
  (segment (start 127.2 102) (end 127.35 101.85) (width 0.182) (layer "B.Cu") (net 251))
  (segment (start 122.575222 97.626) (end 123.224778 97.626) (width 0.182) (layer "B.Cu") (net 251))
  (segment (start 122.393222 97.444) (end 122.397786 97.484498) (width 0.182) (layer "B.Cu") (net 251))
  (segment (start 123.402214 95.664498) (end 123.388754 95.702966) (width 0.182) (layer "B.Cu") (net 251))
  (segment (start 122.432929 96.602524) (end 122.411246 96.637033) (width 0.182) (layer "B.Cu") (net 251))
  (segment (start 122.968524 95.402293) (end 123.003033 95.423976) (width 0.182) (layer "B.Cu") (net 251))
  (segment (start 122.393222 96.716) (end 122.397786 96.756498) (width 0.182) (layer "B.Cu") (net 251))
  (segment (start 123.303744 97.971976) (end 123.265276 97.985436) (width 0.182) (layer "B.Cu") (net 251))
  (segment (start 123.224778 96.17) (end 123.265276 96.174563) (width 0.182) (layer "B.Cu") (net 251))
  (segment (start 122.411246 95.909033) (end 122.397786 95.947501) (width 0.182) (layer "B.Cu") (net 251))
  (segment (start 122.534724 97.266563) (end 122.496256 97.280023) (width 0.182) (layer "B.Cu") (net 251))
  (segment (start 123.367071 97.921475) (end 123.338253 97.950293) (width 0.182) (layer "B.Cu") (net 251))
  (segment (start 122.9 95.26) (end 122.904563 95.300498) (width 0.182) (layer "B.Cu") (net 251))
  (segment (start 123.338253 96.937706) (end 123.367071 96.966524) (width 0.182) (layer "B.Cu") (net 251))
  (segment (start 122.461747 95.845706) (end 122.432929 95.874524) (width 0.182) (layer "B.Cu") (net 251))
  (segment (start 123.303744 98.699976) (end 123.265276 98.713436) (width 0.182) (layer "B.Cu") (net 251))
  (segment (start 123.367071 98.422524) (end 123.388754 98.457033) (width 0.182) (layer "B.Cu") (net 251))
  (segment (start 123.338253 98.678293) (end 123.303744 98.699976) (width 0.182) (layer "B.Cu") (net 251))
  (segment (start 123.224778 97.626) (end 123.265276 97.630563) (width 0.182) (layer "B.Cu") (net 251))
  (segment (start 123.402214 97.120498) (end 123.388754 97.158966) (width 0.182) (layer "B.Cu") (net 251))
  (segment (start 123.338253 97.222293) (end 123.303744 97.243976) (width 0.182) (layer "B.Cu") (net 251))
  (segment (start 122.397786 96.756498) (end 122.411246 96.794966) (width 0.182) (layer "B.Cu") (net 251))
  (segment (start 122.575222 95.806) (end 122.534724 95.810563) (width 0.182) (layer "B.Cu") (net 251))
  (segment (start 123.388754 98.614966) (end 123.367071 98.649475) (width 0.182) (layer "B.Cu") (net 251))
  (segment (start 122.411246 97.365033) (end 122.397786 97.403501) (width 0.182) (layer "B.Cu") (net 251))
  (segment (start 123.388754 95.545033) (end 123.402214 95.583501) (width 0.182) (layer "B.Cu") (net 251))
  (segment (start 123.402214 97.767501) (end 123.406778 97.808) (width 0.182) (layer "B.Cu") (net 251))
  (segment (start 123.265276 96.902563) (end 123.303744 96.916023) (width 0.182) (layer "B.Cu") (net 251))
  (segment (start 123.338253 98.393706) (end 123.367071 98.422524) (width 0.182) (layer "B.Cu") (net 251))
  (segment (start 123.3 102) (end 127.2 102) (width 0.182) (layer "B.Cu") (net 251))
  (segment (start 123.367071 95.737475) (end 123.338253 95.766293) (width 0.182) (layer "B.Cu") (net 251))
  (segment (start 122.432929 98.285475) (end 122.461747 98.314293) (width 0.182) (layer "B.Cu") (net 251))
  (segment (start 122.9 101.6) (end 123.3 102) (width 0.182) (layer "B.Cu") (net 251))
  (segment (start 122.432929 98.058524) (end 122.411246 98.093033) (width 0.182) (layer "B.Cu") (net 251))
  (segment (start 123.224778 98.354) (end 123.265276 98.358563) (width 0.182) (layer "B.Cu") (net 251))
  (segment (start 122.461747 96.130293) (end 122.496256 96.151976) (width 0.182) (layer "B.Cu") (net 251))
  (segment (start 123.265276 97.630563) (end 123.303744 97.644023) (width 0.182) (layer "B.Cu") (net 251))
  (segment (start 127.35 101.85) (end 127.35 100.25) (width 0.182) (layer "B.Cu") (net 251))
  (segment (start 123.402214 95.583501) (end 123.406778 95.624) (width 0.182) (layer "B.Cu") (net 251))
  (segment (start 122.397786 96.675501) (end 122.393222 96.716) (width 0.182) (layer "B.Cu") (net 251))
  (segment (start 122.575222 97.262) (end 122.534724 97.266563) (width 0.182) (layer "B.Cu") (net 251))
  (segment (start 123.338253 96.494293) (end 123.303744 96.515976) (width 0.182) (layer "B.Cu") (net 251))
  (segment (start 123.338253 96.209706) (end 123.367071 96.238524) (width 0.182) (layer "B.Cu") (net 251))
  (segment (start 123.367071 97.694524) (end 123.388754 97.729033) (width 0.182) (layer "B.Cu") (net 251))
  (segment (start 123.265276 98.713436) (end 123.224778 98.718) (width 0.182) (layer "B.Cu") (net 251))
  (segment (start 123.224778 96.898) (end 123.265276 96.902563) (width 0.182) (layer "B.Cu") (net 251))
  (segment (start 122.411246 96.794966) (end 122.432929 96.829475) (width 0.182) (layer "B.Cu") (net 251))
  (segment (start 123.406778 98.536) (end 123.402214 98.576498) (width 0.182) (layer "B.Cu") (net 251))
  (segment (start 122.397786 98.131501) (end 122.393222 98.172) (width 0.182) (layer "B.Cu") (net 251))
  (segment (start 122.432929 95.874524) (end 122.411246 95.909033) (width 0.182) (layer "B.Cu") (net 251))
  (segment (start 122.461747 96.573706) (end 122.432929 96.602524) (width 0.182) (layer "B.Cu") (net 251))
  (segment (start 123.367071 96.238524) (end 123.388754 96.273033) (width 0.182) (layer "B.Cu") (net 251))
  (segment (start 123.224778 97.262) (end 122.575222 97.262) (width 0.182) (layer "B.Cu") (net 251))
  (segment (start 122.411246 98.093033) (end 122.397786 98.131501) (width 0.182) (layer "B.Cu") (net 251))
  (segment (start 123.388754 98.457033) (end 123.402214 98.495501) (width 0.182) (layer "B.Cu") (net 251))
  (segment (start 123.388754 95.702966) (end 123.367071 95.737475) (width 0.182) (layer "B.Cu") (net 251))
  (segment (start 122.411246 98.250966) (end 122.432929 98.285475) (width 0.182) (layer "B.Cu") (net 251))
  (segment (start 123.303744 96.515976) (end 123.265276 96.529436) (width 0.182) (layer "B.Cu") (net 251))
  (segment (start 123.265276 97.257436) (end 123.224778 97.262) (width 0.182) (layer "B.Cu") (net 251))
  (segment (start 122.432929 96.829475) (end 122.461747 96.858293) (width 0.182) (layer "B.Cu") (net 251))
  (segment (start 122.534724 96.893436) (end 122.575222 96.898) (width 0.182) (layer "B.Cu") (net 251))
  (segment (start 122.496256 96.879976) (end 122.534724 96.893436) (width 0.182) (layer "B.Cu") (net 251))
  (segment (start 122.575222 96.534) (end 122.534724 96.538563) (width 0.182) (layer "B.Cu") (net 251))
  (segment (start 123.265276 95.446563) (end 123.303744 95.460023) (width 0.182) (layer "B.Cu") (net 251))
  (segment (start 122.461747 98.314293) (end 122.496256 98.335976) (width 0.182) (layer "B.Cu") (net 251))
  (segment (start 123.367071 98.649475) (end 123.338253 98.678293) (width 0.182) (layer "B.Cu") (net 251))
  (segment (start 122.393222 98.172) (end 122.397786 98.212498) (width 0.182) (layer "B.Cu") (net 251))
  (segment (start 122.939706 98.786524) (end 122.918023 98.821033) (width 0.182) (layer "B.Cu") (net 251))
  (segment (start 122.534724 97.994563) (end 122.496256 98.008023) (width 0.182) (layer "B.Cu") (net 251))
  (segment (start 122.534724 95.810563) (end 122.496256 95.824023) (width 0.182) (layer "B.Cu") (net 251))
  (segment (start 123.367071 96.465475) (end 123.338253 96.494293) (width 0.182) (layer "B.Cu") (net 251))
  (segment (start 123.303744 96.188023) (end 123.338253 96.209706) (width 0.182) (layer "B.Cu") (net 251))
  (segment (start 122.432929 97.330524) (end 122.411246 97.365033) (width 0.182) (layer "B.Cu") (net 251))
  (segment (start 122.9 94.285) (end 122.9 95.26) (width 0.182) (layer "B.Cu") (net 251))
  (segment (start 123.402214 98.495501) (end 123.406778 98.536) (width 0.182) (layer "B.Cu") (net 251))
  (segment (start 122.575222 96.898) (end 123.224778 96.898) (width 0.182) (layer "B.Cu") (net 251))
  (segment (start 122.397786 96.028498) (end 122.411246 96.066966) (width 0.182) (layer "B.Cu") (net 251))
  (segment (start 122.397786 97.484498) (end 122.411246 97.522966) (width 0.182) (layer "B.Cu") (net 251))
  (segment (start 123.367071 95.510524) (end 123.388754 95.545033) (width 0.182) (layer "B.Cu") (net 251))
  (segment (start 123.388754 97.001033) (end 123.402214 97.039501) (width 0.182) (layer "B.Cu") (net 251))
  (segment (start 123.402214 97.039501) (end 123.406778 97.08) (width 0.182) (layer "B.Cu") (net 251))
  (segment (start 123.224778 97.99) (end 122.575222 97.99) (width 0.182) (layer "B.Cu") (net 251))
  (segment (start 122.411246 96.066966) (end 122.432929 96.101475) (width 0.182) (layer "B.Cu") (net 251))
  (segment (start 122.411246 96.637033) (end 122.397786 96.675501) (width 0.182) (layer "B.Cu") (net 251))
  (segment (start 122.393222 95.988) (end 122.397786 96.028498) (width 0.182) (layer "B.Cu") (net 251))
  (segment (start 123.402214 96.311501) (end 123.406778 96.352) (width 0.182) (layer "B.Cu") (net 251))
  (segment (start 123.003033 95.423976) (end 123.041501 95.437436) (width 0.182) (layer "B.Cu") (net 251))
  (segment (start 122.9 98.9) (end 122.9 101.6) (width 0.182) (layer "B.Cu") (net 251))
  (segment (start 122.534724 98.349436) (end 122.575222 98.354) (width 0.182) (layer "B.Cu") (net 251))
  (segment (start 123.303744 96.916023) (end 123.338253 96.937706) (width 0.182) (layer "B.Cu") (net 251))
  (segment (start 122.918023 98.821033) (end 122.904563 98.859501) (width 0.182) (layer "B.Cu") (net 251))
  (segment (start 123.041501 98.722563) (end 123.003033 98.736023) (width 0.182) (layer "B.Cu") (net 251))
  (segment (start 122.397786 95.947501) (end 122.393222 95.988) (width 0.182) (layer "B.Cu") (net 251))
  (segment (start 123.265276 97.985436) (end 123.224778 97.99) (width 0.182) (layer "B.Cu") (net 251))
  (segment (start 122.575222 97.99) (end 122.534724 97.994563) (width 0.182) (layer "B.Cu") (net 251))
  (segment (start 123.224778 95.442) (end 123.265276 95.446563) (width 0.182) (layer "B.Cu") (net 251))
  (segment (start 123.303744 98.372023) (end 123.338253 98.393706) (width 0.182) (layer "B.Cu") (net 251))
  (segment (start 122.496256 96.552023) (end 122.461747 96.573706) (width 0.182) (layer "B.Cu") (net 251))
  (segment (start 122.496256 98.335976) (end 122.534724 98.349436) (width 0.182) (layer "B.Cu") (net 251))
  (segment (start 123.265276 95.801436) (end 123.224778 95.806) (width 0.182) (layer "B.Cu") (net 251))
  (segment (start 123.388754 97.886966) (end 123.367071 97.921475) (width 0.182) (layer "B.Cu") (net 251))
  (segment (start 123.303744 97.243976) (end 123.265276 97.257436) (width 0.182) (layer "B.Cu") (net 251))
  (segment (start 123.406778 97.808) (end 123.402214 97.848498) (width 0.182) (layer "B.Cu") (net 251))
  (segment (start 123.338253 95.481706) (end 123.367071 95.510524) (width 0.182) (layer "B.Cu") (net 251))
  (segment (start 123.082 95.442) (end 123.224778 95.442) (width 0.182) (layer "B.Cu") (net 251))
  (segment (start 122.461747 97.301706) (end 122.432929 97.330524) (width 0.182) (layer "B.Cu") (net 251))
  (segment (start 127.35 100.25) (end 126.299 99.199) (width 0.182) (layer "B.Cu") (net 251))
  (segment (start 122.432929 97.557475) (end 122.461747 97.586293) (width 0.182) (layer "B.Cu") (net 251))
  (segment (start 123.402214 98.576498) (end 123.388754 98.614966) (width 0.182) (layer "B.Cu") (net 251))
  (segment (start 122.904563 95.300498) (end 122.918023 95.338966) (width 0.182) (layer "B.Cu") (net 251))
  (segment (start 121.43327 97.755495) (end 121.438284 97.8) (width 0.182) (layer "B.Cu") (net 252))
  (segment (start 121.238284 96.8) (end 121.282789 96.805014) (width 0.182) (layer "B.Cu") (net 252))
  (segment (start 121.238284 98) (end 120.561716 98) (width 0.182) (layer "B.Cu") (net 252))
  (segment (start 121.394651 96.875302) (end 121.418478 96.913223) (width 0.182) (layer "B.Cu") (net 252))
  (segment (start 121.238284 97.6) (end 121.282789 97.605014) (width 0.182) (layer "B.Cu") (net 252))
  (segment (start 120.474939 97.580193) (end 120.517211 97.594985) (width 0.182) (layer "B.Cu") (net 252))
  (segment (start 121.394651 97.675302) (end 121.418478 97.713223) (width 0.182) (layer "B.Cu") (net 252))
  (segment (start 121.325061 96.819806) (end 121.362982 96.843633) (width 0.182) (layer "B.Cu") (net 252))
  (segment (start 120.824697 98.443633) (end 120.856366 98.475302) (width 0.182) (layer "B.Cu") (net 252))
  (segment (start 127.85 99.32) (end 127.425 98.895) (width 0.182) (layer "B.Cu") (net 252))
  (segment (start 120.517211 95.994985) (end 120.561716 96) (width 0.182) (layer "B.Cu") (net 252))
  (segment (start 120.856366 98.475302) (end 120.880193 98.513223) (width 0.182) (layer "B.Cu") (net 252))
  (segment (start 120.381522 96.686776) (end 120.405349 96.724697) (width 0.182) (layer "B.Cu") (net 252))
  (segment (start 121.282789 96.005014) (end 121.325061 96.019806) (width 0.182) (layer "B.Cu") (net 252))
  (segment (start 120.561716 96.8) (end 121.238284 96.8) (width 0.182) (layer "B.Cu") (net 252))
  (segment (start 121.394651 96.324697) (end 121.362982 96.356366) (width 0.182) (layer "B.Cu") (net 252))
  (segment (start 121.325061 97.180193) (end 121.282789 97.194985) (width 0.182) (layer "B.Cu") (net 252))
  (segment (start 120.437018 97.243633) (end 120.405349 97.275302) (width 0.182) (layer "B.Cu") (net 252))
  (segment (start 121.325061 96.380193) (end 121.282789 96.394985) (width 0.182) (layer "B.Cu") (net 252))
  (segment (start 120.405349 97.275302) (end 120.381522 97.313223) (width 0.182) (layer "B.Cu") (net 252))
  (segment (start 120.561716 97.6) (end 121.238284 97.6) (width 0.182) (layer "B.Cu") (net 252))
  (segment (start 121.238284 96.4) (end 120.561716 96.4) (width 0.182) (layer "B.Cu") (net 252))
  (segment (start 121.394651 97.124697) (end 121.362982 97.156366) (width 0.182) (layer "B.Cu") (net 252))
  (segment (start 121.43327 97.844504) (end 121.418478 97.886776) (width 0.182) (layer "B.Cu") (net 252))
  (segment (start 120.786776 95.580193) (end 120.744504 95.594985) (width 0.182) (layer "B.Cu") (net 252))
  (segment (start 120.381522 97.313223) (end 120.36673 97.355495) (width 0.182) (layer "B.Cu") (net 252))
  (segment (start 120.561716 96) (end 121.238284 96) (width 0.182) (layer "B.Cu") (net 252))
  (segment (start 120.36673 96.644504) (end 120.381522 96.686776) (width 0.182) (layer "B.Cu") (net 252))
  (segment (start 120.856366 95.524697) (end 120.824697 95.556366) (width 0.182) (layer "B.Cu") (net 252))
  (segment (start 120.381522 96.513223) (end 120.36673 96.555495) (width 0.182) (layer "B.Cu") (net 252))
  (segment (start 120.381522 98.286776) (end 120.405349 98.324697) (width 0.182) (layer "B.Cu") (net 252))
  (segment (start 121.43327 96.155495) (end 121.438284 96.2) (width 0.182) (layer "B.Cu") (net 252))
  (segment (start 120.9 98.6) (end 120.9 102.5) (width 0.182) (layer "B.Cu") (net 252))
  (segment (start 120.517211 96.405014) (end 120.474939 96.419806) (width 0.182) (layer "B.Cu") (net 252))
  (segment (start 120.361716 98.2) (end 120.36673 98.244504) (width 0.182) (layer "B.Cu") (net 252))
  (segment (start 121.418478 97.713223) (end 121.43327 97.755495) (width 0.182) (layer "B.Cu") (net 252))
  (segment (start 121.362982 97.156366) (end 121.325061 97.180193) (width 0.182) (layer "B.Cu") (net 252))
  (segment (start 121.362982 96.843633) (end 121.394651 96.875302) (width 0.182) (layer "B.Cu") (net 252))
  (segment (start 121.438284 97.8) (end 121.43327 97.844504) (width 0.182) (layer "B.Cu") (net 252))
  (segment (start 120.36673 97.444504) (end 120.381522 97.486776) (width 0.182) (layer "B.Cu") (net 252))
  (segment (start 120.474939 95.980193) (end 120.517211 95.994985) (width 0.182) (layer "B.Cu") (net 252))
  (segment (start 121.418478 96.286776) (end 121.394651 96.324697) (width 0.182) (layer "B.Cu") (net 252))
  (segment (start 120.474939 96.780193) (end 120.517211 96.794985) (width 0.182) (layer "B.Cu") (net 252))
  (segment (start 120.474939 98.019806) (end 120.437018 98.043633) (width 0.182) (layer "B.Cu") (net 252))
  (segment (start 120.517211 98.394985) (end 120.561716 98.4) (width 0.182) (layer "B.Cu") (net 252))
  (segment (start 121.418478 97.086776) (end 121.394651 97.124697) (width 0.182) (layer "B.Cu") (net 252))
  (segment (start 120.381522 95.713223) (end 120.36673 95.755495) (width 0.182) (layer "B.Cu") (net 252))
  (segment (start 120.561716 96.4) (end 120.517211 96.405014) (width 0.182) (layer "B.Cu") (net 252))
  (segment (start 120.36673 95.844504) (end 120.381522 95.886776) (width 0.182) (layer "B.Cu") (net 252))
  (segment (start 120.561716 98) (end 120.517211 98.005014) (width 0.182) (layer "B.Cu") (net 252))
  (segment (start 120.517211 97.594985) (end 120.561716 97.6) (width 0.182) (layer "B.Cu") (net 252))
  (segment (start 121.325061 97.619806) (end 121.362982 97.643633) (width 0.182) (layer "B.Cu") (net 252))
  (segment (start 121.362982 96.356366) (end 121.325061 96.380193) (width 0.182) (layer "B.Cu") (net 252))
  (segment (start 120.561716 97.2) (end 120.517211 97.205014) (width 0.182) (layer "B.Cu") (net 252))
  (segment (start 120.361716 96.6) (end 120.36673 96.644504) (width 0.182) (layer "B.Cu") (net 252))
  (segment (start 121.43327 97.044504) (end 121.418478 97.086776) (width 0.182) (layer "B.Cu") (net 252))
  (segment (start 120.405349 95.675302) (end 120.381522 95.713223) (width 0.182) (layer "B.Cu") (net 252))
  (segment (start 123.4 102.4) (end 127.4 102.4) (width 0.182) (layer "B.Cu") (net 252))
  (segment (start 120.9 94.285) (end 120.9 95.4) (width 0.182) (layer "B.Cu") (net 252))
  (segment (start 120.744504 95.594985) (end 120.7 95.6) (width 0.182) (layer "B.Cu") (net 252))
  (segment (start 121.43327 96.244504) (end 121.418478 96.286776) (width 0.182) (layer "B.Cu") (net 252))
  (segment (start 121.438284 97) (end 121.43327 97.044504) (width 0.182) (layer "B.Cu") (net 252))
  (segment (start 121.418478 96.113223) (end 121.43327 96.155495) (width 0.182) (layer "B.Cu") (net 252))
  (segment (start 122.8 103) (end 123.4 102.4) (width 0.182) (layer "B.Cu") (net 252))
  (segment (start 120.361716 97.4) (end 120.36673 97.444504) (width 0.182) (layer "B.Cu") (net 252))
  (segment (start 121.282789 97.194985) (end 121.238284 97.2) (width 0.182) (layer "B.Cu") (net 252))
  (segment (start 120.517211 98.005014) (end 120.474939 98.019806) (width 0.182) (layer "B.Cu") (net 252))
  (segment (start 120.474939 95.619806) (end 120.437018 95.643633) (width 0.182) (layer "B.Cu") (net 252))
  (segment (start 121.325061 96.019806) (end 121.362982 96.043633) (width 0.182) (layer "B.Cu") (net 252))
  (segment (start 120.405349 96.475302) (end 120.381522 96.513223) (width 0.182) (layer "B.Cu") (net 252))
  (segment (start 120.744504 98.405014) (end 120.786776 98.419806) (width 0.182) (layer "B.Cu") (net 252))
  (segment (start 120.437018 95.643633) (end 120.405349 95.675302) (width 0.182) (layer "B.Cu") (net 252))
  (segment (start 120.36673 96.555495) (end 120.361716 96.6) (width 0.182) (layer "B.Cu") (net 252))
  (segment (start 120.405349 98.324697) (end 120.437018 98.356366) (width 0.182) (layer "B.Cu") (net 252))
  (segment (start 120.7 95.6) (end 120.561716 95.6) (width 0.182) (layer "B.Cu") (net 252))
  (segment (start 121.43327 96.955495) (end 121.438284 97) (width 0.182) (layer "B.Cu") (net 252))
  (segment (start 121.362982 97.643633) (end 121.394651 97.675302) (width 0.182) (layer "B.Cu") (net 252))
  (segment (start 120.561716 98.4) (end 120.7 98.4) (width 0.182) (layer "B.Cu") (net 252))
  (segment (start 121.394651 97.924697) (end 121.362982 97.956366) (width 0.182) (layer "B.Cu") (net 252))
  (segment (start 120.880193 98.513223) (end 120.894985 98.555495) (width 0.182) (layer "B.Cu") (net 252))
  (segment (start 127.85 101.95) (end 127.85 99.32) (width 0.182) (layer "B.Cu") (net 252))
  (segment (start 121.362982 97.956366) (end 121.325061 97.980193) (width 0.182) (layer "B.Cu") (net 252))
  (segment (start 120.437018 96.443633) (end 120.405349 96.475302) (width 0.182) (layer "B.Cu") (net 252))
  (segment (start 121.418478 97.886776) (end 121.394651 97.924697) (width 0.182) (layer "B.Cu") (net 252))
  (segment (start 120.437018 96.756366) (end 120.474939 96.780193) (width 0.182) (layer "B.Cu") (net 252))
  (segment (start 120.474939 96.419806) (end 120.437018 96.443633) (width 0.182) (layer "B.Cu") (net 252))
  (segment (start 120.381522 98.113223) (end 120.36673 98.155495) (width 0.182) (layer "B.Cu") (net 252))
  (segment (start 120.517211 97.205014) (end 120.474939 97.219806) (width 0.182) (layer "B.Cu") (net 252))
  (segment (start 120.361716 95.8) (end 120.36673 95.844504) (width 0.182) (layer "B.Cu") (net 252))
  (segment (start 120.824697 95.556366) (end 120.786776 95.580193) (width 0.182) (layer "B.Cu") (net 252))
  (segment (start 120.36673 98.244504) (end 120.381522 98.286776) (width 0.182) (layer "B.Cu") (net 252))
  (segment (start 127.4 102.4) (end 127.85 101.95) (width 0.182) (layer "B.Cu") (net 252))
  (segment (start 120.7 98.4) (end 120.744504 98.405014) (width 0.182) (layer "B.Cu") (net 252))
  (segment (start 121.362982 96.043633) (end 121.394651 96.075302) (width 0.182) (layer "B.Cu") (net 252))
  (segment (start 121.238284 96) (end 121.282789 96.005014) (width 0.182) (layer "B.Cu") (net 252))
  (segment (start 121.238284 97.2) (end 120.561716 97.2) (width 0.182) (layer "B.Cu") (net 252))
  (segment (start 120.517211 96.794985) (end 120.561716 96.8) (width 0.182) (layer "B.Cu") (net 252))
  (segment (start 121.394651 96.075302) (end 121.418478 96.113223) (width 0.182) (layer "B.Cu") (net 252))
  (segment (start 121.4 103) (end 122.8 103) (width 0.182) (layer "B.Cu") (net 252))
  (segment (start 121.282789 97.994985) (end 121.238284 98) (width 0.182) (layer "B.Cu") (net 252))
  (segment (start 121.438284 96.2) (end 121.43327 96.244504) (width 0.182) (layer "B.Cu") (net 252))
  (segment (start 120.36673 97.355495) (end 120.361716 97.4) (width 0.182) (layer "B.Cu") (net 252))
  (segment (start 121.282789 96.394985) (end 121.238284 96.4) (width 0.182) (layer "B.Cu") (net 252))
  (segment (start 120.381522 97.486776) (end 120.405349 97.524697) (width 0.182) (layer "B.Cu") (net 252))
  (segment (start 120.561716 95.6) (end 120.517211 95.605014) (width 0.182) (layer "B.Cu") (net 252))
  (segment (start 121.418478 96.913223) (end 121.43327 96.955495) (width 0.182) (layer "B.Cu") (net 252))
  (segment (start 120.9 95.4) (end 120.894985 95.444504) (width 0.182) (layer "B.Cu") (net 252))
  (segment (start 120.474939 97.219806) (end 120.437018 97.243633) (width 0.182) (layer "B.Cu") (net 252))
  (segment (start 120.517211 95.605014) (end 120.474939 95.619806) (width 0.182) (layer "B.Cu") (net 252))
  (segment (start 120.9 102.5) (end 121.4 103) (width 0.182) (layer "B.Cu") (net 252))
  (segment (start 120.437018 97.556366) (end 120.474939 97.580193) (width 0.182) (layer "B.Cu") (net 252))
  (segment (start 120.36673 95.755495) (end 120.361716 95.8) (width 0.182) (layer "B.Cu") (net 252))
  (segment (start 120.880193 95.486776) (end 120.856366 95.524697) (width 0.182) (layer "B.Cu") (net 252))
  (segment (start 120.894985 95.444504) (end 120.880193 95.486776) (width 0.182) (layer "B.Cu") (net 252))
  (segment (start 120.405349 96.724697) (end 120.437018 96.756366) (width 0.182) (layer "B.Cu") (net 252))
  (segment (start 120.894985 98.555495) (end 120.9 98.6) (width 0.182) (layer "B.Cu") (net 252))
  (segment (start 121.282789 96.805014) (end 121.325061 96.819806) (width 0.182) (layer "B.Cu") (net 252))
  (segment (start 120.437018 98.043633) (end 120.405349 98.075302) (width 0.182) (layer "B.Cu") (net 252))
  (segment (start 120.381522 95.886776) (end 120.405349 95.924697) (width 0.182) (layer "B.Cu") (net 252))
  (segment (start 120.405349 98.075302) (end 120.381522 98.113223) (width 0.182) (layer "B.Cu") (net 252))
  (segment (start 120.474939 98.380193) (end 120.517211 98.394985) (width 0.182) (layer "B.Cu") (net 252))
  (segment (start 120.786776 98.419806) (end 120.824697 98.443633) (width 0.182) (layer "B.Cu") (net 252))
  (segment (start 120.405349 95.924697) (end 120.437018 95.956366) (width 0.182) (layer "B.Cu") (net 252))
  (segment (start 120.36673 98.155495) (end 120.361716 98.2) (width 0.182) (layer "B.Cu") (net 252))
  (segment (start 120.405349 97.524697) (end 120.437018 97.556366) (width 0.182) (layer "B.Cu") (net 252))
  (segment (start 120.437018 95.956366) (end 120.474939 95.980193) (width 0.182) (layer "B.Cu") (net 252))
  (segment (start 120.437018 98.356366) (end 120.474939 98.380193) (width 0.182) (layer "B.Cu") (net 252))
  (segment (start 121.282789 97.605014) (end 121.325061 97.619806) (width 0.182) (layer "B.Cu") (net 252))
  (segment (start 121.325061 97.980193) (end 121.282789 97.994985) (width 0.182) (layer "B.Cu") (net 252))
  (segment (start 128.5 141.3875) (end 127.4625 141.3875) (width 0.2) (layer "F.Cu") (net 253))
  (segment (start 128 140.6125) (end 128 141.3875) (width 0.2) (layer "F.Cu") (net 253))
  (segment (start 128.5 141.3875) (end 128.5 140.6125) (width 0.2) (layer "F.Cu") (net 253))
  (segment (start 128.5 143.04) (end 128.5 141.3875) (width 0.2) (layer "F.Cu") (net 253))
  (segment (start 128.25 144.74) (end 128.25 145.123498) (width 0.25) (layer "F.Cu") (net 253))
  (segment (start 128.25 145.123498) (end 128.5 145.373498) (width 0.25) (layer "F.Cu") (net 253))
  (segment (start 128.5 145.373498) (end 128.5 145.9) (width 0.25) (layer "F.Cu") (net 253))
  (segment (start 128.5 145.9) (end 128.9 146.3) (width 0.25) (layer "F.Cu") (net 253))
  (segment (start 128.9 146.3) (end 130.1 146.3) (width 0.25) (layer "F.Cu") (net 253))
  (segment (start 130.5 145.9) (end 130.1 146.3) (width 0.25) (layer "F.Cu") (net 253))
  (segment (start 130.5 145.373498) (end 130.75 145.123498) (width 0.25) (layer "F.Cu") (net 253))
  (segment (start 130.75 145.123498) (end 130.75 144.74) (width 0.25) (layer "F.Cu") (net 253))
  (segment (start 128.25 144.74) (end 128.25 143.740002) (width 0.25) (layer "F.Cu") (net 253))
  (segment (start 128.25 143.740002) (end 128.5 143.490002) (width 0.25) (layer "F.Cu") (net 253))
  (segment (start 128.5 143.490002) (end 128.5 143.04) (width 0.25) (layer "F.Cu") (net 253))
  (segment (start 131 143.04) (end 131 144.039998) (width 0.25) (layer "F.Cu") (net 253))
  (segment (start 131 144.039998) (end 130.75 144.289998) (width 0.25) (layer "F.Cu") (net 253))
  (segment (start 130.75 144.289998) (end 130.75 144.74) (width 0.25) (layer "F.Cu") (net 253))
  (segment (start 130.5 145.373498) (end 130.5 145.9) (width 0.25) (layer "F.Cu") (net 253))
  (via (at 86.717157 105.367157) (size 0.6) (drill 0.25) (layers "F.Cu" "B.Cu") (net 254))
  (segment (start 86.717157 105.367157) (end 86.717157 105.756066) (width 0.125) (layer "In2.Cu") (net 254))
  (segment (start 82.93269 129.8375) (end 66.43269 129.8375) (width 0.125) (layer "In2.Cu") (net 254))
  (segment (start 66.43269 129.8375) (end 63.93269 132.3375) (width 0.125) (layer "In2.Cu") (net 254))
  (segment (start 86.4375 126.33269) (end 82.93269 129.8375) (width 0.125) (layer "In2.Cu") (net 254))
  (segment (start 86.4375 106.035723) (end 86.4375 126.33269) (width 0.125) (layer "In2.Cu") (net 254))
  (segment (start 86.717157 105.756066) (end 86.4375 106.035723) (width 0.125) (layer "In2.Cu") (net 254))
  (segment (start 63.93269 132.3375) (end 59.8625 132.3375) (width 0.125) (layer "In2.Cu") (net 254))
  (segment (start 59.8625 132.3375) (end 58.5 133.7) (width 0.125) (layer "In2.Cu") (net 254))
  (segment (start 95.091211 104.17344) (end 94.449782 104.17344) (width 0.125) (layer "B.Cu") (net 254))
  (segment (start 87.106066 105.367157) (end 86.717157 105.367157) (width 0.125) (layer "B.Cu") (net 254))
  (segment (start 87.398223 105.075) (end 87.106066 105.367157) (width 0.125) (layer "B.Cu") (net 254))
  (segment (start 94.449782 104.17344) (end 94.148222 104.475) (width 0.125) (layer "B.Cu") (net 254))
  (segment (start 90.748222 105.075) (end 87.398223 105.075) (width 0.125) (layer "B.Cu") (net 254))
  (segment (start 94.148222 104.475) (end 91.348222 104.475) (width 0.125) (layer "B.Cu") (net 254))
  (segment (start 95.166211 104.09844) (end 95.091211 104.17344) (width 0.125) (layer "B.Cu") (net 254))
  (segment (start 91.348222 104.475) (end 90.748222 105.075) (width 0.125) (layer "B.Cu") (net 254))
  (via (at 87.282843 105.932843) (size 0.6) (drill 0.25) (layers "F.Cu" "B.Cu") (net 255))
  (segment (start 86.893934 105.932843) (end 86.7625 106.064277) (width 0.125) (layer "In2.Cu") (net 255))
  (segment (start 86.7625 126.46731) (end 83.06731 130.1625) (width 0.125) (layer "In2.Cu") (net 255))
  (segment (start 59.99712 132.6625) (end 59.77 132.88962) (width 0.125) (layer "In2.Cu") (net 255))
  (segment (start 86.7625 106.064277) (end 86.7625 126.46731) (width 0.125) (layer "In2.Cu") (net 255))
  (segment (start 83.06731 130.1625) (end 66.56731 130.1625) (width 0.125) (layer "In2.Cu") (net 255))
  (segment (start 66.56731 130.1625) (end 64.06731 132.6625) (width 0.125) (layer "In2.Cu") (net 255))
  (segment (start 59.77 132.88962) (end 59.77 136.24) (width 0.125) (layer "In2.Cu") (net 255))
  (segment (start 64.06731 132.6625) (end 59.99712 132.6625) (width 0.125) (layer "In2.Cu") (net 255))
  (segment (start 87.282843 105.932843) (end 86.893934 105.932843) (width 0.125) (layer "In2.Cu") (net 255))
  (segment (start 91.451778 104.725) (end 90.851778 105.325) (width 0.125) (layer "B.Cu") (net 255))
  (segment (start 87.501777 105.325) (end 87.282843 105.543934) (width 0.125) (layer "B.Cu") (net 255))
  (segment (start 95.166211 104.49844) (end 95.091211 104.42344) (width 0.125) (layer "B.Cu") (net 255))
  (segment (start 87.282843 105.543934) (end 87.282843 105.932843) (width 0.125) (layer "B.Cu") (net 255))
  (segment (start 94.553338 104.42344) (end 94.251778 104.725) (width 0.125) (layer "B.Cu") (net 255))
  (segment (start 95.091211 104.42344) (end 94.553338 104.42344) (width 0.125) (layer "B.Cu") (net 255))
  (segment (start 94.251778 104.725) (end 91.451778 104.725) (width 0.125) (layer "B.Cu") (net 255))
  (segment (start 90.851778 105.325) (end 87.501777 105.325) (width 0.125) (layer "B.Cu") (net 255))
  (via (at 88.167157 103.967157) (size 0.6) (drill 0.25) (layers "F.Cu" "B.Cu") (net 256))
  (segment (start 83.43269 130.8375) (end 87.8375 126.43269) (width 0.125) (layer "In2.Cu") (net 256))
  (segment (start 87.8375 104.685723) (end 88.167157 104.356066) (width 0.125) (layer "In2.Cu") (net 256))
  (segment (start 61.04 133.7) (end 62.04 134.7) (width 0.125) (layer "In2.Cu") (net 256))
  (segment (start 64.8375 134.0625) (end 64.8375 132.93269) (width 0.125) (layer "In2.Cu") (net 256))
  (segment (start 66.93269 130.8375) (end 83.43269 130.8375) (width 0.125) (layer "In2.Cu") (net 256))
  (segment (start 62.04 134.7) (end 64.2 134.7) (width 0.125) (layer "In2.Cu") (net 256))
  (segment (start 87.8375 126.43269) (end 87.8375 104.685723) (width 0.125) (layer "In2.Cu") (net 256))
  (segment (start 64.2 134.7) (end 64.8375 134.0625) (width 0.125) (layer "In2.Cu") (net 256))
  (segment (start 64.8375 132.93269) (end 66.93269 130.8375) (width 0.125) (layer "In2.Cu") (net 256))
  (segment (start 88.167157 104.356066) (end 88.167157 103.967157) (width 0.125) (layer "In2.Cu") (net 256))
  (segment (start 90.848222 103.675) (end 88.848223 103.675) (width 0.125) (layer "B.Cu") (net 256))
  (segment (start 91.549782 102.97344) (end 90.848222 103.675) (width 0.125) (layer "B.Cu") (net 256))
  (segment (start 95.166211 102.89844) (end 95.091211 102.97344) (width 0.125) (layer "B.Cu") (net 256))
  (segment (start 95.091211 102.97344) (end 91.549782 102.97344) (width 0.125) (layer "B.Cu") (net 256))
  (segment (start 88.848223 103.675) (end 88.556066 103.967157) (width 0.125) (layer "B.Cu") (net 256))
  (segment (start 88.556066 103.967157) (end 88.167157 103.967157) (width 0.125) (layer "B.Cu") (net 256))
  (via (at 88.732843 104.532843) (size 0.6) (drill 0.25) (layers "F.Cu" "B.Cu") (net 257))
  (segment (start 88.343934 104.532843) (end 88.732843 104.532843) (width 0.125) (layer "In2.Cu") (net 257))
  (segment (start 65.1625 133.06731) (end 67.06731 131.1625) (width 0.125) (layer "In2.Cu") (net 257))
  (segment (start 88.1625 104.714277) (end 88.343934 104.532843) (width 0.125) (layer "In2.Cu") (net 257))
  (segment (start 83.56731 131.1625) (end 88.1625 126.56731) (width 0.125) (layer "In2.Cu") (net 257))
  (segment (start 65.1625 135.9275) (end 65.1625 133.06731) (width 0.125) (layer "In2.Cu") (net 257))
  (segment (start 88.1625 126.56731) (end 88.1625 104.714277) (width 0.125) (layer "In2.Cu") (net 257))
  (segment (start 67.06731 131.1625) (end 83.56731 131.1625) (width 0.125) (layer "In2.Cu") (net 257))
  (segment (start 95.091211 103.22344) (end 91.653338 103.22344) (width 0.125) (layer "B.Cu") (net 257))
  (segment (start 95.166211 103.29844) (end 95.091211 103.22344) (width 0.125) (layer "B.Cu") (net 257))
  (segment (start 91.653338 103.22344) (end 90.951778 103.925) (width 0.125) (layer "B.Cu") (net 257))
  (segment (start 90.951778 103.925) (end 88.951777 103.925) (width 0.125) (layer "B.Cu") (net 257))
  (segment (start 88.951777 103.925) (end 88.732843 104.143934) (width 0.125) (layer "B.Cu") (net 257))
  (segment (start 88.732843 104.143934) (end 88.732843 104.532843) (width 0.125) (layer "B.Cu") (net 257))
  (via (at 89.967157 102.467157) (size 0.6) (drill 0.25) (layers "F.Cu" "B.Cu") (net 258))
  (segment (start 89.3375 103.485723) (end 89.967157 102.856066) (width 0.125) (layer "In2.Cu") (net 258))
  (segment (start 83.68269 132.0875) (end 88.8375 126.93269) (width 0.125) (layer "In2.Cu") (net 258))
  (segment (start 68.18269 132.0875) (end 83.68269 132.0875) (width 0.125) (layer "In2.Cu") (net 258))
  (segment (start 67.16019 133.7) (end 67.3375 133.52269) (width 0.125) (layer "In2.Cu") (net 258))
  (segment (start 89.967157 102.856066) (end 89.967157 102.467157) (width 0.125) (layer "In2.Cu") (net 258))
  (segment (start 67.3375 133.52269) (end 67.3375 132.93269) (width 0.125) (layer "In2.Cu") (net 258))
  (segment (start 88.8375 126.93269) (end 88.8375 117.93269) (width 0.125) (layer "In2.Cu") (net 258))
  (segment (start 89.3375 112.81731) (end 89.3375 103.485723) (width 0.125) (layer "In2.Cu") (net 258))
  (segment (start 90.3375 113.81731) (end 89.3375 112.81731) (width 0.125) (layer "In2.Cu") (net 258))
  (segment (start 90.3375 116.43269) (end 90.3375 113.81731) (width 0.125) (layer "In2.Cu") (net 258))
  (segment (start 88.8375 117.93269) (end 90.3375 116.43269) (width 0.125) (layer "In2.Cu") (net 258))
  (segment (start 66.12 133.7) (end 67.16019 133.7) (width 0.125) (layer "In2.Cu") (net 258))
  (segment (start 67.3375 132.93269) (end 68.18269 132.0875) (width 0.125) (layer "In2.Cu") (net 258))
  (segment (start 90.649783 102.17344) (end 90.356066 102.467157) (width 0.125) (layer "B.Cu") (net 258))
  (segment (start 90.356066 102.467157) (end 89.967157 102.467157) (width 0.125) (layer "B.Cu") (net 258))
  (segment (start 95.091211 102.17344) (end 90.649783 102.17344) (width 0.125) (layer "B.Cu") (net 258))
  (segment (start 95.166211 102.09844) (end 95.091211 102.17344) (width 0.125) (layer "B.Cu") (net 258))
  (via (at 90.532843 103.032843) (size 0.6) (drill 0.25) (layers "F.Cu" "B.Cu") (net 259))
  (segment (start 89.1625 127.06731) (end 89.1625 118.06731) (width 0.125) (layer "In2.Cu") (net 259))
  (segment (start 67.39 133.92981) (end 67.6625 133.65731) (width 0.125) (layer "In2.Cu") (net 259))
  (segment (start 67.6625 133.06731) (end 68.31731 132.4125) (width 0.125) (layer "In2.Cu") (net 259))
  (segment (start 90.6625 113.68269) (end 89.6625 112.68269) (width 0.125) (layer "In2.Cu") (net 259))
  (segment (start 90.143934 103.032843) (end 90.532843 103.032843) (width 0.125) (layer "In2.Cu") (net 259))
  (segment (start 89.6625 112.68269) (end 89.6625 103.514277) (width 0.125) (layer "In2.Cu") (net 259))
  (segment (start 67.39 136.24) (end 67.39 133.92981) (width 0.125) (layer "In2.Cu") (net 259))
  (segment (start 89.6625 103.514277) (end 90.143934 103.032843) (width 0.125) (layer "In2.Cu") (net 259))
  (segment (start 90.6625 116.56731) (end 90.6625 113.68269) (width 0.125) (layer "In2.Cu") (net 259))
  (segment (start 83.81731 132.4125) (end 89.1625 127.06731) (width 0.125) (layer "In2.Cu") (net 259))
  (segment (start 89.1625 118.06731) (end 90.6625 116.56731) (width 0.125) (layer "In2.Cu") (net 259))
  (segment (start 67.6625 133.65731) (end 67.6625 133.06731) (width 0.125) (layer "In2.Cu") (net 259))
  (segment (start 68.31731 132.4125) (end 83.81731 132.4125) (width 0.125) (layer "In2.Cu") (net 259))
  (segment (start 90.532843 102.643934) (end 90.532843 103.032843) (width 0.125) (layer "B.Cu") (net 259))
  (segment (start 95.166211 102.49844) (end 95.091211 102.42344) (width 0.125) (layer "B.Cu") (net 259))
  (segment (start 95.091211 102.42344) (end 90.753337 102.42344) (width 0.125) (layer "B.Cu") (net 259))
  (segment (start 90.753337 102.42344) (end 90.532843 102.643934) (width 0.125) (layer "B.Cu") (net 259))
  (via (at 91.967157 99.217157) (size 0.6) (drill 0.25) (layers "F.Cu" "B.Cu") (net 260))
  (segment (start 91.3375 116.93269) (end 91.3375 100.18269) (width 0.125) (layer "In2.Cu") (net 260))
  (segment (start 89.8375 127.43269) (end 89.8375 118.43269) (width 0.125) (layer "In2.Cu") (net 260))
  (segment (start 89.8375 118.43269) (end 91.3375 116.93269) (width 0.125) (layer "In2.Cu") (net 260))
  (segment (start 68.66 133.7) (end 69.70019 133.7) (width 0.125) (layer "In2.Cu") (net 260))
  (segment (start 70.06269 133.3375) (end 83.93269 133.3375) (width 0.125) (layer "In2.Cu") (net 260))
  (segment (start 91.3375 100.18269) (end 91.967157 99.553033) (width 0.125) (layer "In2.Cu") (net 260))
  (segment (start 83.93269 133.3375) (end 89.8375 127.43269) (width 0.125) (layer "In2.Cu") (net 260))
  (segment (start 69.70019 133.7) (end 70.06269 133.3375) (width 0.125) (layer "In2.Cu") (net 260))
  (segment (start 91.967157 99.553033) (end 91.967157 99.217157) (width 0.125) (layer "In2.Cu") (net 260))
  (segment (start 96.171211 101.09344) (end 96.096211 101.01844) (width 0.125) (layer "B.Cu") (net 260))
  (segment (start 96.096211 100.419433) (end 94.551778 98.875) (width 0.125) (layer "B.Cu") (net 260))
  (segment (start 92.356066 99.217157) (end 91.967157 99.217157) (width 0.125) (layer "B.Cu") (net 260))
  (segment (start 96.096211 101.01844) (end 96.096211 100.419433) (width 0.125) (layer "B.Cu") (net 260))
  (segment (start 92.698223 98.875) (end 92.356066 99.217157) (width 0.125) (layer "B.Cu") (net 260))
  (segment (start 94.551778 98.875) (end 92.698223 98.875) (width 0.125) (layer "B.Cu") (net 260))
  (via (at 92.532843 99.782843) (size 0.6) (drill 0.25) (layers "F.Cu" "B.Cu") (net 261))
  (segment (start 70.19731 133.6625) (end 84.06731 133.6625) (width 0.125) (layer "In2.Cu") (net 261))
  (segment (start 69.93 133.92981) (end 70.19731 133.6625) (width 0.125) (layer "In2.Cu") (net 261))
  (segment (start 69.93 136.24) (end 69.93 133.92981) (width 0.125) (layer "In2.Cu") (net 261))
  (segment (start 90.1625 127.56731) (end 90.1625 118.56731) (width 0.125) (layer "In2.Cu") (net 261))
  (segment (start 84.06731 133.6625) (end 90.1625 127.56731) (width 0.125) (layer "In2.Cu") (net 261))
  (segment (start 91.6625 100.31731) (end 92.196967 99.782843) (width 0.125) (layer "In2.Cu") (net 261))
  (segment (start 92.196967 99.782843) (end 92.532843 99.782843) (width 0.125) (layer "In2.Cu") (net 261))
  (segment (start 90.1625 118.56731) (end 91.6625 117.06731) (width 0.125) (layer "In2.Cu") (net 261))
  (segment (start 91.6625 117.06731) (end 91.6625 100.31731) (width 0.125) (layer "In2.Cu") (net 261))
  (segment (start 95.846211 100.522989) (end 94.448222 99.125) (width 0.125) (layer "B.Cu") (net 261))
  (segment (start 95.846211 101.01844) (end 95.846211 100.522989) (width 0.125) (layer "B.Cu") (net 261))
  (segment (start 94.448222 99.125) (end 92.801777 99.125) (width 0.125) (layer "B.Cu") (net 261))
  (segment (start 95.771211 101.09344) (end 95.846211 101.01844) (width 0.125) (layer "B.Cu") (net 261))
  (segment (start 92.532843 99.393934) (end 92.532843 99.782843) (width 0.125) (layer "B.Cu") (net 261))
  (segment (start 92.801777 99.125) (end 92.532843 99.393934) (width 0.125) (layer "B.Cu") (net 261))
  (via (at 97.9 106.1) (size 0.6) (drill 0.25) (layers "F.Cu" "B.Cu") (net 262))
  (segment (start 91.4 134.4) (end 91.4 119.2) (width 0.15) (layer "In2.Cu") (net 262))
  (segment (start 87.977587 138.233491) (end 85.437585 138.233491) (width 0.15) (layer "In2.Cu") (net 262))
  (segment (start 91.4 134.4) (end 91.4 134.811078) (width 0.15) (layer "In2.Cu") (net 262))
  (segment (start 85.437585 138.233491) (end 84.171076 139.5) (width 0.15) (layer "In2.Cu") (net 262))
  (segment (start 92.9 113.1) (end 93.65 112.35) (width 0.15) (layer "In2.Cu") (net 262))
  (segment (start 91.4 134.4) (end 91.4 134.7) (width 0.15) (layer "In2.Cu") (net 262))
  (segment (start 71.940002 145.6) (end 71.110004 145.6) (width 0.15) (layer "In2.Cu") (net 262))
  (segment (start 97.9 106.4) (end 97.9 106.1) (width 0.15) (layer "In2.Cu") (net 262))
  (segment (start 98.1 106.6) (end 97.9 106.4) (width 0.15) (layer "In2.Cu") (net 262))
  (segment (start 98.1 112.1) (end 98.1 106.6) (width 0.15) (layer "In2.Cu") (net 262))
  (segment (start 97.85 112.35) (end 98.1 112.1) (width 0.15) (layer "In2.Cu") (net 262))
  (segment (start 70.855002 145.855002) (end 70.855002 146.659999) (width 0.15) (layer "In2.Cu") (net 262))
  (segment (start 92.9 117.7) (end 92.9 113.1) (width 0.15) (layer "In2.Cu") (net 262))
  (segment (start 91.4 134.811078) (end 87.977587 138.233491) (width 0.15) (layer "In2.Cu") (net 262))
  (segment (start 74.8 139.5) (end 74.1 140.2) (width 0.15) (layer "In2.Cu") (net 262))
  (segment (start 74.1 143.440002) (end 71.940002 145.6) (width 0.15) (layer "In2.Cu") (net 262))
  (segment (start 74.1 140.2) (end 74.1 143.440002) (width 0.15) (layer "In2.Cu") (net 262))
  (segment (start 91.4 119.2) (end 92.9 117.7) (width 0.15) (layer "In2.Cu") (net 262))
  (segment (start 84.171076 139.5) (end 74.8 139.5) (width 0.15) (layer "In2.Cu") (net 262))
  (segment (start 71.110004 145.6) (end 70.855002 145.855002) (width 0.15) (layer "In2.Cu") (net 262))
  (segment (start 93.65 112.35) (end 97.85 112.35) (width 0.15) (layer "In2.Cu") (net 262))
  (segment (start 97.771211 105.971211) (end 97.9 106.1) (width 0.15) (layer "B.Cu") (net 262))
  (segment (start 97.771211 105.10344) (end 97.771211 105.971211) (width 0.15) (layer "B.Cu") (net 262))
  (via (at 98.625003 106.1) (size 0.6) (drill 0.25) (layers "F.Cu" "B.Cu") (net 263))
  (segment (start 91.67501 119.313912) (end 93.17501 117.813912) (width 0.15) (layer "In2.Cu") (net 263))
  (segment (start 85.551497 138.508501) (end 84.259998 139.8) (width 0.15) (layer "In2.Cu") (net 263))
  (segment (start 74.9 139.8) (end 74.37501 140.32499) (width 0.15) (layer "In2.Cu") (net 263))
  (segment (start 69.6 145.1) (end 69.3 144.8) (width 0.15) (layer "In2.Cu") (net 263))
  (segment (start 93.755559 112.694461) (end 98.005539 112.694461) (width 0.15) (layer "In2.Cu") (net 263))
  (segment (start 60.4 144.8) (end 60.114998 145.085002) (width 0.15) (layer "In2.Cu") (net 263))
  (segment (start 98.625003 106.374997) (end 98.625003 106.1) (width 0.15) (layer "In2.Cu") (net 263))
  (segment (start 98.4 112.3) (end 98.4 106.6) (width 0.15) (layer "In2.Cu") (net 263))
  (segment (start 91.67501 134.92499) (end 88.091499 138.508501) (width 0.15) (layer "In2.Cu") (net 263))
  (segment (start 93.17501 113.27501) (end 93.755559 112.694461) (width 0.15) (layer "In2.Cu") (net 263))
  (segment (start 93.17501 117.813912) (end 93.17501 113.27501) (width 0.15) (layer "In2.Cu") (net 263))
  (segment (start 69.6 147.4) (end 69.6 145.1) (width 0.15) (layer "In2.Cu") (net 263))
  (segment (start 70.1 147.9) (end 69.6 147.4) (width 0.15) (layer "In2.Cu") (net 263))
  (segment (start 72.114462 147.485538) (end 71.7 147.9) (width 0.15) (layer "In2.Cu") (net 263))
  (segment (start 91.67501 134.52499) (end 91.67501 119.313912) (width 0.15) (layer "In2.Cu") (net 263))
  (segment (start 88.091499 138.508501) (end 85.551497 138.508501) (width 0.15) (layer "In2.Cu") (net 263))
  (segment (start 91.67501 134.52499) (end 91.67501 134.92499) (width 0.15) (layer "In2.Cu") (net 263))
  (segment (start 69.3 144.8) (end 60.4 144.8) (width 0.15) (layer "In2.Cu") (net 263))
  (segment (start 91.67501 134.813912) (end 91.67501 134.52499) (width 0.15) (layer "In2.Cu") (net 263))
  (segment (start 74.37501 143.553914) (end 72.114462 145.814462) (width 0.15) (layer "In2.Cu") (net 263))
  (segment (start 98.4 106.6) (end 98.625003 106.374997) (width 0.15) (layer "In2.Cu") (net 263))
  (segment (start 74.37501 140.32499) (end 74.37501 143.553914) (width 0.15) (layer "In2.Cu") (net 263))
  (segment (start 71.7 147.9) (end 70.1 147.9) (width 0.15) (layer "In2.Cu") (net 263))
  (segment (start 98.005539 112.694461) (end 98.4 112.3) (width 0.15) (layer "In2.Cu") (net 263))
  (segment (start 84.259998 139.8) (end 74.9 139.8) (width 0.15) (layer "In2.Cu") (net 263))
  (segment (start 60.114998 145.085002) (end 60.114998 146.659999) (width 0.15) (layer "In2.Cu") (net 263))
  (segment (start 72.114462 145.814462) (end 72.114462 147.485538) (width 0.15) (layer "In2.Cu") (net 263))
  (segment (start 98.571211 106.046208) (end 98.625003 106.1) (width 0.15) (layer "B.Cu") (net 263))
  (segment (start 98.571211 105.10344) (end 98.571211 106.046208) (width 0.15) (layer "B.Cu") (net 263))
  (segment (start 116.25 145.4925) (end 116.25 144.74) (width 0.182) (layer "F.Cu") (net 264))
  (via (at 108.6 145.4) (size 0.6) (drill 0.25) (layers "F.Cu" "B.Cu") (net 264))
  (via (at 116.2 145.6) (size 0.6) (drill 0.25) (layers "F.Cu" "B.Cu") (net 264))
  (segment (start 113.9 144.7) (end 113.6 145) (width 0.182) (layer "In2.Cu") (net 264))
  (segment (start 113.6 145) (end 113.6 145.5) (width 0.182) (layer "In2.Cu") (net 264))
  (segment (start 115.8 144.7) (end 113.9 144.7) (width 0.182) (layer "In2.Cu") (net 264))
  (segment (start 116.2 145.1) (end 115.8 144.7) (width 0.182) (layer "In2.Cu") (net 264))
  (segment (start 116.2 145.6) (end 116.2 145.1) (width 0.182) (layer "In2.Cu") (net 264))
  (segment (start 113.6 147) (end 113.6 145.5) (width 0.182) (layer "In2.Cu") (net 264))
  (segment (start 113.1 147.5) (end 113.6 147) (width 0.182) (layer "In2.Cu") (net 264))
  (segment (start 109.1 147.5) (end 113.1 147.5) (width 0.182) (layer "In2.Cu") (net 264))
  (segment (start 108.6 147) (end 109.1 147.5) (width 0.182) (layer "In2.Cu") (net 264))
  (segment (start 108.6 145.4) (end 108.6 147) (width 0.182) (layer "In2.Cu") (net 264))
  (segment (start 108.55 144.75) (end 108.55 145.35) (width 0.15) (layer "B.Cu") (net 264))
  (segment (start 115 142.3075) (end 115 143.04) (width 0.182) (layer "F.Cu") (net 265))
  (via (at 109.5475 145.4) (size 0.6) (drill 0.25) (layers "F.Cu" "B.Cu") (net 265))
  (via (at 115 142.3075) (size 0.6) (drill 0.25) (layers "F.Cu" "B.Cu") (net 265))
  (segment (start 109.9 147.1) (end 109.5475 146.7475) (width 0.182) (layer "In2.Cu") (net 265))
  (segment (start 109.5475 146.7475) (end 109.5475 145.4) (width 0.182) (layer "In2.Cu") (net 265))
  (segment (start 112.9 147.1) (end 109.9 147.1) (width 0.182) (layer "In2.Cu") (net 265))
  (segment (start 113.2 146.8) (end 112.9 147.1) (width 0.182) (layer "In2.Cu") (net 265))
  (segment (start 113.2 144.6) (end 113.2 146.8) (width 0.182) (layer "In2.Cu") (net 265))
  (segment (start 115 142.8) (end 113.2 144.6) (width 0.182) (layer "In2.Cu") (net 265))
  (segment (start 115 142.3075) (end 115 142.8) (width 0.182) (layer "In2.Cu") (net 265))
  (segment (start 109.55 144.75) (end 109.55 145.3975) (width 0.155) (layer "B.Cu") (net 265))
  (segment (start 105.94 93.224999) (end 105.825 93.109999) (width 0.125) (layer "B.Cu") (net 266))
  (segment (start 105.25 87.800001) (end 105.25 86.9) (width 0.125) (layer "B.Cu") (net 266))
  (segment (start 105.825 89.148222) (end 105.125 88.448222) (width 0.125) (layer "B.Cu") (net 266))
  (segment (start 105.94 93.45) (end 105.94 93.224999) (width 0.125) (layer "B.Cu") (net 266))
  (segment (start 105.125 88.448222) (end 105.125 87.925001) (width 0.125) (layer "B.Cu") (net 266))
  (segment (start 105.825 93.109999) (end 105.825 89.148222) (width 0.125) (layer "B.Cu") (net 266))
  (segment (start 105.125 87.925001) (end 105.25 87.800001) (width 0.125) (layer "B.Cu") (net 266))
  (segment (start 105.575 89.251778) (end 104.875 88.551778) (width 0.125) (layer "B.Cu") (net 267))
  (segment (start 105.46 93.45) (end 105.46 93.224999) (width 0.125) (layer "B.Cu") (net 267))
  (segment (start 104.875 87.925001) (end 104.75 87.800001) (width 0.125) (layer "B.Cu") (net 267))
  (segment (start 104.875 88.551778) (end 104.875 87.925001) (width 0.125) (layer "B.Cu") (net 267))
  (segment (start 105.46 93.224999) (end 105.575 93.109999) (width 0.125) (layer "B.Cu") (net 267))
  (segment (start 104.75 87.800001) (end 104.75 86.9) (width 0.125) (layer "B.Cu") (net 267))
  (segment (start 105.575 93.109999) (end 105.575 89.251778) (width 0.125) (layer "B.Cu") (net 267))
  (segment (start 96.425 92.548222) (end 96.425 93.109999) (width 0.125) (layer "B.Cu") (net 268))
  (segment (start 96.25 87.800001) (end 96.125 87.925001) (width 0.125) (layer "B.Cu") (net 268))
  (segment (start 96.425 93.109999) (end 96.54 93.224999) (width 0.125) (layer "B.Cu") (net 268))
  (segment (start 96.54 93.224999) (end 96.54 93.45) (width 0.125) (layer "B.Cu") (net 268))
  (segment (start 96.125 87.925001) (end 96.125 92.248222) (width 0.125) (layer "B.Cu") (net 268))
  (segment (start 96.25 86.9) (end 96.25 87.800001) (width 0.125) (layer "B.Cu") (net 268))
  (segment (start 96.125 92.248222) (end 96.425 92.548222) (width 0.125) (layer "B.Cu") (net 268))
  (segment (start 95.875 87.925001) (end 95.875 92.351778) (width 0.125) (layer "B.Cu") (net 269))
  (segment (start 95.875 92.351778) (end 96.175 92.651778) (width 0.125) (layer "B.Cu") (net 269))
  (segment (start 96.175 93.109999) (end 96.06 93.224999) (width 0.125) (layer "B.Cu") (net 269))
  (segment (start 96.06 93.224999) (end 96.06 93.45) (width 0.125) (layer "B.Cu") (net 269))
  (segment (start 95.75 86.9) (end 95.75 87.800001) (width 0.125) (layer "B.Cu") (net 269))
  (segment (start 96.175 92.651778) (end 96.175 93.109999) (width 0.125) (layer "B.Cu") (net 269))
  (segment (start 95.75 87.800001) (end 95.875 87.925001) (width 0.125) (layer "B.Cu") (net 269))
  (segment (start 104.525 93.109999) (end 104.64 93.224999) (width 0.125) (layer "B.Cu") (net 270))
  (segment (start 104.525 90.448222) (end 104.525 93.109999) (width 0.125) (layer "B.Cu") (net 270))
  (segment (start 104.125 87.925001) (end 104.125 90.048222) (width 0.125) (layer "B.Cu") (net 270))
  (segment (start 104.64 93.224999) (end 104.64 93.45) (width 0.125) (layer "B.Cu") (net 270))
  (segment (start 104.125 90.048222) (end 104.525 90.448222) (width 0.125) (layer "B.Cu") (net 270))
  (segment (start 104.25 87.800001) (end 104.125 87.925001) (width 0.125) (layer "B.Cu") (net 270))
  (segment (start 104.25 86.9) (end 104.25 87.800001) (width 0.125) (layer "B.Cu") (net 270))
  (segment (start 103.75 86.9) (end 103.75 87.800001) (width 0.125) (layer "B.Cu") (net 271))
  (segment (start 104.275 90.551778) (end 104.275 93.109999) (width 0.125) (layer "B.Cu") (net 271))
  (segment (start 104.275 93.109999) (end 104.16 93.224999) (width 0.125) (layer "B.Cu") (net 271))
  (segment (start 103.875 87.925001) (end 103.875 90.151778) (width 0.125) (layer "B.Cu") (net 271))
  (segment (start 104.16 93.224999) (end 104.16 93.45) (width 0.125) (layer "B.Cu") (net 271))
  (segment (start 103.75 87.800001) (end 103.875 87.925001) (width 0.125) (layer "B.Cu") (net 271))
  (segment (start 103.875 90.151778) (end 104.275 90.551778) (width 0.125) (layer "B.Cu") (net 271))
  (segment (start 95.25 87.800001) (end 95.125 87.925001) (width 0.125) (layer "B.Cu") (net 272))
  (segment (start 95.25 86.9) (end 95.25 87.800001) (width 0.125) (layer "B.Cu") (net 272))
  (segment (start 95.24 93.224999) (end 95.24 93.45) (width 0.125) (layer "B.Cu") (net 272))
  (segment (start 95.125 87.925001) (end 95.125 93.109999) (width 0.125) (layer "B.Cu") (net 272))
  (segment (start 95.125 93.109999) (end 95.24 93.224999) (width 0.125) (layer "B.Cu") (net 272))
  (segment (start 94.875 87.925001) (end 94.875 93.109999) (width 0.125) (layer "B.Cu") (net 273))
  (segment (start 94.76 93.224999) (end 94.76 93.45) (width 0.125) (layer "B.Cu") (net 273))
  (segment (start 94.875 93.109999) (end 94.76 93.224999) (width 0.125) (layer "B.Cu") (net 273))
  (segment (start 94.75 87.800001) (end 94.875 87.925001) (width 0.125) (layer "B.Cu") (net 273))
  (segment (start 94.75 86.9) (end 94.75 87.800001) (width 0.125) (layer "B.Cu") (net 273))
  (segment (start 97.725 92.048222) (end 97.725 93.109999) (width 0.125) (layer "B.Cu") (net 274))
  (segment (start 97.625 91.948222) (end 97.725 92.048222) (width 0.125) (layer "B.Cu") (net 274))
  (segment (start 97.725 93.109999) (end 97.84 93.224999) (width 0.125) (layer "B.Cu") (net 274))
  (segment (start 97.75 87.800001) (end 97.625 87.925001) (width 0.125) (layer "B.Cu") (net 274))
  (segment (start 97.625 87.925001) (end 97.625 91.948222) (width 0.125) (layer "B.Cu") (net 274))
  (segment (start 97.84 93.224999) (end 97.84 93.45) (width 0.125) (layer "B.Cu") (net 274))
  (segment (start 97.75 86.9) (end 97.75 87.800001) (width 0.125) (layer "B.Cu") (net 274))
  (segment (start 97.475 93.109999) (end 97.36 93.224999) (width 0.125) (layer "B.Cu") (net 275))
  (segment (start 97.25 87.800001) (end 97.375 87.925001) (width 0.125) (layer "B.Cu") (net 275))
  (segment (start 97.36 93.224999) (end 97.36 93.45) (width 0.125) (layer "B.Cu") (net 275))
  (segment (start 97.25 86.9) (end 97.25 87.800001) (width 0.125) (layer "B.Cu") (net 275))
  (segment (start 97.475 92.151778) (end 97.475 93.109999) (width 0.125) (layer "B.Cu") (net 275))
  (segment (start 97.375 87.925001) (end 97.375 92.051778) (width 0.125) (layer "B.Cu") (net 275))
  (segment (start 97.375 92.051778) (end 97.475 92.151778) (width 0.125) (layer "B.Cu") (net 275))
  (segment (start 103.34 93.45) (end 103.34 93.224999) (width 0.125) (layer "B.Cu") (net 276))
  (segment (start 103.125 87.925001) (end 103.25 87.800001) (width 0.125) (layer "B.Cu") (net 276))
  (segment (start 103.125 88.648222) (end 103.125 87.925001) (width 0.125) (layer "B.Cu") (net 276))
  (segment (start 103.25 87.800001) (end 103.25 86.9) (width 0.125) (layer "B.Cu") (net 276))
  (segment (start 103.225 93.109999) (end 103.225 88.748222) (width 0.125) (layer "B.Cu") (net 276))
  (segment (start 103.34 93.224999) (end 103.225 93.109999) (width 0.125) (layer "B.Cu") (net 276))
  (segment (start 103.225 88.748222) (end 103.125 88.648222) (width 0.125) (layer "B.Cu") (net 276))
  (segment (start 102.975 88.851778) (end 102.875 88.751778) (width 0.125) (layer "B.Cu") (net 277))
  (segment (start 102.75 87.800001) (end 102.75 86.9) (width 0.125) (layer "B.Cu") (net 277))
  (segment (start 102.875 88.751778) (end 102.875 87.925001) (width 0.125) (layer "B.Cu") (net 277))
  (segment (start 102.86 93.224999) (end 102.975 93.109999) (width 0.125) (layer "B.Cu") (net 277))
  (segment (start 102.975 93.109999) (end 102.975 88.851778) (width 0.125) (layer "B.Cu") (net 277))
  (segment (start 102.875 87.925001) (end 102.75 87.800001) (width 0.125) (layer "B.Cu") (net 277))
  (segment (start 102.86 93.45) (end 102.86 93.224999) (width 0.125) (layer "B.Cu") (net 277))
  (segment (start 94.25 87.800001) (end 94.125 87.925001) (width 0.125) (layer "B.Cu") (net 278))
  (segment (start 93.94 93.224999) (end 93.94 93.45) (width 0.125) (layer "B.Cu") (net 278))
  (segment (start 94.125 92.151778) (end 93.825 92.451778) (width 0.125) (layer "B.Cu") (net 278))
  (segment (start 94.125 87.925001) (end 94.125 92.151778) (width 0.125) (layer "B.Cu") (net 278))
  (segment (start 94.25 86.9) (end 94.25 87.800001) (width 0.125) (layer "B.Cu") (net 278))
  (segment (start 93.825 93.109999) (end 93.94 93.224999) (width 0.125) (layer "B.Cu") (net 278))
  (segment (start 93.825 92.451778) (end 93.825 93.109999) (width 0.125) (layer "B.Cu") (net 278))
  (segment (start 93.875 87.925001) (end 93.875 92.048222) (width 0.125) (layer "B.Cu") (net 279))
  (segment (start 93.575 93.109999) (end 93.46 93.224999) (width 0.125) (layer "B.Cu") (net 279))
  (segment (start 93.875 92.048222) (end 93.575 92.348222) (width 0.125) (layer "B.Cu") (net 279))
  (segment (start 93.75 86.9) (end 93.75 87.800001) (width 0.125) (layer "B.Cu") (net 279))
  (segment (start 93.575 92.348222) (end 93.575 93.109999) (width 0.125) (layer "B.Cu") (net 279))
  (segment (start 93.46 93.224999) (end 93.46 93.45) (width 0.125) (layer "B.Cu") (net 279))
  (segment (start 93.75 87.800001) (end 93.875 87.925001) (width 0.125) (layer "B.Cu") (net 279))
  (segment (start 102.125 87.925001) (end 102.125 92.051778) (width 0.125) (layer "B.Cu") (net 280))
  (segment (start 102.125 92.051778) (end 101.925 92.251778) (width 0.125) (layer "B.Cu") (net 280))
  (segment (start 102.04 93.224999) (end 102.04 93.45) (width 0.125) (layer "B.Cu") (net 280))
  (segment (start 102.25 87.800001) (end 102.125 87.925001) (width 0.125) (layer "B.Cu") (net 280))
  (segment (start 102.25 86.9) (end 102.25 87.800001) (width 0.125) (layer "B.Cu") (net 280))
  (segment (start 101.925 93.109999) (end 102.04 93.224999) (width 0.125) (layer "B.Cu") (net 280))
  (segment (start 101.925 92.251778) (end 101.925 93.109999) (width 0.125) (layer "B.Cu") (net 280))
  (segment (start 101.875 87.925001) (end 101.875 91.948222) (width 0.125) (layer "B.Cu") (net 281))
  (segment (start 101.675 92.148222) (end 101.675 93.109999) (width 0.125) (layer "B.Cu") (net 281))
  (segment (start 101.875 91.948222) (end 101.675 92.148222) (width 0.125) (layer "B.Cu") (net 281))
  (segment (start 101.675 93.109999) (end 101.56 93.224999) (width 0.125) (layer "B.Cu") (net 281))
  (segment (start 101.75 86.9) (end 101.75 87.800001) (width 0.125) (layer "B.Cu") (net 281))
  (segment (start 101.75 87.800001) (end 101.875 87.925001) (width 0.125) (layer "B.Cu") (net 281))
  (segment (start 101.56 93.224999) (end 101.56 93.45) (width 0.125) (layer "B.Cu") (net 281))
  (segment (start 93.125 87.925001) (end 93.125 91.651778) (width 0.125) (layer "B.Cu") (net 282))
  (segment (start 92.64 93.224999) (end 92.64 93.45) (width 0.125) (layer "B.Cu") (net 282))
  (segment (start 92.525 92.251778) (end 92.525 93.109999) (width 0.125) (layer "B.Cu") (net 282))
  (segment (start 92.525 93.109999) (end 92.64 93.224999) (width 0.125) (layer "B.Cu") (net 282))
  (segment (start 93.25 86.9) (end 93.25 87.800001) (width 0.125) (layer "B.Cu") (net 282))
  (segment (start 93.25 87.800001) (end 93.125 87.925001) (width 0.125) (layer "B.Cu") (net 282))
  (segment (start 93.125 91.651778) (end 92.525 92.251778) (width 0.125) (layer "B.Cu") (net 282))
  (segment (start 92.875 91.548222) (end 92.275 92.148222) (width 0.125) (layer "B.Cu") (net 283))
  (segment (start 92.75 86.9) (end 92.75 87.800001) (width 0.125) (layer "B.Cu") (net 283))
  (segment (start 92.875 87.925001) (end 92.875 91.548222) (width 0.125) (layer "B.Cu") (net 283))
  (segment (start 92.275 92.148222) (end 92.275 93.109999) (width 0.125) (layer "B.Cu") (net 283))
  (segment (start 92.16 93.224999) (end 92.16 93.45) (width 0.125) (layer "B.Cu") (net 283))
  (segment (start 92.75 87.800001) (end 92.875 87.925001) (width 0.125) (layer "B.Cu") (net 283))
  (segment (start 92.275 93.109999) (end 92.16 93.224999) (width 0.125) (layer "B.Cu") (net 283))
  (segment (start 136.2 124.4) (end 135.7 123.9) (width 0.125) (layer "F.Cu") (net 284))
  (segment (start 135.291425 123.491425) (end 135.7 123.9) (width 0.125) (layer "F.Cu") (net 284))
  (segment (start 134.873164 123.491425) (end 135.291425 123.491425) (width 0.125) (layer "F.Cu") (net 284))
  (segment (start 137.47322 124.4) (end 136.2 124.4) (width 0.125) (layer "F.Cu") (net 284))
  (via (at 135.7 123.9) (size 0.6) (drill 0.25) (layers "F.Cu" "B.Cu") (net 284))
  (via (at 122.202158 113.796762) (size 0.6) (drill 0.25) (layers "F.Cu" "B.Cu") (net 284))
  (via (at 136 120) (size 0.6) (drill 0.25) (layers "F.Cu" "B.Cu") (net 284))
  (segment (start 123.440002 115.8) (end 123.2 115.559998) (width 0.15) (layer "In2.Cu") (net 284))
  (segment (start 130.4 116.5) (end 129.7 115.8) (width 0.15) (layer "In2.Cu") (net 284))
  (segment (start 123.2 115.559998) (end 123.2 114.093524) (width 0.15) (layer "In2.Cu") (net 284))
  (segment (start 123.2 114.093524) (end 122.903238 113.796762) (width 0.15) (layer "In2.Cu") (net 284))
  (segment (start 129.7 115.8) (end 123.440002 115.8) (width 0.15) (layer "In2.Cu") (net 284))
  (segment (start 135.684999 119.184999) (end 133.373921 119.184999) (width 0.15) (layer "In2.Cu") (net 284))
  (segment (start 122.903238 113.796762) (end 122.202158 113.796762) (width 0.15) (layer "In2.Cu") (net 284))
  (segment (start 130.4 117.871245) (end 130.4 116.5) (width 0.15) (layer "In2.Cu") (net 284))
  (segment (start 133.373921 119.184999) (end 132.513912 118.32499) (width 0.15) (layer "In2.Cu") (net 284))
  (segment (start 130.853745 118.32499) (end 130.4 117.871245) (width 0.15) (layer "In2.Cu") (net 284))
  (segment (start 136 119.5) (end 135.684999 119.184999) (width 0.15) (layer "In2.Cu") (net 284))
  (segment (start 132.513912 118.32499) (end 130.853745 118.32499) (width 0.15) (layer "In2.Cu") (net 284))
  (segment (start 136 120) (end 136 119.5) (width 0.15) (layer "In2.Cu") (net 284))
  (segment (start 135.400001 123.600001) (end 135.7 123.9) (width 0.125) (layer "In3.Cu") (net 284))
  (segment (start 136 120) (end 135.400001 120.599999) (width 0.125) (layer "In3.Cu") (net 284))
  (segment (start 135.400001 120.599999) (end 135.400001 123.600001) (width 0.125) (layer "In3.Cu") (net 284))
  (segment (start 121.820396 113.415) (end 122.202158 113.796762) (width 0.125) (layer "B.Cu") (net 284))
  (segment (start 120.8 113.415) (end 121.820396 113.415) (width 0.125) (layer "B.Cu") (net 284))
  (segment (start 140.2 120.8) (end 139.8 120.4) (width 0.15) (layer "B.Cu") (net 284))
  (segment (start 139.2 120.4) (end 138.8 120) (width 0.15) (layer "B.Cu") (net 284))
  (segment (start 119.75 113.6) (end 120.615 113.6) (width 0.2) (layer "B.Cu") (net 284))
  (segment (start 140.2 123.5508) (end 140.2 120.8) (width 0.15) (layer "B.Cu") (net 284))
  (segment (start 138.8 120) (end 136 120) (width 0.15) (layer "B.Cu") (net 284))
  (segment (start 139.8 120.4) (end 139.2 120.4) (width 0.15) (layer "B.Cu") (net 284))
  (segment (start 135.8 124.8) (end 135.7 124.7) (width 0.125) (layer "F.Cu") (net 285))
  (segment (start 137.47322 124.8) (end 135.8 124.8) (width 0.125) (layer "F.Cu") (net 285))
  (via (at 136.9 138.4) (size 0.6) (drill 0.25) (layers "F.Cu" "B.Cu") (net 285))
  (via (at 135.7 124.7) (size 0.6) (drill 0.25) (layers "F.Cu" "B.Cu") (net 285))
  (segment (start 135.5 128.928498) (end 135.5 130.146434) (width 0.125) (layer "In2.Cu") (net 285))
  (segment (start 136.9 134) (end 136.9 138.4) (width 0.125) (layer "In2.Cu") (net 285))
  (segment (start 136.4 128.028498) (end 135.5 128.928498) (width 0.125) (layer "In2.Cu") (net 285))
  (segment (start 135.5 130.146434) (end 134.9 130.746434) (width 0.125) (layer "In2.Cu") (net 285))
  (segment (start 134.9 132) (end 136.9 134) (width 0.125) (layer "In2.Cu") (net 285))
  (segment (start 134.9 130.746434) (end 134.9 132) (width 0.125) (layer "In2.Cu") (net 285))
  (segment (start 136.4 125.4) (end 136.4 128.028498) (width 0.125) (layer "In2.Cu") (net 285))
  (segment (start 135.7 124.7) (end 136.4 125.4) (width 0.125) (layer "In2.Cu") (net 285))
  (segment (start 136.2 124.7) (end 136.6 125.1) (width 0.15) (layer "B.Cu") (net 285))
  (segment (start 139.35 125.8) (end 141.2492 125.8) (width 0.15) (layer "B.Cu") (net 285))
  (segment (start 136.6 125.1) (end 138.65 125.1) (width 0.15) (layer "B.Cu") (net 285))
  (segment (start 136.9 143.9) (end 138.1 145.1) (width 0.15) (layer "B.Cu") (net 285))
  (segment (start 135.7 124.7) (end 136.2 124.7) (width 0.15) (layer "B.Cu") (net 285))
  (segment (start 136.9 138.4) (end 136.9 143.9) (width 0.15) (layer "B.Cu") (net 285))
  (segment (start 141.2492 125.8) (end 142 126.5508) (width 0.15) (layer "B.Cu") (net 285))
  (segment (start 138.65 125.1) (end 139.35 125.8) (width 0.15) (layer "B.Cu") (net 285))
  (segment (start 139.25 145.065) (end 138.135 145.065) (width 0.15) (layer "B.Cu") (net 285))
  (segment (start 100.201561 102.55) (end 100.351561 102.7) (width 0.23) (layer "F.Cu") (net 286))
  (segment (start 99.5 102.55) (end 100.201561 102.55) (width 0.23) (layer "F.Cu") (net 286))
  (via (at 104 103.4) (size 0.6) (drill 0.25) (layers "F.Cu" "B.Cu") (net 286))
  (via (at 100.351561 102.7) (size 0.6) (drill 0.25) (layers "F.Cu" "B.Cu") (net 286))
  (segment (start 100.396795 102.745234) (end 103.345234 102.745234) (width 0.125) (layer "In1.Cu") (net 286))
  (segment (start 100.351561 102.7) (end 100.396795 102.745234) (width 0.125) (layer "In1.Cu") (net 286))
  (segment (start 103.345234 102.745234) (end 104 103.4) (width 0.125) (layer "In1.Cu") (net 286))
  (segment (start 99.176211 102.89844) (end 100.153121 102.89844) (width 0.23) (layer "B.Cu") (net 286))
  (segment (start 100.153121 102.89844) (end 100.351561 102.7) (width 0.23) (layer "B.Cu") (net 286))
  (segment (start 100.793827 102.257734) (end 100.351561 102.7) (width 0.23) (layer "B.Cu") (net 286))
  (segment (start 101.064173 102.257734) (end 100.793827 102.257734) (width 0.23) (layer "B.Cu") (net 286))
  (segment (start 105 103.2508) (end 104.1492 103.2508) (width 0.125) (layer "B.Cu") (net 286))
  (segment (start 104.1492 103.2508) (end 104 103.4) (width 0.125) (layer "B.Cu") (net 286))
  (segment (start 132.8 107.8) (end 132.8 113.2) (width 0.15) (layer "F.Cu") (net 287))
  (segment (start 134.873164 121.491425) (end 135.391424 121.491425) (width 0.15) (layer "F.Cu") (net 287))
  (segment (start 136.299999 122.4) (end 136 122.100001) (width 0.15) (layer "F.Cu") (net 287))
  (segment (start 137.47322 122.4) (end 136.299999 122.4) (width 0.15) (layer "F.Cu") (net 287))
  (segment (start 132.279395 113.720605) (end 131.86635 114.13365) (width 0.15) (layer "F.Cu") (net 287))
  (segment (start 134.575009 107.424991) (end 133.175009 107.424991) (width 0.15) (layer "F.Cu") (net 287))
  (segment (start 134.85 107.25) (end 134.75 107.25) (width 0.15) (layer "F.Cu") (net 287))
  (segment (start 132.8 113.2) (end 132.279395 113.720605) (width 0.15) (layer "F.Cu") (net 287))
  (segment (start 131.86635 114.13365) (end 131.226348 114.13365) (width 0.15) (layer "F.Cu") (net 287))
  (segment (start 135.391424 121.491425) (end 136 122.100001) (width 0.15) (layer "F.Cu") (net 287))
  (segment (start 134.75 107.25) (end 134.575009 107.424991) (width 0.15) (layer "F.Cu") (net 287))
  (segment (start 133.175009 107.424991) (end 132.8 107.8) (width 0.15) (layer "F.Cu") (net 287))
  (segment (start 131.226348 114.13365) (end 130.8 114.559998) (width 0.15) (layer "F.Cu") (net 287))
  (segment (start 130.8 114.559998) (end 130.8 115.2) (width 0.15) (layer "F.Cu") (net 287))
  (via (at 134.85 107.25) (size 0.6) (drill 0.25) (layers "F.Cu" "B.Cu") (net 287))
  (via (at 130.8 115.2) (size 0.6) (drill 0.25) (layers "F.Cu" "B.Cu") (net 287))
  (via (at 136 122.100001) (size 0.6) (drill 0.25) (layers "F.Cu" "B.Cu") (net 287))
  (segment (start 136 122) (end 136 122.100001) (width 0.15) (layer "In3.Cu") (net 287))
  (segment (start 136.6 120.5) (end 136.22499 120.87501) (width 0.15) (layer "In3.Cu") (net 287))
  (segment (start 136.22499 120.87501) (end 136.22499 121.77501) (width 0.15) (layer "In3.Cu") (net 287))
  (segment (start 136.6 119.8) (end 136.6 120.5) (width 0.15) (layer "In3.Cu") (net 287))
  (segment (start 135.7 119.4) (end 135.340002 119.4) (width 0.15) (layer "In3.Cu") (net 287))
  (segment (start 136.22499 121.77501) (end 136 122) (width 0.15) (layer "In3.Cu") (net 287))
  (segment (start 135.7 119.4) (end 136.2 119.4) (width 0.15) (layer "In3.Cu") (net 287))
  (segment (start 136.2 119.4) (end 136.6 119.8) (width 0.15) (layer "In3.Cu") (net 287))
  (segment (start 131.140002 115.2) (end 130.8 115.2) (width 0.15) (layer "In3.Cu") (net 287))
  (segment (start 135.340002 119.4) (end 131.140002 115.2) (width 0.15) (layer "In3.Cu") (net 287))
  (segment (start 134.3 107.305) (end 134.795 107.305) (width 0.15) (layer "B.Cu") (net 287))
  (segment (start 142 125.0508) (end 141.5746 124.6254) (width 0.15) (layer "B.Cu") (net 287))
  (segment (start 136.400001 122.100001) (end 136.6 122.3) (width 0.15) (layer "B.Cu") (net 287))
  (segment (start 136.8 124.4) (end 141.3492 124.4) (width 0.15) (layer "B.Cu") (net 287))
  (segment (start 134.95 107.15) (end 134.85 107.25) (width 0.15) (layer "B.Cu") (net 287))
  (segment (start 134.795 107.305) (end 134.85 107.25) (width 0.15) (layer "B.Cu") (net 287))
  (segment (start 141.3492 124.4) (end 141.5746 124.6254) (width 0.15) (layer "B.Cu") (net 287))
  (segment (start 136.6 122.3) (end 136.6 124.2) (width 0.15) (layer "B.Cu") (net 287))
  (segment (start 136.6 124.2) (end 136.8 124.4) (width 0.15) (layer "B.Cu") (net 287))
  (segment (start 135.615 107.15) (end 134.95 107.15) (width 0.15) (layer "B.Cu") (net 287))
  (segment (start 136 122.100001) (end 136.400001 122.100001) (width 0.15) (layer "B.Cu") (net 287))
  (segment (start 131.721623 114.7) (end 131.4 114.7) (width 0.15) (layer "F.Cu") (net 288))
  (segment (start 132.418309 114.003314) (end 131.721623 114.7) (width 0.15) (layer "F.Cu") (net 288))
  (segment (start 135.491424 122.491424) (end 136 123) (width 0.15) (layer "F.Cu") (net 288))
  (segment (start 132.418309 113.995615) (end 132.418309 114.003314) (width 0.15) (layer "F.Cu") (net 288))
  (segment (start 134.873164 122.491424) (end 135.491424 122.491424) (width 0.15) (layer "F.Cu") (net 288))
  (segment (start 133.299999 107.700001) (end 133.07501 107.92499) (width 0.15) (layer "F.Cu") (net 288))
  (segment (start 133.07501 107.92499) (end 133.07501 113.338914) (width 0.15) (layer "F.Cu") (net 288))
  (segment (start 137.47322 122.8) (end 136.2 122.8) (width 0.15) (layer "F.Cu") (net 288))
  (segment (start 134.550001 107.700001) (end 133.299999 107.700001) (width 0.15) (layer "F.Cu") (net 288))
  (segment (start 136.2 122.8) (end 136 123) (width 0.15) (layer "F.Cu") (net 288))
  (segment (start 133.07501 113.338914) (end 132.418309 113.995615) (width 0.15) (layer "F.Cu") (net 288))
  (segment (start 134.85 108) (end 134.550001 107.700001) (width 0.15) (layer "F.Cu") (net 288))
  (via (at 134.85 108) (size 0.6) (drill 0.25) (layers "F.Cu" "B.Cu") (net 288))
  (via (at 136 123) (size 0.6) (drill 0.25) (layers "F.Cu" "B.Cu") (net 288))
  (via (at 131.4 114.7) (size 0.6) (drill 0.25) (layers "F.Cu" "B.Cu") (net 288))
  (segment (start 135.453914 119.12499) (end 131.4 115.071076) (width 0.15) (layer "In3.Cu") (net 288))
  (segment (start 131.4 115.071076) (end 131.4 114.7) (width 0.15) (layer "In3.Cu") (net 288))
  (segment (start 135.97501 119.12499) (end 135.453914 119.12499) (width 0.15) (layer "In3.Cu") (net 288))
  (segment (start 136.5 122.5) (end 136 123) (width 0.15) (layer "In3.Cu") (net 288))
  (segment (start 136.87501 119.686088) (end 136.87501 120.613912) (width 0.15) (layer "In3.Cu") (net 288))
  (segment (start 136.87501 120.613912) (end 136.5 120.988922) (width 0.15) (layer "In3.Cu") (net 288))
  (segment (start 135.97501 119.12499) (end 136.313912 119.12499) (width 0.15) (layer "In3.Cu") (net 288))
  (segment (start 136.313912 119.12499) (end 136.87501 119.686088) (width 0.15) (layer "In3.Cu") (net 288))
  (segment (start 136.5 120.988922) (end 136.5 122.5) (width 0.15) (layer "In3.Cu") (net 288))
  (segment (start 134.74 107.89) (end 134.85 108) (width 0.15) (layer "B.Cu") (net 288))
  (segment (start 136.7 124.7) (end 138.85 124.7) (width 0.15) (layer "B.Cu") (net 288))
  (segment (start 136 123) (end 136.299999 123.299999) (width 0.15) (layer "B.Cu") (net 288))
  (segment (start 135 108.15) (end 134.85 108) (width 0.15) (layer "B.Cu") (net 288))
  (segment (start 138.85 124.7) (end 139.2008 125.0508) (width 0.15) (layer "B.Cu") (net 288))
  (segment (start 136.299999 124.299999) (end 136.7 124.7) (width 0.15) (layer "B.Cu") (net 288))
  (segment (start 140.25 125.0508) (end 139.2008 125.0508) (width 0.15) (layer "B.Cu") (net 288))
  (segment (start 134.3 107.89) (end 134.74 107.89) (width 0.15) (layer "B.Cu") (net 288))
  (segment (start 136.299999 123.299999) (end 136.299999 124.299999) (width 0.15) (layer "B.Cu") (net 288))
  (segment (start 135.615 108.15) (end 135 108.15) (width 0.15) (layer "B.Cu") (net 288))
  (segment (start 137.47322 125.2) (end 135.186116 125.2) (width 0.125) (layer "F.Cu") (net 289))
  (segment (start 134.873164 125.512952) (end 134.873164 124.512952) (width 0.125) (layer "F.Cu") (net 289))
  (segment (start 135.186116 125.2) (end 134.873164 125.512952) (width 0.125) (layer "F.Cu") (net 289))
  (segment (start 135.15 125.2) (end 135 125.05) (width 0.15) (layer "F.Cu") (net 289))
  (segment (start 137.47322 125.2) (end 135.15 125.2) (width 0.15) (layer "F.Cu") (net 289))
  (via (at 135 125.05) (size 0.6) (drill 0.25) (layers "F.Cu" "B.Cu") (net 289))
  (segment (start 136.5 125.5) (end 138.5 125.5) (width 0.15) (layer "B.Cu") (net 289))
  (segment (start 138.5 125.5) (end 139.5508 126.5508) (width 0.15) (layer "B.Cu") (net 289))
  (segment (start 136.2 125.2) (end 136.5 125.5) (width 0.15) (layer "B.Cu") (net 289))
  (segment (start 139.5508 126.5508) (end 140.25 126.5508) (width 0.15) (layer "B.Cu") (net 289))
  (segment (start 135.15 125.2) (end 136.2 125.2) (width 0.15) (layer "B.Cu") (net 289))
  (segment (start 135 125.05) (end 135.15 125.2) (width 0.15) (layer "B.Cu") (net 289))
  (via (at 112 142.05) (size 0.6) (drill 0.25) (layers "F.Cu" "B.Cu") (net 290))
  (via (at 118.2 132.5) (size 0.6) (drill 0.25) (layers "F.Cu" "B.Cu") (net 290))
  (segment (start 112.4 138.9) (end 112 139.3) (width 0.15) (layer "In3.Cu") (net 290))
  (segment (start 118.2 138.4) (end 117.7 138.9) (width 0.15) (layer "In3.Cu") (net 290))
  (segment (start 118.2 132.5) (end 118.2 138.4) (width 0.15) (layer "In3.Cu") (net 290))
  (segment (start 117.7 138.9) (end 112.4 138.9) (width 0.15) (layer "In3.Cu") (net 290))
  (segment (start 112 142.05) (end 112 139.3) (width 0.15) (layer "In3.Cu") (net 290))
  (segment (start 110.55 144.75) (end 110.6 144.7) (width 0.155) (layer "B.Cu") (net 290))
  (segment (start 110.6 144.7) (end 110.6 144.6) (width 0.155) (layer "B.Cu") (net 290))
  (segment (start 110.6 144.6) (end 110.925 144.275) (width 0.155) (layer "B.Cu") (net 290))
  (segment (start 112 142.093702) (end 112 142.05) (width 0.155) (layer "B.Cu") (net 290))
  (segment (start 110.925 144.275) (end 110.925 143.168702) (width 0.155) (layer "B.Cu") (net 290))
  (segment (start 110.925 143.168702) (end 112 142.093702) (width 0.155) (layer "B.Cu") (net 290))
  (segment (start 112 141.385) (end 112 142.05) (width 0.155) (layer "B.Cu") (net 290))
  (segment (start 120.085 132.5) (end 120.6 133.015) (width 0.15) (layer "B.Cu") (net 290))
  (segment (start 118.2 132.5) (end 117.7 132.5) (width 0.15) (layer "B.Cu") (net 290))
  (segment (start 112 142.05) (end 112 142.6) (width 0.15) (layer "B.Cu") (net 290))
  (segment (start 118.2 132.5) (end 120.085 132.5) (width 0.15) (layer "B.Cu") (net 290))
  (segment (start 117.5 132.5) (end 117.7 132.5) (width 0.15) (layer "B.Cu") (net 290))
  (segment (start 110.7 138.75) (end 110.7 139.274997) (width 0.155) (layer "F.Cu") (net 291))
  (segment (start 110.7 139.274997) (end 110.925003 139.5) (width 0.155) (layer "F.Cu") (net 291))
  (segment (start 110.8 148.4) (end 110.8 142.55) (width 0.15) (layer "F.Cu") (net 291))
  (segment (start 110.8 142.55) (end 111.25 142.1) (width 0.15) (layer "F.Cu") (net 291))
  (segment (start 110.9 148.5) (end 110.8 148.4) (width 0.15) (layer "F.Cu") (net 291))
  (via (at 111.25 142.1) (size 0.6) (drill 0.25) (layers "F.Cu" "B.Cu") (net 291))
  (via (at 110.925003 139.5) (size 0.6) (drill 0.25) (layers "F.Cu" "B.Cu") (net 291))
  (via (at 110.9 148.5) (size 0.6) (drill 0.25) (layers "F.Cu" "B.Cu") (net 291))
  (segment (start 111.25 139.824997) (end 110.925003 139.5) (width 0.15) (layer "In3.Cu") (net 291))
  (segment (start 111.25 142.1) (end 111.25 139.824997) (width 0.15) (layer "In3.Cu") (net 291))
  (segment (start 110.55 142.75) (end 111.2 142.1) (width 0.155) (layer "B.Cu") (net 291))
  (segment (start 111.2 142.1) (end 111.25 142.1) (width 0.155) (layer "B.Cu") (net 291))
  (segment (start 111 141.385) (end 111 141.85) (width 0.155) (layer "B.Cu") (net 291))
  (segment (start 111 141.85) (end 111.25 142.1) (width 0.155) (layer "B.Cu") (net 291))
  (segment (start 111.2508 147.6) (end 111.2508 148.1492) (width 0.15) (layer "B.Cu") (net 291))
  (segment (start 111.2508 148.1492) (end 110.9 148.5) (width 0.15) (layer "B.Cu") (net 291))
  (segment (start 110.3 138.75) (end 110.3 139.4) (width 0.155) (layer "F.Cu") (net 292))
  (segment (start 110.3 139.4) (end 110.2 139.5) (width 0.155) (layer "F.Cu") (net 292))
  (segment (start 110.45 142.1) (end 110.45 148.05) (width 0.15) (layer "F.Cu") (net 292))
  (segment (start 110.45 148.05) (end 110 148.5) (width 0.15) (layer "F.Cu") (net 292))
  (via (at 110.45 142.1) (size 0.6) (drill 0.25) (layers "F.Cu" "B.Cu") (net 292))
  (via (at 110.2 139.5) (size 0.6) (drill 0.25) (layers "F.Cu" "B.Cu") (net 292))
  (via (at 110 148.5) (size 0.6) (drill 0.25) (layers "F.Cu" "B.Cu") (net 292))
  (segment (start 110.45 142.1) (end 110.45 139.75) (width 0.15) (layer "In3.Cu") (net 292))
  (segment (start 110.45 139.75) (end 110.2 139.5) (width 0.15) (layer "In3.Cu") (net 292))
  (segment (start 110.05 142.85) (end 110.05 142.5) (width 0.155) (layer "B.Cu") (net 292))
  (segment (start 110.05 142.5) (end 110.45 142.1) (width 0.155) (layer "B.Cu") (net 292))
  (segment (start 110 141.385) (end 110 141.65) (width 0.155) (layer "B.Cu") (net 292))
  (segment (start 110 141.65) (end 110.45 142.1) (width 0.155) (layer "B.Cu") (net 292))
  (segment (start 110.0508 148.4492) (end 110 148.5) (width 0.15) (layer "B.Cu") (net 292))
  (segment (start 110.0508 147.6) (end 110.0508 148.4492) (width 0.15) (layer "B.Cu") (net 292))
  (segment (start 114.095 93.080003) (end 114.175003 93) (width 0.15) (layer "F.Cu") (net 293))
  (segment (start 114.175003 93) (end 114.175003 92.459997) (width 0.15) (layer "F.Cu") (net 293))
  (segment (start 114.095 93.55) (end 114.095 93.080003) (width 0.15) (layer "F.Cu") (net 293))
  (via (at 114.175003 93) (size 0.6) (drill 0.25) (layers "F.Cu" "B.Cu") (net 293))
  (segment (start 112.851427 92.048573) (end 112.851427 87.951427) (width 0.15) (layer "B.Cu") (net 293))
  (segment (start 114.175003 93) (end 114.175003 92.125803) (width 0.15) (layer "B.Cu") (net 293))
  (segment (start 112.851427 87.951427) (end 113.25 87.552854) (width 0.15) (layer "B.Cu") (net 293))
  (segment (start 113.034803 92.231949) (end 112.851427 92.048573) (width 0.15) (layer "B.Cu") (net 293))
  (segment (start 114.175003 93) (end 113.406953 92.231949) (width 0.15) (layer "B.Cu") (net 293))
  (segment (start 113.406953 92.231949) (end 113.034803 92.231949) (width 0.15) (layer "B.Cu") (net 293))
  (segment (start 113.25 87.552854) (end 113.25 86.9) (width 0.15) (layer "B.Cu") (net 293))
  (segment (start 110.595 93.55) (end 110.595 93.080003) (width 0.15) (layer "F.Cu") (net 294))
  (segment (start 110.675003 93) (end 110.675003 92.459997) (width 0.15) (layer "F.Cu") (net 294))
  (segment (start 110.595 93.080003) (end 110.675003 93) (width 0.15) (layer "F.Cu") (net 294))
  (via (at 110.675003 93) (size 0.6) (drill 0.25) (layers "F.Cu" "B.Cu") (net 294))
  (segment (start 112.02501 91.313912) (end 112.02501 89.67501) (width 0.15) (layer "B.Cu") (net 294))
  (segment (start 112.02501 87.87499) (end 112.25 87.65) (width 0.15) (layer "B.Cu") (net 294))
  (segment (start 112.25 87.65) (end 112.25 86.9) (width 0.15) (layer "B.Cu") (net 294))
  (segment (start 111.15 92) (end 111.10001 91.95001) (width 0.15) (layer "B.Cu") (net 294))
  (segment (start 111.10001 91.95001) (end 111.388912 91.95001) (width 0.15) (layer "B.Cu") (net 294))
  (segment (start 110.65001 91.95001) (end 111.10001 91.95001) (width 0.15) (layer "B.Cu") (net 294))
  (segment (start 110.47501 92.67501) (end 110.47501 92.12501) (width 0.15) (layer "B.Cu") (net 294))
  (segment (start 111.388912 91.95001) (end 112.02501 91.313912) (width 0.15) (layer "B.Cu") (net 294))
  (segment (start 110.675003 92.875003) (end 110.47501 92.67501) (width 0.15) (layer "B.Cu") (net 294))
  (segment (start 110.47501 92.12501) (end 110.65001 91.95001) (width 0.15) (layer "B.Cu") (net 294))
  (segment (start 112.02501 89.67501) (end 112.02501 87.87499) (width 0.15) (layer "B.Cu") (net 294))
  (segment (start 110.675003 93) (end 110.675003 92.875003) (width 0.15) (layer "B.Cu") (net 294))
  (segment (start 113.51 93.55) (end 113.51 93.06) (width 0.15) (layer "F.Cu") (net 295))
  (segment (start 113.51 93.06) (end 113.45 93) (width 0.15) (layer "F.Cu") (net 295))
  (segment (start 113.45 93) (end 113.45 92.485) (width 0.15) (layer "F.Cu") (net 295))
  (via (at 113.45 93) (size 0.6) (drill 0.25) (layers "F.Cu" "B.Cu") (net 295))
  (segment (start 112.576417 92.162485) (end 112.576417 87.837515) (width 0.15) (layer "B.Cu") (net 295))
  (segment (start 112.920891 92.506959) (end 112.576417 92.162485) (width 0.15) (layer "B.Cu") (net 295))
  (segment (start 113.45 93) (end 113.16 93) (width 0.15) (layer "B.Cu") (net 295))
  (segment (start 112.75 87.663932) (end 112.75 86.9) (width 0.15) (layer "B.Cu") (net 295))
  (segment (start 112.920891 92.760891) (end 112.920891 92.506959) (width 0.15) (layer "B.Cu") (net 295))
  (segment (start 112.576417 87.837515) (end 112.75 87.663932) (width 0.15) (layer "B.Cu") (net 295))
  (segment (start 110.01 93.06) (end 109.95 93) (width 0.15) (layer "F.Cu") (net 296))
  (segment (start 110.01 93.55) (end 110.01 93.06) (width 0.15) (layer "F.Cu") (net 296))
  (segment (start 109.95 93) (end 109.95 92.485) (width 0.15) (layer "F.Cu") (net 296))
  (via (at 109.95 93) (size 0.6) (drill 0.25) (layers "F.Cu" "B.Cu") (net 296))
  (segment (start 110.2 92.7) (end 110.2 92.011098) (width 0.15) (layer "B.Cu") (net 296))
  (segment (start 110.2 92.011098) (end 110.536098 91.675) (width 0.15) (layer "B.Cu") (net 296))
  (segment (start 111.75 86.9) (end 111.75 89.7) (width 0.15) (layer "B.Cu") (net 296))
  (segment (start 111.275 91.675) (end 111.75 91.2) (width 0.15) (layer "B.Cu") (net 296))
  (segment (start 111.75 91.2) (end 111.75 89.7) (width 0.15) (layer "B.Cu") (net 296))
  (segment (start 109.95 92.95) (end 110.2 92.7) (width 0.15) (layer "B.Cu") (net 296))
  (segment (start 109.8 92.1) (end 110.111098 92.1) (width 0.15) (layer "B.Cu") (net 296))
  (segment (start 109.95 93) (end 109.95 92.95) (width 0.15) (layer "B.Cu") (net 296))
  (segment (start 110.536098 91.675) (end 111.275 91.675) (width 0.15) (layer "B.Cu") (net 296))
  (segment (start 110.111098 92.1) (end 110.2 92.011098) (width 0.15) (layer "B.Cu") (net 296))
  (segment (start 137.47322 127.2) (end 136.6 127.2) (width 0.15) (layer "F.Cu") (net 297))
  (segment (start 136.6 127.2) (end 135.687047 128.112953) (width 0.15) (layer "F.Cu") (net 297))
  (segment (start 135.687047 128.112953) (end 134.538164 128.112953) (width 0.15) (layer "F.Cu") (net 297))
  (segment (start 135.327049 126.912953) (end 136.240002 126) (width 0.15) (layer "F.Cu") (net 298))
  (segment (start 136.240002 126) (end 137.47322 126) (width 0.15) (layer "F.Cu") (net 298))
  (segment (start 134.538164 126.912953) (end 135.327049 126.912953) (width 0.15) (layer "F.Cu") (net 298))
  (segment (start 135.387047 127.312953) (end 134.538164 127.312953) (width 0.15) (layer "F.Cu") (net 299))
  (segment (start 137.47322 126.4) (end 136.3 126.4) (width 0.15) (layer "F.Cu") (net 299))
  (segment (start 136.3 126.4) (end 135.387047 127.312953) (width 0.15) (layer "F.Cu") (net 299))
  (segment (start 135.487047 127.712953) (end 134.538164 127.712953) (width 0.15) (layer "F.Cu") (net 300))
  (segment (start 137.47322 126.8) (end 136.4 126.8) (width 0.15) (layer "F.Cu") (net 300))
  (segment (start 136.4 126.8) (end 135.487047 127.712953) (width 0.15) (layer "F.Cu") (net 300))
  (segment (start 109.9 138.75) (end 109.9 139.048574) (width 0.155) (layer "F.Cu") (net 301))
  (segment (start 109.9 139.048574) (end 109.422079 139.526495) (width 0.155) (layer "F.Cu") (net 301))
  (segment (start 109.9 147.9) (end 109 147.9) (width 0.15) (layer "F.Cu") (net 301))
  (segment (start 109 147.9) (end 108.8 148.1) (width 0.15) (layer "F.Cu") (net 301))
  (segment (start 110.1 147.7) (end 109.9 147.9) (width 0.15) (layer "F.Cu") (net 301))
  (segment (start 110.100001 142.700001) (end 110.1 147.7) (width 0.15) (layer "F.Cu") (net 301))
  (segment (start 109.6 142.2) (end 110.100001 142.700001) (width 0.15) (layer "F.Cu") (net 301))
  (segment (start 108.8 148.1) (end 108.8 148.5) (width 0.15) (layer "F.Cu") (net 301))
  (via (at 109.422079 139.526495) (size 0.6) (drill 0.25) (layers "F.Cu" "B.Cu") (net 301))
  (via (at 109.6 142.2) (size 0.6) (drill 0.25) (layers "F.Cu" "B.Cu") (net 301))
  (via (at 108.8 148.5) (size 0.6) (drill 0.25) (layers "F.Cu" "B.Cu") (net 301))
  (segment (start 109.6 142.2) (end 109.6 139.704416) (width 0.15) (layer "In3.Cu") (net 301))
  (segment (start 109.6 139.704416) (end 109.422079 139.526495) (width 0.15) (layer "In3.Cu") (net 301))
  (segment (start 109.55 142.85) (end 109.55 142.25) (width 0.155) (layer "B.Cu") (net 301))
  (segment (start 109.55 142.25) (end 109.6 142.2) (width 0.155) (layer "B.Cu") (net 301))
  (segment (start 108.8508 148.4492) (end 108.8 148.5) (width 0.15) (layer "B.Cu") (net 301))
  (segment (start 108.8508 147.6) (end 108.8508 148.4492) (width 0.15) (layer "B.Cu") (net 301))
  (segment (start 99.5 143.04) (end 99.5 142.514999) (width 0.155) (layer "F.Cu") (net 302))
  (segment (start 99.5 142.514999) (end 99.61 142.404999) (width 0.155) (layer "F.Cu") (net 302))
  (segment (start 99.61 142.404999) (end 99.61 142.126244) (width 0.155) (layer "F.Cu") (net 302))
  (segment (start 99.61 142.126244) (end 99.3875 141.903744) (width 0.155) (layer "F.Cu") (net 302))
  (via (at 99.3875 141.903744) (size 0.6) (drill 0.25) (layers "F.Cu" "B.Cu") (net 302))
  (segment (start 99.61 139.965) (end 99.61 139.69201) (width 0.155) (layer "B.Cu") (net 302))
  (segment (start 99.61 141.453751) (end 99.5 141.343751) (width 0.155) (layer "B.Cu") (net 302))
  (segment (start 99.3875 141.903744) (end 99.61 141.681244) (width 0.155) (layer "B.Cu") (net 302))
  (segment (start 99.61 141.681244) (end 99.61 141.453751) (width 0.155) (layer "B.Cu") (net 302))
  (segment (start 99.86 139.44201) (end 99.86 138.945) (width 0.155) (layer "B.Cu") (net 302))
  (segment (start 99.61 139.69201) (end 99.86 139.44201) (width 0.155) (layer "B.Cu") (net 302))
  (segment (start 99.86 138.945) (end 99.5 138.585) (width 0.155) (layer "B.Cu") (net 302))
  (segment (start 99.5 141.343751) (end 99.5 140.075) (width 0.155) (layer "B.Cu") (net 302))
  (segment (start 99.5 140.075) (end 99.61 139.965) (width 0.155) (layer "B.Cu") (net 302))
  (segment (start 99.89 142.404999) (end 99.89 142.126244) (width 0.155) (layer "F.Cu") (net 303))
  (segment (start 100 143.04) (end 100 142.514999) (width 0.155) (layer "F.Cu") (net 303))
  (segment (start 99.89 142.126244) (end 100.1125 141.903744) (width 0.155) (layer "F.Cu") (net 303))
  (segment (start 100 142.514999) (end 99.89 142.404999) (width 0.155) (layer "F.Cu") (net 303))
  (via (at 100.1125 141.903744) (size 0.6) (drill 0.25) (layers "F.Cu" "B.Cu") (net 303))
  (segment (start 99.89 139.965) (end 99.89 139.80799) (width 0.155) (layer "B.Cu") (net 303))
  (segment (start 99.89 141.453751) (end 100 141.343751) (width 0.155) (layer "B.Cu") (net 303))
  (segment (start 99.89 141.681244) (end 99.89 141.453751) (width 0.155) (layer "B.Cu") (net 303))
  (segment (start 100.1125 141.903744) (end 99.89 141.681244) (width 0.155) (layer "B.Cu") (net 303))
  (segment (start 100.14 138.945) (end 100.5 138.585) (width 0.155) (layer "B.Cu") (net 303))
  (segment (start 100.14 139.55799) (end 100.14 138.945) (width 0.155) (layer "B.Cu") (net 303))
  (segment (start 99.89 139.80799) (end 100.14 139.55799) (width 0.155) (layer "B.Cu") (net 303))
  (segment (start 100 140.075) (end 99.89 139.965) (width 0.155) (layer "B.Cu") (net 303))
  (segment (start 100 141.343751) (end 100 140.075) (width 0.155) (layer "B.Cu") (net 303))
  (segment (start 103.5 142.514999) (end 103.61 142.404999) (width 0.155) (layer "F.Cu") (net 304))
  (segment (start 103.5 143.04) (end 103.5 142.514999) (width 0.155) (layer "F.Cu") (net 304))
  (segment (start 103.61 142.404999) (end 103.61 142.12781) (width 0.155) (layer "F.Cu") (net 304))
  (segment (start 103.61 142.12781) (end 103.3875 141.90531) (width 0.155) (layer "F.Cu") (net 304))
  (via (at 103.3875 141.90531) (size 0.6) (drill 0.25) (layers "F.Cu" "B.Cu") (net 304))
  (segment (start 103.3875 141.90531) (end 103.61 141.68281) (width 0.155) (layer "B.Cu") (net 304))
  (segment (start 103.61 141.68281) (end 103.61 141.453751) (width 0.155) (layer "B.Cu") (net 304))
  (segment (start 103.61 141.453751) (end 103.5 141.343751) (width 0.155) (layer "B.Cu") (net 304))
  (segment (start 103.36 139.55799) (end 103.36 138.945) (width 0.155) (layer "B.Cu") (net 304))
  (segment (start 103.61 139.965) (end 103.61 139.80799) (width 0.155) (layer "B.Cu") (net 304))
  (segment (start 103.36 138.945) (end 103 138.585) (width 0.155) (layer "B.Cu") (net 304))
  (segment (start 103.61 139.80799) (end 103.36 139.55799) (width 0.155) (layer "B.Cu") (net 304))
  (segment (start 103.5 140.075) (end 103.61 139.965) (width 0.155) (layer "B.Cu") (net 304))
  (segment (start 103.5 141.343751) (end 103.5 140.075) (width 0.155) (layer "B.Cu") (net 304))
  (segment (start 104 143.04) (end 104 142.514999) (width 0.155) (layer "F.Cu") (net 305))
  (segment (start 104 142.514999) (end 103.89 142.404999) (width 0.155) (layer "F.Cu") (net 305))
  (segment (start 103.89 142.404999) (end 103.89 142.12781) (width 0.155) (layer "F.Cu") (net 305))
  (segment (start 103.89 142.12781) (end 104.1125 141.90531) (width 0.155) (layer "F.Cu") (net 305))
  (via (at 104.1125 141.90531) (size 0.6) (drill 0.25) (layers "F.Cu" "B.Cu") (net 305))
  (segment (start 104.1125 141.90531) (end 103.89 141.68281) (width 0.155) (layer "B.Cu") (net 305))
  (segment (start 103.89 141.68281) (end 103.89 141.453751) (width 0.155) (layer "B.Cu") (net 305))
  (segment (start 103.89 141.453751) (end 104 141.343751) (width 0.155) (layer "B.Cu") (net 305))
  (segment (start 103.64 139.44201) (end 103.64 138.945) (width 0.155) (layer "B.Cu") (net 305))
  (segment (start 103.89 139.965) (end 103.89 139.69201) (width 0.155) (layer "B.Cu") (net 305))
  (segment (start 103.64 138.945) (end 104 138.585) (width 0.155) (layer "B.Cu") (net 305))
  (segment (start 103.89 139.69201) (end 103.64 139.44201) (width 0.155) (layer "B.Cu") (net 305))
  (segment (start 104 141.343751) (end 104 140.075) (width 0.155) (layer "B.Cu") (net 305))
  (segment (start 104 140.075) (end 103.89 139.965) (width 0.155) (layer "B.Cu") (net 305))
  (segment (start 103.25 145.265001) (end 103.36 145.375001) (width 0.155) (layer "F.Cu") (net 306))
  (segment (start 104.343673 146.656327) (end 104.343673 146.341663) (width 0.155) (layer "F.Cu") (net 306))
  (segment (start 103.742847 146.190837) (end 104.192847 146.190837) (width 0.155) (layer "F.Cu") (net 306))
  (segment (start 104.192847 146.190837) (end 104.343673 146.341663) (width 0.155) (layer "F.Cu") (net 306))
  (segment (start 103.36 145.80799) (end 103.742847 146.190837) (width 0.155) (layer "F.Cu") (net 306))
  (segment (start 103.36 145.375001) (end 103.36 145.80799) (width 0.155) (layer "F.Cu") (net 306))
  (segment (start 103.25 144.74) (end 103.25 145.265001) (width 0.155) (layer "F.Cu") (net 306))
  (via (at 104.343673 146.656327) (size 0.6) (drill 0.25) (layers "F.Cu" "B.Cu") (net 306))
  (segment (start 105.11 142.39201) (end 104.06 143.44201) (width 0.155) (layer "B.Cu") (net 306))
  (segment (start 105.11 141.453751) (end 105.11 142.39201) (width 0.155) (layer "B.Cu") (net 306))
  (segment (start 104.06 146.05799) (end 104.343673 146.341663) (width 0.155) (layer "B.Cu") (net 306))
  (segment (start 105 141.343751) (end 105.11 141.453751) (width 0.155) (layer "B.Cu") (net 306))
  (segment (start 104.06 143.44201) (end 104.06 146.05799) (width 0.155) (layer "B.Cu") (net 306))
  (segment (start 104.343673 146.341663) (end 104.343673 146.656327) (width 0.155) (layer "B.Cu") (net 306))
  (segment (start 105.11 139.965) (end 105.11 139.69201) (width 0.155) (layer "B.Cu") (net 306))
  (segment (start 105.11 139.69201) (end 105.36 139.44201) (width 0.155) (layer "B.Cu") (net 306))
  (segment (start 105.36 138.945) (end 105 138.585) (width 0.155) (layer "B.Cu") (net 306))
  (segment (start 105.36 139.44201) (end 105.36 138.945) (width 0.155) (layer "B.Cu") (net 306))
  (segment (start 105 140.075) (end 105.11 139.965) (width 0.155) (layer "B.Cu") (net 306))
  (segment (start 105 141.343751) (end 105 140.075) (width 0.155) (layer "B.Cu") (net 306))
  (segment (start 103.75 145.265001) (end 103.64 145.375001) (width 0.155) (layer "F.Cu") (net 307))
  (segment (start 103.858827 145.910837) (end 104.308827 145.910837) (width 0.155) (layer "F.Cu") (net 307))
  (segment (start 103.64 145.69201) (end 103.858827 145.910837) (width 0.155) (layer "F.Cu") (net 307))
  (segment (start 104.856327 146.143673) (end 104.541663 146.143673) (width 0.155) (layer "F.Cu") (net 307))
  (segment (start 103.75 144.74) (end 103.75 145.265001) (width 0.155) (layer "F.Cu") (net 307))
  (segment (start 104.308827 145.910837) (end 104.541663 146.143673) (width 0.155) (layer "F.Cu") (net 307))
  (segment (start 103.64 145.375001) (end 103.64 145.69201) (width 0.155) (layer "F.Cu") (net 307))
  (via (at 104.856327 146.143673) (size 0.6) (drill 0.25) (layers "F.Cu" "B.Cu") (net 307))
  (segment (start 104.34 145.94201) (end 104.541663 146.143673) (width 0.155) (layer "B.Cu") (net 307))
  (segment (start 104.34 143.55799) (end 104.34 145.94201) (width 0.155) (layer "B.Cu") (net 307))
  (segment (start 104.541663 146.143673) (end 104.856327 146.143673) (width 0.155) (layer "B.Cu") (net 307))
  (segment (start 105.39 142.50799) (end 104.34 143.55799) (width 0.155) (layer "B.Cu") (net 307))
  (segment (start 105.39 141.453751) (end 105.39 142.50799) (width 0.155) (layer "B.Cu") (net 307))
  (segment (start 105.5 141.343751) (end 105.39 141.453751) (width 0.155) (layer "B.Cu") (net 307))
  (segment (start 105.64 138.945) (end 106 138.585) (width 0.155) (layer "B.Cu") (net 307))
  (segment (start 105.39 139.965) (end 105.39 139.80799) (width 0.155) (layer "B.Cu") (net 307))
  (segment (start 105.39 139.80799) (end 105.64 139.55799) (width 0.155) (layer "B.Cu") (net 307))
  (segment (start 105.64 139.55799) (end 105.64 138.945) (width 0.155) (layer "B.Cu") (net 307))
  (segment (start 105.5 140.075) (end 105.39 139.965) (width 0.155) (layer "B.Cu") (net 307))
  (segment (start 105.5 141.343751) (end 105.5 140.075) (width 0.155) (layer "B.Cu") (net 307))
  (segment (start 99.36 145.375001) (end 99.36 145.654316) (width 0.155) (layer "F.Cu") (net 308))
  (segment (start 99.36 145.654316) (end 99.1375 145.876816) (width 0.155) (layer "F.Cu") (net 308))
  (segment (start 99.25 144.74) (end 99.25 145.265001) (width 0.155) (layer "F.Cu") (net 308))
  (segment (start 99.25 145.265001) (end 99.36 145.375001) (width 0.155) (layer "F.Cu") (net 308))
  (via (at 99.1375 145.876816) (size 0.6) (drill 0.25) (layers "F.Cu" "B.Cu") (net 308))
  (segment (start 98.11 139.965) (end 98.11 139.80799) (width 0.155) (layer "B.Cu") (net 308))
  (segment (start 99.1375 145.876816) (end 99.36 145.654316) (width 0.155) (layer "B.Cu") (net 308))
  (segment (start 98.11 141.80799) (end 98.11 141.453751) (width 0.155) (layer "B.Cu") (net 308))
  (segment (start 99.36 145.654316) (end 99.36 143.05799) (width 0.155) (layer "B.Cu") (net 308))
  (segment (start 99.36 143.05799) (end 98.11 141.80799) (width 0.155) (layer "B.Cu") (net 308))
  (segment (start 98.11 141.453751) (end 98 141.343751) (width 0.155) (layer "B.Cu") (net 308))
  (segment (start 97.86 138.945) (end 97.5 138.585) (width 0.155) (layer "B.Cu") (net 308))
  (segment (start 97.86 139.55799) (end 97.86 138.945) (width 0.155) (layer "B.Cu") (net 308))
  (segment (start 98.11 139.80799) (end 97.86 139.55799) (width 0.155) (layer "B.Cu") (net 308))
  (segment (start 98 141.343751) (end 98 140.075) (width 0.155) (layer "B.Cu") (net 308))
  (segment (start 98 140.075) (end 98.11 139.965) (width 0.155) (layer "B.Cu") (net 308))
  (segment (start 151.524999 130.74) (end 151.75 130.74) (width 0.125) (layer "F.Cu") (net 309))
  (segment (start 151.0375 130.625) (end 151.409999 130.625) (width 0.125) (layer "F.Cu") (net 309))
  (segment (start 151.409999 130.625) (end 151.524999 130.74) (width 0.125) (layer "F.Cu") (net 309))
  (segment (start 150.8 130.8625) (end 151.0375 130.625) (width 0.125) (layer "F.Cu") (net 309))
  (via (at 150.8 130.8625) (size 0.6) (drill 0.25) (layers "F.Cu" "B.Cu") (net 309))
  (segment (start 150.5625 130.625) (end 150.8 130.8625) (width 0.125) (layer "B.Cu") (net 309))
  (segment (start 149.8937 131) (end 150.2687 130.625) (width 0.125) (layer "B.Cu") (net 309))
  (segment (start 150.2687 130.625) (end 150.5625 130.625) (width 0.125) (layer "B.Cu") (net 309))
  (segment (start 151.0375 130.375) (end 151.409999 130.375) (width 0.125) (layer "F.Cu") (net 310))
  (segment (start 150.8 130.1375) (end 151.0375 130.375) (width 0.125) (layer "F.Cu") (net 310))
  (segment (start 151.524999 130.26) (end 151.75 130.26) (width 0.125) (layer "F.Cu") (net 310))
  (segment (start 151.409999 130.375) (end 151.524999 130.26) (width 0.125) (layer "F.Cu") (net 310))
  (via (at 150.8 130.1375) (size 0.6) (drill 0.25) (layers "F.Cu" "B.Cu") (net 310))
  (segment (start 150.2687 130.375) (end 150.5625 130.375) (width 0.125) (layer "B.Cu") (net 310))
  (segment (start 149.8937 130) (end 150.2687 130.375) (width 0.125) (layer "B.Cu") (net 310))
  (segment (start 150.5625 130.375) (end 150.8 130.1375) (width 0.125) (layer "B.Cu") (net 310))
  (segment (start 150.8 127.8625) (end 151.0375 127.625) (width 0.125) (layer "F.Cu") (net 311))
  (segment (start 151.524999 127.74) (end 151.75 127.74) (width 0.125) (layer "F.Cu") (net 311))
  (segment (start 151.0375 127.625) (end 151.409999 127.625) (width 0.125) (layer "F.Cu") (net 311))
  (segment (start 151.409999 127.625) (end 151.524999 127.74) (width 0.125) (layer "F.Cu") (net 311))
  (via (at 150.8 127.8625) (size 0.6) (drill 0.25) (layers "F.Cu" "B.Cu") (net 311))
  (segment (start 149.8937 128) (end 150.2687 127.625) (width 0.125) (layer "B.Cu") (net 311))
  (segment (start 150.2687 127.625) (end 150.5625 127.625) (width 0.125) (layer "B.Cu") (net 311))
  (segment (start 150.5625 127.625) (end 150.8 127.8625) (width 0.125) (layer "B.Cu") (net 311))
  (segment (start 151.524999 127.26) (end 151.75 127.26) (width 0.125) (layer "F.Cu") (net 312))
  (segment (start 151.409999 127.375) (end 151.524999 127.26) (width 0.125) (layer "F.Cu") (net 312))
  (segment (start 151.0375 127.375) (end 151.409999 127.375) (width 0.125) (layer "F.Cu") (net 312))
  (segment (start 150.8 127.1375) (end 151.0375 127.375) (width 0.125) (layer "F.Cu") (net 312))
  (via (at 150.8 127.1375) (size 0.6) (drill 0.25) (layers "F.Cu" "B.Cu") (net 312))
  (segment (start 149.8937 127) (end 150.2687 127.375) (width 0.125) (layer "B.Cu") (net 312))
  (segment (start 150.5625 127.375) (end 150.8 127.1375) (width 0.125) (layer "B.Cu") (net 312))
  (segment (start 150.2687 127.375) (end 150.5625 127.375) (width 0.125) (layer "B.Cu") (net 312))
  (segment (start 151.409999 124.625) (end 151.524999 124.74) (width 0.125) (layer "F.Cu") (net 313))
  (segment (start 150.8 124.8625) (end 151.0375 124.625) (width 0.125) (layer "F.Cu") (net 313))
  (segment (start 151.524999 124.74) (end 151.75 124.74) (width 0.125) (layer "F.Cu") (net 313))
  (segment (start 151.0375 124.625) (end 151.409999 124.625) (width 0.125) (layer "F.Cu") (net 313))
  (via (at 150.8 124.8625) (size 0.6) (drill 0.25) (layers "F.Cu" "B.Cu") (net 313))
  (segment (start 149.8937 125) (end 150.2687 124.625) (width 0.125) (layer "B.Cu") (net 313))
  (segment (start 150.5625 124.625) (end 150.8 124.8625) (width 0.125) (layer "B.Cu") (net 313))
  (segment (start 150.2687 124.625) (end 150.5625 124.625) (width 0.125) (layer "B.Cu") (net 313))
  (segment (start 151.409999 124.375) (end 151.524999 124.26) (width 0.125) (layer "F.Cu") (net 314))
  (segment (start 151.0375 124.375) (end 151.409999 124.375) (width 0.125) (layer "F.Cu") (net 314))
  (segment (start 150.8 124.1375) (end 151.0375 124.375) (width 0.125) (layer "F.Cu") (net 314))
  (segment (start 151.524999 124.26) (end 151.75 124.26) (width 0.125) (layer "F.Cu") (net 314))
  (via (at 150.8 124.1375) (size 0.6) (drill 0.25) (layers "F.Cu" "B.Cu") (net 314))
  (segment (start 150.5625 124.375) (end 150.8 124.1375) (width 0.125) (layer "B.Cu") (net 314))
  (segment (start 150.2687 124.375) (end 150.5625 124.375) (width 0.125) (layer "B.Cu") (net 314))
  (segment (start 149.8937 124) (end 150.2687 124.375) (width 0.125) (layer "B.Cu") (net 314))
  (segment (start 150.8 121.8625) (end 151.0375 121.625) (width 0.125) (layer "F.Cu") (net 315))
  (segment (start 151.524999 121.74) (end 151.75 121.74) (width 0.125) (layer "F.Cu") (net 315))
  (segment (start 151.409999 121.625) (end 151.524999 121.74) (width 0.125) (layer "F.Cu") (net 315))
  (segment (start 151.0375 121.625) (end 151.409999 121.625) (width 0.125) (layer "F.Cu") (net 315))
  (via (at 150.8 121.8625) (size 0.6) (drill 0.25) (layers "F.Cu" "B.Cu") (net 315))
  (segment (start 149.8937 122) (end 150.2687 121.625) (width 0.125) (layer "B.Cu") (net 315))
  (segment (start 150.2687 121.625) (end 150.5625 121.625) (width 0.125) (layer "B.Cu") (net 315))
  (segment (start 150.5625 121.625) (end 150.8 121.8625) (width 0.125) (layer "B.Cu") (net 315))
  (segment (start 151.409999 121.375) (end 151.524999 121.26) (width 0.125) (layer "F.Cu") (net 316))
  (segment (start 151.524999 121.26) (end 151.75 121.26) (width 0.125) (layer "F.Cu") (net 316))
  (segment (start 151.0375 121.375) (end 151.409999 121.375) (width 0.125) (layer "F.Cu") (net 316))
  (segment (start 150.8 121.1375) (end 151.0375 121.375) (width 0.125) (layer "F.Cu") (net 316))
  (via (at 150.8 121.1375) (size 0.6) (drill 0.25) (layers "F.Cu" "B.Cu") (net 316))
  (segment (start 150.2687 121.375) (end 150.5625 121.375) (width 0.125) (layer "B.Cu") (net 316))
  (segment (start 149.8937 121) (end 150.2687 121.375) (width 0.125) (layer "B.Cu") (net 316))
  (segment (start 150.5625 121.375) (end 150.8 121.1375) (width 0.125) (layer "B.Cu") (net 316))
  (segment (start 151.0375 118.625) (end 151.409999 118.625) (width 0.125) (layer "F.Cu") (net 317))
  (segment (start 150.8 118.8625) (end 151.0375 118.625) (width 0.125) (layer "F.Cu") (net 317))
  (segment (start 151.524999 118.74) (end 151.75 118.74) (width 0.125) (layer "F.Cu") (net 317))
  (segment (start 151.409999 118.625) (end 151.524999 118.74) (width 0.125) (layer "F.Cu") (net 317))
  (via (at 150.8 118.8625) (size 0.6) (drill 0.25) (layers "F.Cu" "B.Cu") (net 317))
  (segment (start 150.5625 118.625) (end 150.8 118.8625) (width 0.125) (layer "B.Cu") (net 317))
  (segment (start 150.2687 118.625) (end 150.5625 118.625) (width 0.125) (layer "B.Cu") (net 317))
  (segment (start 149.8937 119) (end 150.2687 118.625) (width 0.125) (layer "B.Cu") (net 317))
  (segment (start 151.409999 118.375) (end 151.524999 118.26) (width 0.125) (layer "F.Cu") (net 318))
  (segment (start 151.0375 118.375) (end 151.409999 118.375) (width 0.125) (layer "F.Cu") (net 318))
  (segment (start 151.524999 118.26) (end 151.75 118.26) (width 0.125) (layer "F.Cu") (net 318))
  (segment (start 150.8 118.1375) (end 151.0375 118.375) (width 0.125) (layer "F.Cu") (net 318))
  (via (at 150.8 118.1375) (size 0.6) (drill 0.25) (layers "F.Cu" "B.Cu") (net 318))
  (segment (start 150.2687 118.375) (end 150.5625 118.375) (width 0.125) (layer "B.Cu") (net 318))
  (segment (start 149.8937 118) (end 150.2687 118.375) (width 0.125) (layer "B.Cu") (net 318))
  (segment (start 150.5625 118.375) (end 150.8 118.1375) (width 0.125) (layer "B.Cu") (net 318))
  (segment (start 85.5 120.8) (end 89.6 120.8) (width 0.15) (layer "F.Cu") (net 319))
  (segment (start 71.065 111.85) (end 71.065 112.535) (width 0.2) (layer "F.Cu") (net 319))
  (segment (start 99.25 115.55) (end 99.25 114.75) (width 0.15) (layer "F.Cu") (net 319))
  (segment (start 90.4 116.6) (end 98.2 116.6) (width 0.15) (layer "F.Cu") (net 319))
  (segment (start 99.25 114.75) (end 99.25 112.45) (width 0.15) (layer "F.Cu") (net 319))
  (segment (start 90 120.4) (end 90 117) (width 0.15) (layer "F.Cu") (net 319))
  (segment (start 71.065 112.535) (end 71.05 112.55) (width 0.2) (layer "F.Cu") (net 319))
  (segment (start 90 117) (end 90.4 116.6) (width 0.15) (layer "F.Cu") (net 319))
  (segment (start 98.2 116.6) (end 99.25 115.55) (width 0.15) (layer "F.Cu") (net 319))
  (segment (start 89.6 120.8) (end 90 120.4) (width 0.15) (layer "F.Cu") (net 319))
  (via (at 85.5 120.8) (size 0.6) (drill 0.25) (layers "F.Cu" "B.Cu") (net 319))
  (via (at 71.05 112.55) (size 0.6) (drill 0.25) (layers "F.Cu" "B.Cu") (net 319))
  (segment (start 71.9 120.6) (end 71.9 120.2) (width 0.15) (layer "In2.Cu") (net 319))
  (segment (start 71.9 120.2) (end 71.7 120) (width 0.15) (layer "In2.Cu") (net 319))
  (segment (start 70.75 112.55) (end 71.05 112.55) (width 0.15) (layer "In2.Cu") (net 319))
  (segment (start 85.5 120.8) (end 72.1 120.8) (width 0.15) (layer "In2.Cu") (net 319))
  (segment (start 70.9 120) (end 70.6 119.7) (width 0.15) (layer "In2.Cu") (net 319))
  (segment (start 70.6 119.7) (end 70.6 112.7) (width 0.15) (layer "In2.Cu") (net 319))
  (segment (start 72.1 120.8) (end 71.9 120.6) (width 0.15) (layer "In2.Cu") (net 319))
  (segment (start 71.7 120) (end 70.9 120) (width 0.15) (layer "In2.Cu") (net 319))
  (segment (start 70.6 112.7) (end 70.75 112.55) (width 0.15) (layer "In2.Cu") (net 319))
  (segment (start 99.75 112.45) (end 99.75 116.35) (width 0.15) (layer "F.Cu") (net 320))
  (segment (start 99.75 116.35) (end 100.2 116.8) (width 0.15) (layer "F.Cu") (net 320))
  (via (at 100.2 116.8) (size 0.6) (drill 0.25) (layers "F.Cu" "B.Cu") (net 320))
  (via (at 120.7 121.9) (size 0.6) (drill 0.25) (layers "F.Cu" "B.Cu") (net 320))
  (segment (start 100.5 116) (end 111.5 116) (width 0.15) (layer "In2.Cu") (net 320))
  (segment (start 112.4 116.9) (end 112.4 120.6) (width 0.15) (layer "In2.Cu") (net 320))
  (segment (start 112.4 120.6) (end 113.5 121.7) (width 0.15) (layer "In2.Cu") (net 320))
  (segment (start 100.2 116.8) (end 100.2 116.3) (width 0.15) (layer "In2.Cu") (net 320))
  (segment (start 100.2 116.3) (end 100.5 116) (width 0.15) (layer "In2.Cu") (net 320))
  (segment (start 120.5 121.7) (end 120.7 121.9) (width 0.15) (layer "In2.Cu") (net 320))
  (segment (start 113.5 121.7) (end 120.5 121.7) (width 0.15) (layer "In2.Cu") (net 320))
  (segment (start 111.5 116) (end 112.4 116.9) (width 0.15) (layer "In2.Cu") (net 320))
  (segment (start 121.365 121.9) (end 120.7 121.9) (width 0.15) (layer "B.Cu") (net 320))
  (segment (start 101.75 145.265001) (end 101.64 145.375001) (width 0.155) (layer "F.Cu") (net 321))
  (segment (start 101.75 144.74) (end 101.75 145.265001) (width 0.155) (layer "F.Cu") (net 321))
  (segment (start 101.64 145.375001) (end 101.64 145.655002) (width 0.155) (layer "F.Cu") (net 321))
  (segment (start 101.64 145.655002) (end 101.8625 145.877502) (width 0.155) (layer "F.Cu") (net 321))
  (segment (start 101.5 143.04) (end 101.5 142.514999) (width 0.155) (layer "F.Cu") (net 321))
  (segment (start 101.61 142.404999) (end 101.61 142.125022) (width 0.155) (layer "F.Cu") (net 321))
  (segment (start 101.61 142.125022) (end 101.3875 141.902522) (width 0.155) (layer "F.Cu") (net 321))
  (segment (start 101.5 142.514999) (end 101.61 142.404999) (width 0.155) (layer "F.Cu") (net 321))
  (segment (start 102.86 120.522161) (end 102.385248 120.996913) (width 0.155) (layer "F.Cu") (net 321))
  (segment (start 102.75 119.750001) (end 102.86 119.860001) (width 0.155) (layer "F.Cu") (net 321))
  (segment (start 102.86 119.860001) (end 102.86 120.522161) (width 0.155) (layer "F.Cu") (net 321))
  (segment (start 102.385248 120.996913) (end 102.070584 120.996913) (width 0.155) (layer "F.Cu") (net 321))
  (segment (start 102.75 118.55) (end 102.75 119.750001) (width 0.155) (layer "F.Cu") (net 321))
  (via (at 101.8625 145.877502) (size 0.6) (drill 0.25) (layers "F.Cu" "B.Cu") (net 321))
  (via (at 101.3875 141.902522) (size 0.6) (drill 0.25) (layers "F.Cu" "B.Cu") (net 321))
  (via (at 102.070584 120.996913) (size 0.6) (drill 0.25) (layers "F.Cu" "B.Cu") (net 321))
  (segment (start 103.227275 146.598486) (end 103.203524 146.574735) (width 0.155) (layer "In2.Cu") (net 321))
  (segment (start 102.974855 146.457092) (end 102.963761 146.425388) (width 0.155) (layer "In2.Cu") (net 321))
  (segment (start 102.08799 146.64) (end 102.092502 146.599947) (width 0.155) (layer "In2.Cu") (net 321))
  (segment (start 103.016477 146.509284) (end 102.992726 146.485533) (width 0.155) (layer "In2.Cu") (net 321))
  (segment (start 102.408719 146.527772) (end 102.430164 146.561901) (width 0.155) (layer "In2.Cu") (net 321))
  (segment (start 102.346089 146.477826) (end 102.380218 146.499271) (width 0.155) (layer "In2.Cu") (net 321))
  (segment (start 103.26 144.89201) (end 103.66 144.49201) (width 0.155) (layer "In2.Cu") (net 321))
  (segment (start 102.465815 146.7581) (end 102.48726 146.792229) (width 0.155) (layer "In2.Cu") (net 321))
  (segment (start 102.092502 146.599947) (end 102.105815 146.561901) (width 0.155) (layer "In2.Cu") (net 321))
  (segment (start 102.105815 146.561901) (end 102.12726 146.527772) (width 0.155) (layer "In2.Cu") (net 321))
  (segment (start 101.61 142.80799) (end 101.61 142.125022) (width 0.155) (layer "In2.Cu") (net 321))
  (segment (start 102.26799 146.46) (end 102.308043 146.464513) (width 0.155) (layer "In2.Cu") (net 321))
  (segment (start 103.245146 146.626927) (end 103.227275 146.598486) (width 0.155) (layer "In2.Cu") (net 321))
  (segment (start 103.203524 146.574735) (end 103.175083 146.556864) (width 0.155) (layer "In2.Cu") (net 321))
  (segment (start 101.64 146.59201) (end 101.90799 146.86) (width 0.155) (layer "In2.Cu") (net 321))
  (segment (start 102.62799 146.86) (end 103.09201 146.86) (width 0.155) (layer "In2.Cu") (net 321))
  (segment (start 103.016477 146.214735) (end 103.044918 146.196864) (width 0.155) (layer "In2.Cu") (net 321))
  (segment (start 102.452502 146.720054) (end 102.465815 146.7581) (width 0.155) (layer "In2.Cu") (net 321))
  (segment (start 102.587936 146.855488) (end 102.62799 146.86) (width 0.155) (layer "In2.Cu") (net 321))
  (segment (start 102.048719 146.792229) (end 102.070164 146.7581) (width 0.155) (layer "In2.Cu") (net 321))
  (segment (start 101.8625 145.877502) (end 101.64 146.100002) (width 0.155) (layer "In2.Cu") (net 321))
  (segment (start 103.26 146.03201) (end 103.26 144.89201) (width 0.155) (layer "In2.Cu") (net 321))
  (segment (start 101.986089 146.842175) (end 102.020218 146.82073) (width 0.155) (layer "In2.Cu") (net 321))
  (segment (start 102.96 146.39201) (end 102.96 146.33201) (width 0.155) (layer "In2.Cu") (net 321))
  (segment (start 102.155761 146.499271) (end 102.18989 146.477826) (width 0.155) (layer "In2.Cu") (net 321))
  (segment (start 102.963761 146.425388) (end 102.96 146.39201) (width 0.155) (layer "In2.Cu") (net 321))
  (segment (start 102.18989 146.477826) (end 102.227936 146.464513) (width 0.155) (layer "In2.Cu") (net 321))
  (segment (start 103.175083 146.167155) (end 103.203524 146.149284) (width 0.155) (layer "In2.Cu") (net 321))
  (segment (start 103.143379 146.178249) (end 103.175083 146.167155) (width 0.155) (layer "In2.Cu") (net 321))
  (segment (start 102.020218 146.82073) (end 102.048719 146.792229) (width 0.155) (layer "In2.Cu") (net 321))
  (segment (start 103.26 146.69201) (end 103.25624 146.658631) (width 0.155) (layer "In2.Cu") (net 321))
  (segment (start 102.974855 146.266927) (end 102.992726 146.238486) (width 0.155) (layer "In2.Cu") (net 321))
  (segment (start 102.96 146.33201) (end 102.963761 146.298631) (width 0.155) (layer "In2.Cu") (net 321))
  (segment (start 103.25624 146.658631) (end 103.245146 146.626927) (width 0.155) (layer "In2.Cu") (net 321))
  (segment (start 102.380218 146.499271) (end 102.408719 146.527772) (width 0.155) (layer "In2.Cu") (net 321))
  (segment (start 103.66 144.49201) (end 103.66 143.55799) (width 0.155) (layer "In2.Cu") (net 321))
  (segment (start 103.227275 146.125533) (end 103.245146 146.097092) (width 0.155) (layer "In2.Cu") (net 321))
  (segment (start 103.044918 146.527155) (end 103.016477 146.509284) (width 0.155) (layer "In2.Cu") (net 321))
  (segment (start 103.25624 146.065388) (end 103.26 146.03201) (width 0.155) (layer "In2.Cu") (net 321))
  (segment (start 102.54989 146.842175) (end 102.587936 146.855488) (width 0.155) (layer "In2.Cu") (net 321))
  (segment (start 102.12726 146.527772) (end 102.155761 146.499271) (width 0.155) (layer "In2.Cu") (net 321))
  (segment (start 102.430164 146.561901) (end 102.443477 146.599947) (width 0.155) (layer "In2.Cu") (net 321))
  (segment (start 103.29201 143.19) (end 101.99201 143.19) (width 0.155) (layer "In2.Cu") (net 321))
  (segment (start 103.143379 146.54577) (end 103.076622 146.538249) (width 0.155) (layer "In2.Cu") (net 321))
  (segment (start 103.076622 146.538249) (end 103.044918 146.527155) (width 0.155) (layer "In2.Cu") (net 321))
  (segment (start 101.64 146.100002) (end 101.64 146.59201) (width 0.155) (layer "In2.Cu") (net 321))
  (segment (start 102.08799 146.68) (end 102.08799 146.64) (width 0.155) (layer "In2.Cu") (net 321))
  (segment (start 101.99201 143.19) (end 101.61 142.80799) (width 0.155) (layer "In2.Cu") (net 321))
  (segment (start 103.076622 146.18577) (end 103.143379 146.178249) (width 0.155) (layer "In2.Cu") (net 321))
  (segment (start 101.90799 146.86) (end 101.948043 146.855488) (width 0.155) (layer "In2.Cu") (net 321))
  (segment (start 103.09201 146.86) (end 103.26 146.69201) (width 0.155) (layer "In2.Cu") (net 321))
  (segment (start 102.992726 146.485533) (end 102.974855 146.457092) (width 0.155) (layer "In2.Cu") (net 321))
  (segment (start 102.308043 146.464513) (end 102.346089 146.477826) (width 0.155) (layer "In2.Cu") (net 321))
  (segment (start 103.044918 146.196864) (end 103.076622 146.18577) (width 0.155) (layer "In2.Cu") (net 321))
  (segment (start 102.48726 146.792229) (end 102.515761 146.82073) (width 0.155) (layer "In2.Cu") (net 321))
  (segment (start 103.203524 146.149284) (end 103.227275 146.125533) (width 0.155) (layer "In2.Cu") (net 321))
  (segment (start 101.948043 146.855488) (end 101.986089 146.842175) (width 0.155) (layer "In2.Cu") (net 321))
  (segment (start 102.44799 146.64) (end 102.44799 146.68) (width 0.155) (layer "In2.Cu") (net 321))
  (segment (start 102.44799 146.68) (end 102.452502 146.720054) (width 0.155) (layer "In2.Cu") (net 321))
  (segment (start 102.070164 146.7581) (end 102.083477 146.720054) (width 0.155) (layer "In2.Cu") (net 321))
  (segment (start 102.227936 146.464513) (end 102.26799 146.46) (width 0.155) (layer "In2.Cu") (net 321))
  (segment (start 101.61 142.125022) (end 101.3875 141.902522) (width 0.155) (layer "In2.Cu") (net 321))
  (segment (start 102.992726 146.238486) (end 103.016477 146.214735) (width 0.155) (layer "In2.Cu") (net 321))
  (segment (start 102.515761 146.82073) (end 102.54989 146.842175) (width 0.155) (layer "In2.Cu") (net 321))
  (segment (start 102.963761 146.298631) (end 102.974855 146.266927) (width 0.155) (layer "In2.Cu") (net 321))
  (segment (start 103.175083 146.556864) (end 103.143379 146.54577) (width 0.155) (layer "In2.Cu") (net 321))
  (segment (start 103.245146 146.097092) (end 103.25624 146.065388) (width 0.155) (layer "In2.Cu") (net 321))
  (segment (start 103.66 143.55799) (end 103.29201 143.19) (width 0.155) (layer "In2.Cu") (net 321))
  (segment (start 102.443477 146.599947) (end 102.44799 146.64) (width 0.155) (layer "In2.Cu") (net 321))
  (segment (start 102.083477 146.720054) (end 102.08799 146.68) (width 0.155) (layer "In2.Cu") (net 321))
  (segment (start 101.3875 141.2625) (end 101.247499 141.122499) (width 0.155) (layer "B.Cu") (net 321))
  (segment (start 101.3875 141.902522) (end 101.3875 141.2625) (width 0.155) (layer "B.Cu") (net 321))
  (segment (start 101.61 139.146298) (end 101.61 121.772161) (width 0.155) (layer "B.Cu") (net 321))
  (segment (start 102.070584 121.311577) (end 102.070584 120.996913) (width 0.155) (layer "B.Cu") (net 321))
  (segment (start 101.247499 139.508799) (end 101.61 139.146298) (width 0.155) (layer "B.Cu") (net 321))
  (segment (start 101.247499 141.122499) (end 101.247499 139.508799) (width 0.155) (layer "B.Cu") (net 321))
  (segment (start 101.61 121.772161) (end 102.070584 121.311577) (width 0.155) (layer "B.Cu") (net 321))
  (segment (start 101.25 144.74) (end 101.25 145.265001) (width 0.155) (layer "F.Cu") (net 322))
  (segment (start 101.25 145.265001) (end 101.36 145.375001) (width 0.155) (layer "F.Cu") (net 322))
  (segment (start 101.36 145.375001) (end 101.36 145.655002) (width 0.155) (layer "F.Cu") (net 322))
  (segment (start 101.36 145.655002) (end 101.1375 145.877502) (width 0.155) (layer "F.Cu") (net 322))
  (segment (start 102 142.514999) (end 101.89 142.404999) (width 0.155) (layer "F.Cu") (net 322))
  (segment (start 102 143.04) (end 102 142.514999) (width 0.155) (layer "F.Cu") (net 322))
  (segment (start 101.89 142.404999) (end 101.89 142.125022) (width 0.155) (layer "F.Cu") (net 322))
  (segment (start 101.89 142.125022) (end 102.1125 141.902522) (width 0.155) (layer "F.Cu") (net 322))
  (segment (start 103.25 119.750001) (end 103.14 119.860001) (width 0.155) (layer "F.Cu") (net 322))
  (segment (start 103.14 120.638141) (end 102.583238 121.194903) (width 0.155) (layer "F.Cu") (net 322))
  (segment (start 102.583238 121.194903) (end 102.583238 121.509567) (width 0.155) (layer "F.Cu") (net 322))
  (segment (start 103.25 118.55) (end 103.25 119.750001) (width 0.155) (layer "F.Cu") (net 322))
  (segment (start 103.14 119.860001) (end 103.14 120.638141) (width 0.155) (layer "F.Cu") (net 322))
  (via (at 101.1375 145.877502) (size 0.6) (drill 0.25) (layers "F.Cu" "B.Cu") (net 322))
  (via (at 102.1125 141.902522) (size 0.6) (drill 0.25) (layers "F.Cu" "B.Cu") (net 322))
  (via (at 102.583238 121.509567) (size 0.6) (drill 0.25) (layers "F.Cu" "B.Cu") (net 322))
  (segment (start 103.54 146.80799) (end 103.54 145.00799) (width 0.155) (layer "In2.Cu") (net 322))
  (segment (start 103.54 145.00799) (end 103.94 144.60799) (width 0.155) (layer "In2.Cu") (net 322))
  (segment (start 103.20799 147.14) (end 103.54 146.80799) (width 0.155) (layer "In2.Cu") (net 322))
  (segment (start 101.79201 147.14) (end 103.20799 147.14) (width 0.155) (layer "In2.Cu") (net 322))
  (segment (start 101.36 146.70799) (end 101.79201 147.14) (width 0.155) (layer "In2.Cu") (net 322))
  (segment (start 101.1375 145.877502) (end 101.36 146.100002) (width 0.155) (layer "In2.Cu") (net 322))
  (segment (start 101.36 146.100002) (end 101.36 146.70799) (width 0.155) (layer "In2.Cu") (net 322))
  (segment (start 103.94 143.44201) (end 103.94 144.60799) (width 0.155) (layer "In2.Cu") (net 322))
  (segment (start 103.40799 142.91) (end 103.94 143.44201) (width 0.155) (layer "In2.Cu") (net 322))
  (segment (start 102.10799 142.91) (end 103.40799 142.91) (width 0.155) (layer "In2.Cu") (net 322))
  (segment (start 101.89 142.69201) (end 102.10799 142.91) (width 0.155) (layer "In2.Cu") (net 322))
  (segment (start 102.1125 141.902522) (end 101.89 142.125022) (width 0.155) (layer "In2.Cu") (net 322))
  (segment (start 101.89 142.125022) (end 101.89 142.69201) (width 0.155) (layer "In2.Cu") (net 322))
  (segment (start 102.1125 141.2625) (end 102.252501 141.122499) (width 0.155) (layer "B.Cu") (net 322))
  (segment (start 102.268574 121.509567) (end 102.583238 121.509567) (width 0.155) (layer "B.Cu") (net 322))
  (segment (start 102.252501 139.508799) (end 101.89 139.146298) (width 0.155) (layer "B.Cu") (net 322))
  (segment (start 101.89 139.146298) (end 101.89 121.888141) (width 0.155) (layer "B.Cu") (net 322))
  (segment (start 102.252501 141.122499) (end 102.252501 139.508799) (width 0.155) (layer "B.Cu") (net 322))
  (segment (start 102.1125 141.902522) (end 102.1125 141.2625) (width 0.155) (layer "B.Cu") (net 322))
  (segment (start 101.89 121.888141) (end 102.268574 121.509567) (width 0.155) (layer "B.Cu") (net 322))
  (segment (start 99.64 145.375001) (end 99.64 145.654316) (width 0.155) (layer "F.Cu") (net 323))
  (segment (start 99.75 144.74) (end 99.75 145.265001) (width 0.155) (layer "F.Cu") (net 323))
  (segment (start 99.75 145.265001) (end 99.64 145.375001) (width 0.155) (layer "F.Cu") (net 323))
  (segment (start 99.64 145.654316) (end 99.8625 145.876816) (width 0.155) (layer "F.Cu") (net 323))
  (via (at 99.8625 145.876816) (size 0.6) (drill 0.25) (layers "F.Cu" "B.Cu") (net 323))
  (segment (start 98.39 139.965) (end 98.39 139.69201) (width 0.155) (layer "B.Cu") (net 323))
  (segment (start 98.39 141.69201) (end 98.39 141.453751) (width 0.155) (layer "B.Cu") (net 323))
  (segment (start 99.8625 145.876816) (end 99.64 145.654316) (width 0.155) (layer "B.Cu") (net 323))
  (segment (start 98.39 141.453751) (end 98.5 141.343751) (width 0.155) (layer "B.Cu") (net 323))
  (segment (start 99.64 142.94201) (end 98.39 141.69201) (width 0.155) (layer "B.Cu") (net 323))
  (segment (start 99.64 145.654316) (end 99.64 142.94201) (width 0.155) (layer "B.Cu") (net 323))
  (segment (start 98.14 139.44201) (end 98.14 138.945) (width 0.155) (layer "B.Cu") (net 323))
  (segment (start 98.14 138.945) (end 98.5 138.585) (width 0.155) (layer "B.Cu") (net 323))
  (segment (start 98.39 139.69201) (end 98.14 139.44201) (width 0.155) (layer "B.Cu") (net 323))
  (segment (start 98.5 141.343751) (end 98.5 140.075) (width 0.155) (layer "B.Cu") (net 323))
  (segment (start 98.5 140.075) (end 98.39 139.965) (width 0.155) (layer "B.Cu") (net 323))
  (segment (start 106.625 89.748222) (end 106.625 87.925001) (width 0.125) (layer "B.Cu") (net 324))
  (segment (start 106.625 87.925001) (end 106.75 87.800001) (width 0.125) (layer "B.Cu") (net 324))
  (segment (start 107.125 93.109999) (end 107.125 90.248222) (width 0.125) (layer "B.Cu") (net 324))
  (segment (start 107.24 93.224999) (end 107.125 93.109999) (width 0.125) (layer "B.Cu") (net 324))
  (segment (start 107.24 93.45) (end 107.24 93.224999) (width 0.125) (layer "B.Cu") (net 324))
  (segment (start 107.125 90.248222) (end 106.625 89.748222) (width 0.125) (layer "B.Cu") (net 324))
  (segment (start 106.75 87.800001) (end 106.75 86.9) (width 0.125) (layer "B.Cu") (net 324))
  (segment (start 106.375 89.851778) (end 106.375 87.925001) (width 0.125) (layer "B.Cu") (net 325))
  (segment (start 106.875 90.351778) (end 106.375 89.851778) (width 0.125) (layer "B.Cu") (net 325))
  (segment (start 106.76 93.224999) (end 106.875 93.109999) (width 0.125) (layer "B.Cu") (net 325))
  (segment (start 106.875 93.109999) (end 106.875 90.351778) (width 0.125) (layer "B.Cu") (net 325))
  (segment (start 106.76 93.45) (end 106.76 93.224999) (width 0.125) (layer "B.Cu") (net 325))
  (segment (start 106.25 87.800001) (end 106.25 86.9) (width 0.125) (layer "B.Cu") (net 325))
  (segment (start 106.375 87.925001) (end 106.25 87.800001) (width 0.125) (layer "B.Cu") (net 325))
  (segment (start 97.25 118.55) (end 97.25 133.15) (width 0.182) (layer "F.Cu") (net 326))
  (segment (start 97.25 133.15) (end 96.8 133.6) (width 0.182) (layer "F.Cu") (net 326))
  (segment (start 100.750329 142.247365) (end 101 142.497036) (width 0.182) (layer "F.Cu") (net 326))
  (segment (start 101 142.497036) (end 101 143.04) (width 0.182) (layer "F.Cu") (net 326))
  (via (at 100.750329 142.247365) (size 0.6) (drill 0.25) (layers "F.Cu" "B.Cu") (net 326))
  (via (at 96.8 133.6) (size 0.6) (drill 0.25) (layers "F.Cu" "B.Cu") (net 326))
  (via (at 100.7 139.45) (size 0.6) (drill 0.25) (layers "F.Cu" "B.Cu") (net 326))
  (segment (start 96.8 133.6) (end 96.500001 133.899999) (width 0.182) (layer "In2.Cu") (net 326))
  (segment (start 96.500001 135.700001) (end 99.2 138.4) (width 0.182) (layer "In2.Cu") (net 326))
  (segment (start 100.4 138.4) (end 100.7 138.7) (width 0.182) (layer "In2.Cu") (net 326))
  (segment (start 100.7 138.7) (end 100.7 139.45) (width 0.182) (layer "In2.Cu") (net 326))
  (segment (start 96.500001 133.899999) (end 96.500001 135.700001) (width 0.182) (layer "In2.Cu") (net 326))
  (segment (start 99.2 138.4) (end 100.4 138.4) (width 0.182) (layer "In2.Cu") (net 326))
  (segment (start 100.75 139.5) (end 100.7 139.45) (width 0.182) (layer "B.Cu") (net 326))
  (segment (start 100.75 142.247036) (end 100.75 139.5) (width 0.182) (layer "B.Cu") (net 326))
  (segment (start 100.750329 142.247365) (end 100.75 142.247036) (width 0.182) (layer "B.Cu") (net 326))
  (segment (start 102.25 144.74) (end 102.25 145.45) (width 0.182) (layer "F.Cu") (net 327))
  (segment (start 102.25 145.45) (end 102.65 145.85) (width 0.182) (layer "F.Cu") (net 327))
  (segment (start 97.75 118.55) (end 97.75 133.85) (width 0.182) (layer "F.Cu") (net 327))
  (segment (start 97.75 133.85) (end 97.2 134.4) (width 0.182) (layer "F.Cu") (net 327))
  (via (at 102.65 145.85) (size 0.6) (drill 0.25) (layers "F.Cu" "B.Cu") (net 327))
  (via (at 97.2 134.4) (size 0.6) (drill 0.25) (layers "F.Cu" "B.Cu") (net 327))
  (via (at 102.8 139.45) (size 0.6) (drill 0.25) (layers "F.Cu" "B.Cu") (net 327))
  (segment (start 102.8 138.6) (end 102.8 139.45) (width 0.182) (layer "In2.Cu") (net 327))
  (segment (start 99.4 138) (end 102.2 138) (width 0.182) (layer "In2.Cu") (net 327))
  (segment (start 97.2 135.8) (end 99.4 138) (width 0.182) (layer "In2.Cu") (net 327))
  (segment (start 97.2 134.4) (end 97.2 135.8) (width 0.182) (layer "In2.Cu") (net 327))
  (segment (start 102.2 138) (end 102.8 138.6) (width 0.182) (layer "In2.Cu") (net 327))
  (segment (start 103.5 144.4) (end 103.5 143.4) (width 0.182) (layer "B.Cu") (net 327))
  (segment (start 102.65 145.25) (end 103.5 144.4) (width 0.182) (layer "B.Cu") (net 327))
  (segment (start 102.65 145.85) (end 102.65 145.25) (width 0.182) (layer "B.Cu") (net 327))
  (segment (start 102.75 139.5) (end 102.8 139.45) (width 0.182) (layer "B.Cu") (net 327))
  (segment (start 102.75 140.3125) (end 102.75 139.5) (width 0.182) (layer "B.Cu") (net 327))
  (segment (start 102.75 140.3125) (end 102.75 142.65) (width 0.182) (layer "B.Cu") (net 327))
  (segment (start 103.5 143.4) (end 102.85 142.75) (width 0.182) (layer "B.Cu") (net 327))
  (segment (start 102.75 142.65) (end 102.85 142.75) (width 0.182) (layer "B.Cu") (net 327))
  (segment (start 94.1 140.285) (end 93.1 140.285) (width 0.155) (layer "F.Cu") (net 328))
  (segment (start 93.1225 143.04) (end 92.9 143.2625) (width 0.155) (layer "F.Cu") (net 328))
  (segment (start 94.125 143.1) (end 93.599999 143.1) (width 0.155) (layer "F.Cu") (net 328))
  (segment (start 93.599999 143.1) (end 93.539999 143.04) (width 0.155) (layer "F.Cu") (net 328))
  (segment (start 93.539999 143.04) (end 93.1225 143.04) (width 0.155) (layer "F.Cu") (net 328))
  (segment (start 94.2375 140.9) (end 94.46 141.1225) (width 0.155) (layer "F.Cu") (net 328))
  (segment (start 94.46 141.1225) (end 94.46 141.389999) (width 0.155) (layer "F.Cu") (net 328))
  (segment (start 94.46 141.389999) (end 94.4 141.449999) (width 0.155) (layer "F.Cu") (net 328))
  (segment (start 94.4 141.449999) (end 94.4 141.975) (width 0.155) (layer "F.Cu") (net 328))
  (segment (start 94.2375 140.9) (end 94.2375 140.4225) (width 0.155) (layer "F.Cu") (net 328))
  (via (at 92.9 143.2625) (size 0.6) (drill 0.25) (layers "F.Cu" "B.Cu") (net 328))
  (via (at 94.2375 140.9) (size 0.6) (drill 0.25) (layers "F.Cu" "B.Cu") (net 328))
  (segment (start 93.893658 141.525243) (end 93.862387 141.540302) (width 0.155) (layer "B.Cu") (net 328))
  (segment (start 93.960421 141.463977) (end 93.920795 141.503602) (width 0.155) (layer "B.Cu") (net 328))
  (segment (start 94.216325 141.522385) (end 94.201266 141.491113) (width 0.155) (layer "B.Cu") (net 328))
  (segment (start 94.087377 141.419553) (end 94.052668 141.419553) (width 0.155) (layer "B.Cu") (net 328))
  (segment (start 93.76 141.540302) (end 93.728728 141.525243) (width 0.155) (layer "B.Cu") (net 328))
  (segment (start 94.121216 141.427276) (end 94.087377 141.419553) (width 0.155) (layer "B.Cu") (net 328))
  (segment (start 93.987558 141.442336) (end 93.960421 141.463977) (width 0.155) (layer "B.Cu") (net 328))
  (segment (start 94.152488 141.442336) (end 94.121216 141.427276) (width 0.155) (layer "B.Cu") (net 328))
  (segment (start 94.224049 141.590933) (end 94.224049 141.556224) (width 0.155) (layer "B.Cu") (net 328))
  (segment (start 94.216325 141.624772) (end 94.224049 141.590933) (width 0.155) (layer "B.Cu") (net 328))
  (segment (start 94.224049 141.556224) (end 94.216325 141.522385) (width 0.155) (layer "B.Cu") (net 328))
  (segment (start 94.14 141.722806) (end 94.179625 141.68318) (width 0.155) (layer "B.Cu") (net 328))
  (segment (start 92.9 143.2625) (end 93.1225 143.04) (width 0.155) (layer "B.Cu") (net 328))
  (segment (start 94.14 141.94201) (end 94.118359 141.914873) (width 0.155) (layer "B.Cu") (net 328))
  (segment (start 94.46 140.25799) (end 94.46 140.6775) (width 0.155) (layer "B.Cu") (net 328))
  (segment (start 94.01883 141.427276) (end 93.987558 141.442336) (width 0.155) (layer "B.Cu") (net 328))
  (segment (start 94.201266 141.491113) (end 94.179625 141.463977) (width 0.155) (layer "B.Cu") (net 328))
  (segment (start 93.75799 143.04) (end 94.14 142.65799) (width 0.155) (layer "B.Cu") (net 328))
  (segment (start 94.095576 141.815053) (end 94.103299 141.781215) (width 0.155) (layer "B.Cu") (net 328))
  (segment (start 93.1225 143.04) (end 93.75799 143.04) (width 0.155) (layer "B.Cu") (net 328))
  (segment (start 93.34 141.14201) (end 93.34 140.25799) (width 0.155) (layer "B.Cu") (net 328))
  (segment (start 94.14 142.65799) (end 94.14 141.94201) (width 0.155) (layer "B.Cu") (net 328))
  (segment (start 93.920795 141.503602) (end 93.893658 141.525243) (width 0.155) (layer "B.Cu") (net 328))
  (segment (start 94.118359 141.914873) (end 94.103299 141.883601) (width 0.155) (layer "B.Cu") (net 328))
  (segment (start 94.103299 141.781215) (end 94.118359 141.749943) (width 0.155) (layer "B.Cu") (net 328))
  (segment (start 94.179625 141.68318) (end 94.201266 141.656043) (width 0.155) (layer "B.Cu") (net 328))
  (segment (start 93.828548 141.548026) (end 93.793839 141.548026) (width 0.155) (layer "B.Cu") (net 328))
  (segment (start 94.052668 141.419553) (end 94.01883 141.427276) (width 0.155) (layer "B.Cu") (net 328))
  (segment (start 94.095576 141.849762) (end 94.095576 141.815053) (width 0.155) (layer "B.Cu") (net 328))
  (segment (start 94.179625 141.463977) (end 94.152488 141.442336) (width 0.155) (layer "B.Cu") (net 328))
  (segment (start 94.201266 141.656043) (end 94.216325 141.624772) (width 0.155) (layer "B.Cu") (net 328))
  (segment (start 94.118359 141.749943) (end 94.14 141.722806) (width 0.155) (layer "B.Cu") (net 328))
  (segment (start 94.103299 141.883601) (end 94.095576 141.849762) (width 0.155) (layer "B.Cu") (net 328))
  (segment (start 93.34 140.25799) (end 93.65799 139.94) (width 0.155) (layer "B.Cu") (net 328))
  (segment (start 93.862387 141.540302) (end 93.828548 141.548026) (width 0.155) (layer "B.Cu") (net 328))
  (segment (start 93.793839 141.548026) (end 93.76 141.540302) (width 0.155) (layer "B.Cu") (net 328))
  (segment (start 93.728728 141.525243) (end 93.701593 141.503603) (width 0.155) (layer "B.Cu") (net 328))
  (segment (start 93.701593 141.503603) (end 93.34 141.14201) (width 0.155) (layer "B.Cu") (net 328))
  (segment (start 93.65799 139.94) (end 94.14201 139.94) (width 0.155) (layer "B.Cu") (net 328))
  (segment (start 94.14201 139.94) (end 94.46 140.25799) (width 0.155) (layer "B.Cu") (net 328))
  (segment (start 94.46 140.6775) (end 94.2375 140.9) (width 0.155) (layer "B.Cu") (net 328))
  (segment (start 95.1 140.285) (end 96.1 140.285) (width 0.155) (layer "F.Cu") (net 329))
  (segment (start 93.599999 142.7) (end 93.539999 142.76) (width 0.155) (layer "F.Cu") (net 329))
  (segment (start 93.1225 142.76) (end 92.9 142.5375) (width 0.155) (layer "F.Cu") (net 329))
  (segment (start 94.125 142.7) (end 93.599999 142.7) (width 0.155) (layer "F.Cu") (net 329))
  (segment (start 93.539999 142.76) (end 93.1225 142.76) (width 0.155) (layer "F.Cu") (net 329))
  (segment (start 94.9625 140.9) (end 94.74 141.1225) (width 0.155) (layer "F.Cu") (net 329))
  (segment (start 94.74 141.1225) (end 94.74 141.389999) (width 0.155) (layer "F.Cu") (net 329))
  (segment (start 94.8 141.449999) (end 94.8 141.975) (width 0.155) (layer "F.Cu") (net 329))
  (segment (start 94.74 141.389999) (end 94.8 141.449999) (width 0.155) (layer "F.Cu") (net 329))
  (segment (start 94.9625 140.9) (end 94.9625 140.4225) (width 0.155) (layer "F.Cu") (net 329))
  (via (at 92.9 142.5375) (size 0.6) (drill 0.25) (layers "F.Cu" "B.Cu") (net 329))
  (via (at 94.9625 140.9) (size 0.6) (drill 0.25) (layers "F.Cu" "B.Cu") (net 329))
  (segment (start 93.86 142.05799) (end 93.06 141.25799) (width 0.155) (layer "B.Cu") (net 329))
  (segment (start 93.86 142.54201) (end 93.86 142.05799) (width 0.155) (layer "B.Cu") (net 329))
  (segment (start 93.64201 142.76) (end 93.86 142.54201) (width 0.155) (layer "B.Cu") (net 329))
  (segment (start 93.1225 142.76) (end 93.64201 142.76) (width 0.155) (layer "B.Cu") (net 329))
  (segment (start 92.9 142.5375) (end 93.1225 142.76) (width 0.155) (layer "B.Cu") (net 329))
  (segment (start 93.06 140.14201) (end 93.06 141.25799) (width 0.155) (layer "B.Cu") (net 329))
  (segment (start 93.54201 139.66) (end 93.06 140.14201) (width 0.155) (layer "B.Cu") (net 329))
  (segment (start 94.25799 139.66) (end 93.54201 139.66) (width 0.155) (layer "B.Cu") (net 329))
  (segment (start 94.74 140.14201) (end 94.25799 139.66) (width 0.155) (layer "B.Cu") (net 329))
  (segment (start 94.9625 140.9) (end 94.74 140.6775) (width 0.155) (layer "B.Cu") (net 329))
  (segment (start 94.74 140.6775) (end 94.74 140.14201) (width 0.155) (layer "B.Cu") (net 329))
  (segment (start 102.5 143.04) (end 102.5 143.5) (width 0.155) (layer "F.Cu") (net 330))
  (segment (start 102.5 143.5) (end 102.1 143.9) (width 0.155) (layer "F.Cu") (net 330))
  (segment (start 96.000001 143.1) (end 96.060001 143.04) (width 0.155) (layer "F.Cu") (net 330))
  (segment (start 96.38875 143.04) (end 96.61125 143.2625) (width 0.155) (layer "F.Cu") (net 330))
  (segment (start 95.475 143.1) (end 96.000001 143.1) (width 0.155) (layer "F.Cu") (net 330))
  (segment (start 96.060001 143.04) (end 96.38875 143.04) (width 0.155) (layer "F.Cu") (net 330))
  (via (at 102.1 143.9) (size 0.6) (drill 0.25) (layers "F.Cu" "B.Cu") (net 330))
  (via (at 96.61125 143.2625) (size 0.6) (drill 0.25) (layers "F.Cu" "B.Cu") (net 330))
  (segment (start 101.55799 144.94) (end 99.64201 144.94) (width 0.155) (layer "In2.Cu") (net 330))
  (segment (start 99.06 144.35799) (end 99.06 143.45799) (width 0.155) (layer "In2.Cu") (net 330))
  (segment (start 96.83375 143.04) (end 96.61125 143.2625) (width 0.155) (layer "In2.Cu") (net 330))
  (segment (start 102.1 143.9) (end 101.84 144.16) (width 0.155) (layer "In2.Cu") (net 330))
  (segment (start 101.84 144.65799) (end 101.55799 144.94) (width 0.155) (layer "In2.Cu") (net 330))
  (segment (start 101.84 144.16) (end 101.84 144.65799) (width 0.155) (layer "In2.Cu") (net 330))
  (segment (start 99.06 143.45799) (end 98.64201 143.04) (width 0.155) (layer "In2.Cu") (net 330))
  (segment (start 98.64201 143.04) (end 96.83375 143.04) (width 0.155) (layer "In2.Cu") (net 330))
  (segment (start 99.64201 144.94) (end 99.06 144.35799) (width 0.155) (layer "In2.Cu") (net 330))
  (segment (start 95.8875 143.4) (end 96.47375 143.4) (width 0.15) (layer "B.Cu") (net 330))
  (segment (start 96.47375 143.4) (end 96.61125 143.2625) (width 0.15) (layer "B.Cu") (net 330))
  (segment (start 95.1125 143.4) (end 95.8875 143.4) (width 0.15) (layer "B.Cu") (net 330))
  (segment (start 100.75 144.15) (end 101 143.9) (width 0.155) (layer "F.Cu") (net 331))
  (segment (start 101 143.9) (end 101.3 143.9) (width 0.155) (layer "F.Cu") (net 331))
  (segment (start 100.75 144.74) (end 100.75 144.15) (width 0.155) (layer "F.Cu") (net 331))
  (segment (start 95.475 142.7) (end 96.000001 142.7) (width 0.155) (layer "F.Cu") (net 331))
  (segment (start 96.000001 142.7) (end 96.060001 142.76) (width 0.155) (layer "F.Cu") (net 331))
  (segment (start 96.060001 142.76) (end 96.38875 142.76) (width 0.155) (layer "F.Cu") (net 331))
  (segment (start 96.38875 142.76) (end 96.61125 142.5375) (width 0.155) (layer "F.Cu") (net 331))
  (via (at 101.3 143.9) (size 0.6) (drill 0.25) (layers "F.Cu" "B.Cu") (net 331))
  (via (at 96.61125 142.5375) (size 0.6) (drill 0.25) (layers "F.Cu" "B.Cu") (net 331))
  (segment (start 101.56 144.16) (end 101.56 144.54201) (width 0.155) (layer "In2.Cu") (net 331))
  (segment (start 99.75799 144.66) (end 99.34 144.24201) (width 0.155) (layer "In2.Cu") (net 331))
  (segment (start 101.56 144.54201) (end 101.44201 144.66) (width 0.155) (layer "In2.Cu") (net 331))
  (segment (start 98.75799 142.76) (end 96.83375 142.76) (width 0.155) (layer "In2.Cu") (net 331))
  (segment (start 101.3 143.9) (end 101.56 144.16) (width 0.155) (layer "In2.Cu") (net 331))
  (segment (start 96.83375 142.76) (end 96.61125 142.5375) (width 0.155) (layer "In2.Cu") (net 331))
  (segment (start 99.34 143.34201) (end 98.75799 142.76) (width 0.155) (layer "In2.Cu") (net 331))
  (segment (start 101.44201 144.66) (end 99.75799 144.66) (width 0.155) (layer "In2.Cu") (net 331))
  (segment (start 99.34 144.24201) (end 99.34 143.34201) (width 0.155) (layer "In2.Cu") (net 331))
  (segment (start 96.47375 142.4) (end 96.61125 142.5375) (width 0.15) (layer "B.Cu") (net 331))
  (segment (start 95.8875 142.4) (end 96.47375 142.4) (width 0.15) (layer "B.Cu") (net 331))
  (segment (start 95.8875 142.4) (end 95.1125 142.4) (width 0.15) (layer "B.Cu") (net 331))
  (segment (start 93.335 129) (end 94 129) (width 0.15) (layer "F.Cu") (net 332))
  (segment (start 85.8 139) (end 85.2 139.6) (width 0.15) (layer "F.Cu") (net 332))
  (segment (start 85.8 138.205) (end 85.8 139) (width 0.15) (layer "F.Cu") (net 332))
  (segment (start 94 129) (end 94.665 129) (width 0.15) (layer "F.Cu") (net 332))
  (via (at 85.2 139.6) (size 0.6) (drill 0.25) (layers "F.Cu" "B.Cu") (net 332))
  (via (at 94 129) (size 0.6) (drill 0.25) (layers "F.Cu" "B.Cu") (net 332))
  (segment (start 87.6 136.6) (end 87.6 136) (width 0.15) (layer "B.Cu") (net 332))
  (segment (start 93.209624 133.750009) (end 93.800007 133.159626) (width 0.15) (layer "B.Cu") (net 332))
  (segment (start 85.6 139.2) (end 85.6 138.6) (width 0.15) (layer "B.Cu") (net 332))
  (segment (start 94 129) (end 94.4508 129) (width 0.15) (layer "B.Cu") (net 332))
  (segment (start 93.800007 133.159626) (end 93.800007 132.599993) (width 0.15) (layer "B.Cu") (net 332))
  (segment (start 87.6 134.375722) (end 88.215358 133.760364) (width 0.15) (layer "B.Cu") (net 332))
  (segment (start 94.9508 129.5) (end 94.4508 129) (width 0.15) (layer "B.Cu") (net 332))
  (segment (start 87.6 134.375722) (end 88.225713 133.750009) (width 0.15) (layer "B.Cu") (net 332))
  (segment (start 88.225713 133.750009) (end 93.209624 133.750009) (width 0.15) (layer "B.Cu") (net 332))
  (segment (start 93.800007 132.599993) (end 93.800007 129.199993) (width 0.15) (layer "B.Cu") (net 332))
  (segment (start 85.6 138.6) (end 87.6 136.6) (width 0.15) (layer "B.Cu") (net 332))
  (segment (start 93.800007 129.199993) (end 94 129) (width 0.15) (layer "B.Cu") (net 332))
  (segment (start 87.6 136) (end 87.6 134.375722) (width 0.15) (layer "B.Cu") (net 332))
  (segment (start 85.2 139.6) (end 85.6 139.2) (width 0.15) (layer "B.Cu") (net 332))
  (segment (start 84.7 137.025) (end 84.1 137.625) (width 0.15) (layer "F.Cu") (net 333))
  (segment (start 93.335 127) (end 94 127) (width 0.15) (layer "F.Cu") (net 333))
  (segment (start 94 127) (end 94.665 127) (width 0.15) (layer "F.Cu") (net 333))
  (segment (start 84.1 137.625) (end 84.1 138.25) (width 0.15) (layer "F.Cu") (net 333))
  (segment (start 85.12 137.025) (end 84.7 137.025) (width 0.15) (layer "F.Cu") (net 333))
  (via (at 84.1 138.25) (size 0.6) (drill 0.25) (layers "F.Cu" "B.Cu") (net 333))
  (via (at 94 127) (size 0.6) (drill 0.25) (layers "F.Cu" "B.Cu") (net 333))
  (segment (start 85 137.35) (end 84.1 138.25) (width 0.15) (layer "B.Cu") (net 333))
  (segment (start 89.7 127) (end 85 131.7) (width 0.15) (layer "B.Cu") (net 333))
  (segment (start 94 127) (end 89.7 127) (width 0.15) (layer "B.Cu") (net 333))
  (segment (start 85 131.7) (end 85 137.35) (width 0.15) (layer "B.Cu") (net 333))
  (segment (start 94 127) (end 94.9492 127) (width 0.2) (layer "B.Cu") (net 333))
  (segment (start 94 126) (end 94.665 126) (width 0.15) (layer "F.Cu") (net 334))
  (segment (start 93.335 126) (end 94 126) (width 0.15) (layer "F.Cu") (net 334))
  (segment (start 84.588922 136.025) (end 83.703922 135.14) (width 0.15) (layer "F.Cu") (net 334))
  (segment (start 85.12 136.025) (end 84.588922 136.025) (width 0.15) (layer "F.Cu") (net 334))
  (segment (start 83.703922 135.14) (end 83.44 135.14) (width 0.15) (layer "F.Cu") (net 334))
  (via (at 83.44 135.14) (size 0.6) (drill 0.25) (layers "F.Cu" "B.Cu") (net 334))
  (via (at 94 126) (size 0.6) (drill 0.25) (layers "F.Cu" "B.Cu") (net 334))
  (segment (start 89.52501 126.67499) (end 84.65 131.55) (width 0.15) (layer "B.Cu") (net 334))
  (segment (start 94 126) (end 93.32501 126.67499) (width 0.15) (layer "B.Cu") (net 334))
  (segment (start 84.65 135.013623) (end 84.341056 135.322567) (width 0.15) (layer "B.Cu") (net 334))
  (segment (start 93.32501 126.67499) (end 89.52501 126.67499) (width 0.15) (layer "B.Cu") (net 334))
  (segment (start 84.341056 135.322567) (end 83.622567 135.322567) (width 0.15) (layer "B.Cu") (net 334))
  (segment (start 84.65 131.55) (end 84.65 135.013623) (width 0.15) (layer "B.Cu") (net 334))
  (segment (start 94 126) (end 94.8008 126) (width 0.2) (layer "B.Cu") (net 334))
  (segment (start 83.622567 135.322567) (end 83.44 135.14) (width 0.15) (layer "B.Cu") (net 334))
  (segment (start 93.335 128) (end 94 128) (width 0.15) (layer "F.Cu") (net 335))
  (segment (start 86.3 133.4) (end 86 133.1) (width 0.15) (layer "F.Cu") (net 335))
  (segment (start 94 128) (end 94.665 128) (width 0.15) (layer "F.Cu") (net 335))
  (segment (start 86.3 134.345) (end 86.3 133.4) (width 0.15) (layer "F.Cu") (net 335))
  (via (at 94 128) (size 0.6) (drill 0.25) (layers "F.Cu" "B.Cu") (net 335))
  (via (at 86 133.1) (size 0.6) (drill 0.25) (layers "F.Cu" "B.Cu") (net 335))
  (segment (start 93.100001 133.399999) (end 93.474999 133.025001) (width 0.15) (layer "B.Cu") (net 335))
  (segment (start 93.474999 133.025001) (end 93.474999 128.525001) (width 0.15) (layer "B.Cu") (net 335))
  (segment (start 86 133.1) (end 86.299999 133.399999) (width 0.15) (layer "B.Cu") (net 335))
  (segment (start 94.7492 128) (end 95 128.2508) (width 0.2) (layer "B.Cu") (net 335))
  (segment (start 94 128) (end 94.7492 128) (width 0.2) (layer "B.Cu") (net 335))
  (segment (start 93.474999 128.525001) (end 94 128) (width 0.15) (layer "B.Cu") (net 335))
  (segment (start 86.299999 133.399999) (end 93.100001 133.399999) (width 0.15) (layer "B.Cu") (net 335))
  (segment (start 99.25 116.75) (end 99.2 116.7) (width 0.3) (layer "F.Cu") (net 336))
  (segment (start 99.25 118.55) (end 99.25 116.75) (width 0.3) (layer "F.Cu") (net 336))
  (via (at 99.2 116.7) (size 0.6) (drill 0.25) (layers "F.Cu" "B.Cu") (net 336))
  (segment (start 100 115.9) (end 99.2 116.7) (width 0.3) (layer "B.Cu") (net 336))
  (segment (start 147 87.4) (end 144.875 87.4) (width 0.15) (layer "F.Cu") (net 337))
  (segment (start 114.55 107.995) (end 114.945 107.995) (width 0.15) (layer "F.Cu") (net 337))
  (segment (start 114.945 107.995) (end 115.05 108.1) (width 0.15) (layer "F.Cu") (net 337))
  (segment (start 115.05 108.1) (end 115.615 108.1) (width 0.15) (layer "F.Cu") (net 337))
  (via (at 115.05 108.1) (size 0.6) (drill 0.25) (layers "F.Cu" "B.Cu") (net 337))
  (via (at 147 87.4) (size 0.6) (drill 0.25) (layers "F.Cu" "B.Cu") (net 337))
  (segment (start 147 87.4) (end 146.57501 87.82499) (width 0.15) (layer "In2.Cu") (net 337))
  (segment (start 132.4 106.5) (end 124.6 106.5) (width 0.15) (layer "In2.Cu") (net 337))
  (segment (start 146.57501 87.82499) (end 146.575008 94.213914) (width 0.15) (layer "In2.Cu") (net 337))
  (segment (start 140.72499 100.063932) (end 140.72499 104.252854) (width 0.15) (layer "In2.Cu") (net 337))
  (segment (start 140.177846 104.799998) (end 139.800002 104.799998) (width 0.15) (layer "In2.Cu") (net 337))
  (segment (start 115.35 107.8) (end 115.05 108.1) (width 0.15) (layer "In2.Cu") (net 337))
  (segment (start 124.6 106.5) (end 124.400001 106.699999) (width 0.15) (layer "In2.Cu") (net 337))
  (segment (start 140.72499 104.252854) (end 140.177846 104.799998) (width 0.15) (layer "In2.Cu") (net 337))
  (segment (start 146.575008 94.213914) (end 140.72499 100.063932) (width 0.15) (layer "In2.Cu") (net 337))
  (segment (start 119.200001 106.699999) (end 118.1 107.8) (width 0.15) (layer "In2.Cu") (net 337))
  (segment (start 118.1 107.8) (end 115.35 107.8) (width 0.15) (layer "In2.Cu") (net 337))
  (segment (start 139.800002 104.799998) (end 139.8 104.8) (width 0.15) (layer "In2.Cu") (net 337))
  (segment (start 139.8 104.8) (end 134.1 104.8) (width 0.15) (layer "In2.Cu") (net 337))
  (segment (start 134.1 104.8) (end 132.4 106.5) (width 0.15) (layer "In2.Cu") (net 337))
  (segment (start 124.400001 106.699999) (end 119.200001 106.699999) (width 0.15) (layer "In2.Cu") (net 337))
  (segment (start 115.05 108.1) (end 115.7492 108.1) (width 0.15) (layer "B.Cu") (net 337))
  (segment (start 114.55 107.41) (end 114.94 107.41) (width 0.15) (layer "F.Cu") (net 338))
  (segment (start 115.05 107.3) (end 115.615 107.3) (width 0.15) (layer "F.Cu") (net 338))
  (segment (start 114.94 107.41) (end 115.05 107.3) (width 0.15) (layer "F.Cu") (net 338))
  (segment (start 144.875 86.4) (end 146.6 86.4) (width 0.15) (layer "F.Cu") (net 338))
  (via (at 146.6 86.4) (size 0.6) (drill 0.25) (layers "F.Cu" "B.Cu") (net 338))
  (via (at 115.05 107.3) (size 0.6) (drill 0.25) (layers "F.Cu" "B.Cu") (net 338))
  (segment (start 115.32499 107.52499) (end 117.97501 107.52499) (width 0.15) (layer "In2.Cu") (net 338))
  (segment (start 133.986088 104.52499) (end 135.67501 104.52499) (width 0.15) (layer "In2.Cu") (net 338))
  (segment (start 118.075 107.425) (end 118.086078 107.425) (width 0.15) (layer "In2.Cu") (net 338))
  (segment (start 124.486088 106.22499) (end 124.72501 106.22499) (width 0.15) (layer "In2.Cu") (net 338))
  (segment (start 115.1 107.3) (end 115.32499 107.52499) (width 0.15) (layer "In2.Cu") (net 338))
  (segment (start 115.05 107.3) (end 115.1 107.3) (width 0.15) (layer "In2.Cu") (net 338))
  (segment (start 146.3 94.1) (end 146.300001 86.699999) (width 0.15) (layer "In2.Cu") (net 338))
  (segment (start 117.97501 107.52499) (end 118.075 107.425) (width 0.15) (layer "In2.Cu") (net 338))
  (segment (start 124.72501 106.22499) (end 129.77501 106.22499) (width 0.15) (layer "In2.Cu") (net 338))
  (segment (start 129.77501 106.22499) (end 132.286088 106.22499) (width 0.15) (layer "In2.Cu") (net 338))
  (segment (start 140.063932 104.52499) (end 140.44998 104.138942) (width 0.15) (layer "In2.Cu") (net 338))
  (segment (start 118.086078 107.425) (end 119.086089 106.424989) (width 0.15) (layer "In2.Cu") (net 338))
  (segment (start 140.44998 99.95002) (end 146.3 94.1) (width 0.15) (layer "In2.Cu") (net 338))
  (segment (start 135.77501 104.52499) (end 140.063932 104.52499) (width 0.15) (layer "In2.Cu") (net 338))
  (segment (start 146.300001 86.699999) (end 146.6 86.4) (width 0.15) (layer "In2.Cu") (net 338))
  (segment (start 124.286089 106.424989) (end 124.486088 106.22499) (width 0.15) (layer "In2.Cu") (net 338))
  (segment (start 140.44998 104.138942) (end 140.44998 99.95002) (width 0.15) (layer "In2.Cu") (net 338))
  (segment (start 132.286088 106.22499) (end 133.986088 104.52499) (width 0.15) (layer "In2.Cu") (net 338))
  (segment (start 135.67501 104.52499) (end 135.77501 104.52499) (width 0.15) (layer "In2.Cu") (net 338))
  (segment (start 119.086089 106.424989) (end 124.286089 106.424989) (width 0.15) (layer "In2.Cu") (net 338))
  (segment (start 115.6508 107.3) (end 115.9 107.0508) (width 0.15) (layer "B.Cu") (net 338))
  (segment (start 115.05 107.3) (end 115.6508 107.3) (width 0.15) (layer "B.Cu") (net 338))
  (segment (start 72.671096 120.94998) (end 73.04998 120.94998) (width 0.15) (layer "F.Cu") (net 339))
  (segment (start 75.115 136.9) (end 75.515 137.3) (width 0.15) (layer "F.Cu") (net 339))
  (segment (start 72.121076 121.5) (end 72.671096 120.94998) (width 0.15) (layer "F.Cu") (net 339))
  (segment (start 70.749983 122.949983) (end 70.749983 121.550017) (width 0.15) (layer "F.Cu") (net 339))
  (segment (start 76.5 122.447601) (end 76.5 122.006278) (width 0.15) (layer "F.Cu") (net 339))
  (segment (start 70.749984 133.494594) (end 74 136.74461) (width 0.15) (layer "F.Cu") (net 339))
  (segment (start 74 136.9) (end 75.115 136.9) (width 0.15) (layer "F.Cu") (net 339))
  (segment (start 70.8 121.5) (end 72.121076 121.5) (width 0.15) (layer "F.Cu") (net 339))
  (segment (start 75.443702 120.94998) (end 73.04998 120.94998) (width 0.15) (layer "F.Cu") (net 339))
  (segment (start 70.749983 122.949983) (end 70.749984 133.494594) (width 0.15) (layer "F.Cu") (net 339))
  (segment (start 70.749983 121.550017) (end 70.8 121.5) (width 0.15) (layer "F.Cu") (net 339))
  (segment (start 76.5 122.006278) (end 75.443702 120.94998) (width 0.15) (layer "F.Cu") (net 339))
  (segment (start 74 136.74461) (end 74 136.9) (width 0.15) (layer "F.Cu") (net 339))
  (via (at 80.85 145.45) (size 0.6) (drill 0.25) (layers "F.Cu" "B.Cu") (net 339))
  (via (at 70.8 121.5) (size 0.6) (drill 0.25) (layers "F.Cu" "B.Cu") (net 339))
  (via (at 74 136.9) (size 0.6) (drill 0.25) (layers "F.Cu" "B.Cu") (net 339))
  (via (at 81.7 126.4) (size 0.6) (drill 0.25) (layers "F.Cu" "B.Cu") (net 339))
  (segment (start 80.7 126.4) (end 81.7 126.4) (width 0.125) (layer "In2.Cu") (net 339))
  (segment (start 80.35001 126.05001) (end 80.7 126.4) (width 0.125) (layer "In2.Cu") (net 339))
  (segment (start 70.812499 122.434001) (end 71 122.621502) (width 0.125) (layer "In2.Cu") (net 339))
  (segment (start 71 122.621502) (end 71 125.553567) (width 0.125) (layer "In2.Cu") (net 339))
  (segment (start 70.8 121.5) (end 70.812499 121.512499) (width 0.125) (layer "In2.Cu") (net 339))
  (segment (start 71 125.553567) (end 71.496443 126.05001) (width 0.125) (layer "In2.Cu") (net 339))
  (segment (start 71.496443 126.05001) (end 80.35001 126.05001) (width 0.125) (layer "In2.Cu") (net 339))
  (segment (start 70.812499 121.512499) (end 70.812499 122.434001) (width 0.125) (layer "In2.Cu") (net 339))
  (segment (start 74 136.9) (end 75.15 136.9) (width 0.15) (layer "In3.Cu") (net 339))
  (segment (start 79.75 143.99892) (end 79.75 144) (width 0.15) (layer "In3.Cu") (net 339))
  (segment (start 75.15 136.9) (end 79.524999 141.274999) (width 0.15) (layer "In3.Cu") (net 339))
  (segment (start 79.75 144) (end 80.85 145.1) (width 0.15) (layer "In3.Cu") (net 339))
  (segment (start 79.524999 141.274999) (end 79.524999 143.773919) (width 0.15) (layer "In3.Cu") (net 339))
  (segment (start 80.85 145.1) (end 80.85 145.45) (width 0.15) (layer "In3.Cu") (net 339))
  (segment (start 79.524999 143.773919) (end 79.75 143.99892) (width 0.15) (layer "In3.Cu") (net 339))
  (segment (start 78.2 127.2008) (end 78.5992 127.6) (width 0.125) (layer "B.Cu") (net 339))
  (segment (start 80.85 146.15) (end 80.85 145.45) (width 0.15) (layer "B.Cu") (net 339))
  (segment (start 81.7 126.971502) (end 81.7 126.4) (width 0.125) (layer "B.Cu") (net 339))
  (segment (start 78.5992 127.6) (end 81.071502 127.6) (width 0.125) (layer "B.Cu") (net 339))
  (segment (start 81.071502 127.6) (end 81.7 126.971502) (width 0.125) (layer "B.Cu") (net 339))
  (segment (start 85.485 104.185) (end 86.385 104.185) (width 0.15) (layer "F.Cu") (net 340))
  (segment (start 75.5 122.447601) (end 75.5 121.9) (width 0.15) (layer "F.Cu") (net 340))
  (segment (start 73.25 121.5) (end 73.75 121.5) (width 0.15) (layer "F.Cu") (net 340))
  (segment (start 85.35 103.65) (end 85.35 104.05) (width 0.15) (layer "F.Cu") (net 340))
  (segment (start 84.85 103.65) (end 84.6 103.9) (width 0.2) (layer "F.Cu") (net 340))
  (segment (start 86.385 104.185) (end 86.625 104.185) (width 0.15) (layer "F.Cu") (net 340))
  (segment (start 86.9 104.185) (end 86.385 104.185) (width 0.15) (layer "F.Cu") (net 340))
  (segment (start 75.5 121.9) (end 75.1 121.5) (width 0.15) (layer "F.Cu") (net 340))
  (segment (start 85.35 103.65) (end 84.85 103.65) (width 0.2) (layer "F.Cu") (net 340))
  (segment (start 72.7 122.05) (end 72.7 121.75) (width 0.15) (layer "F.Cu") (net 340))
  (segment (start 75.1 121.5) (end 73.75 121.5) (width 0.15) (layer "F.Cu") (net 340))
  (segment (start 85.35 104.05) (end 85.485 104.185) (width 0.15) (layer "F.Cu") (net 340))
  (segment (start 72.7 121.75) (end 72.95 121.5) (width 0.15) (layer "F.Cu") (net 340))
  (segment (start 72.95 121.5) (end 73.25 121.5) (width 0.15) (layer "F.Cu") (net 340))
  (via (at 81.65 124.35) (size 0.6) (drill 0.25) (layers "F.Cu" "B.Cu") (net 340))
  (via (at 84.6 103.9) (size 0.6) (drill 0.25) (layers "F.Cu" "B.Cu") (net 340))
  (via (at 72.7 122.05) (size 0.6) (drill 0.25) (layers "F.Cu" "B.Cu") (net 340))
  (segment (start 73 124.1) (end 72.999999 122.349999) (width 0.125) (layer "In2.Cu") (net 340))
  (segment (start 72.999999 122.349999) (end 72.7 122.05) (width 0.125) (layer "In2.Cu") (net 340))
  (segment (start 81.65 124.35) (end 81.612499 124.387501) (width 0.125) (layer "In2.Cu") (net 340))
  (segment (start 81.612499 124.387501) (end 73.287501 124.387501) (width 0.125) (layer "In2.Cu") (net 340))
  (segment (start 73.287501 124.387501) (end 73 124.1) (width 0.125) (layer "In2.Cu") (net 340))
  (segment (start 73.6 121.15) (end 72.7 122.05) (width 0.15) (layer "In3.Cu") (net 340))
  (segment (start 84.6 103.9) (end 84.2 103.5) (width 0.15) (layer "In3.Cu") (net 340))
  (segment (start 84.2 103.5) (end 75.2 103.5) (width 0.15) (layer "In3.Cu") (net 340))
  (segment (start 75.2 103.5) (end 73.6 105.1) (width 0.15) (layer "In3.Cu") (net 340))
  (segment (start 73.6 105.1) (end 73.6 121.15) (width 0.15) (layer "In3.Cu") (net 340))
  (segment (start 81.6 124.4) (end 78.5492 124.4) (width 0.15) (layer "B.Cu") (net 340))
  (segment (start 78.5492 124.4) (end 78.2 124.0508) (width 0.15) (layer "B.Cu") (net 340))
  (segment (start 81.65 124.35) (end 81.6 124.4) (width 0.15) (layer "B.Cu") (net 340))
  (segment (start 73.37501 121.22499) (end 72.785008 121.22499) (width 0.15) (layer "F.Cu") (net 341))
  (segment (start 73.944312 136.3) (end 74.6 136.3) (width 0.15) (layer "F.Cu") (net 341))
  (segment (start 71.02499 123.22499) (end 71.02499 122.47501) (width 0.15) (layer "F.Cu") (net 341))
  (segment (start 75.515 136.3) (end 74.6 136.3) (width 0.15) (layer "F.Cu") (net 341))
  (segment (start 71.809998 122.2) (end 71.3 122.2) (width 0.15) (layer "F.Cu") (net 341))
  (segment (start 75.32979 121.22499) (end 73.37501 121.22499) (width 0.15) (layer "F.Cu") (net 341))
  (segment (start 71.02499 123.22499) (end 71.02499 124.446088) (width 0.15) (layer "F.Cu") (net 341))
  (segment (start 71.02499 124.446088) (end 71.024992 133.38068) (width 0.15) (layer "F.Cu") (net 341))
  (segment (start 73.37501 121.22499) (end 72.986088 121.22499) (width 0.15) (layer "F.Cu") (net 341))
  (segment (start 72.986088 121.22499) (end 72.986086 121.224992) (width 0.15) (layer "F.Cu") (net 341))
  (segment (start 71.024992 133.38068) (end 73.944312 136.3) (width 0.15) (layer "F.Cu") (net 341))
  (segment (start 72.986088 121.22499) (end 72.785008 121.22499) (width 0.15) (layer "F.Cu") (net 341))
  (segment (start 71.02499 122.47501) (end 71.3 122.2) (width 0.15) (layer "F.Cu") (net 341))
  (segment (start 76.000001 122.447601) (end 76.000001 121.895201) (width 0.15) (layer "F.Cu") (net 341))
  (segment (start 72.785008 121.22499) (end 71.809998 122.2) (width 0.15) (layer "F.Cu") (net 341))
  (segment (start 76.000001 121.895201) (end 75.32979 121.22499) (width 0.15) (layer "F.Cu") (net 341))
  (via (at 71.3 122.2) (size 0.6) (drill 0.25) (layers "F.Cu" "B.Cu") (net 341))
  (via (at 74.6 136.3) (size 0.6) (drill 0.25) (layers "F.Cu" "B.Cu") (net 341))
  (via (at 81.75 125.4) (size 0.6) (drill 0.25) (layers "F.Cu" "B.Cu") (net 341))
  (via (at 83 147.25) (size 0.6) (drill 0.25) (layers "F.Cu" "B.Cu") (net 341))
  (segment (start 71.3 125.5) (end 71.6 125.8) (width 0.125) (layer "In2.Cu") (net 341))
  (segment (start 71.6 125.8) (end 80.4 125.8) (width 0.125) (layer "In2.Cu") (net 341))
  (segment (start 80.8 125.4) (end 81.75 125.4) (width 0.125) (layer "In2.Cu") (net 341))
  (segment (start 71.3 122.2) (end 71.3 125.5) (width 0.125) (layer "In2.Cu") (net 341))
  (segment (start 80.4 125.8) (end 80.8 125.4) (width 0.125) (layer "In2.Cu") (net 341))
  (segment (start 75.263914 136.624992) (end 74.924992 136.624992) (width 0.15) (layer "In3.Cu") (net 341))
  (segment (start 79.800009 141.161087) (end 75.263914 136.624992) (width 0.15) (layer "In3.Cu") (net 341))
  (segment (start 83 147.25) (end 83 146.859998) (width 0.15) (layer "In3.Cu") (net 341))
  (segment (start 74.924992 136.624992) (end 74.6 136.3) (width 0.15) (layer "In3.Cu") (net 341))
  (segment (start 83 146.859998) (end 79.800009 143.660007) (width 0.15) (layer "In3.Cu") (net 341))
  (segment (start 79.800009 143.660007) (end 79.800009 141.161087) (width 0.15) (layer "In3.Cu") (net 341))
  (segment (start 80.809998 125.4) (end 80.284999 125.924999) (width 0.15) (layer "B.Cu") (net 341))
  (segment (start 95.8 146.35) (end 92.65 146.35) (width 0.15) (layer "B.Cu") (net 341))
  (segment (start 83 147.25) (end 91.75 147.25) (width 0.155) (layer "B.Cu") (net 341))
  (segment (start 81.75 125.4) (end 80.809998 125.4) (width 0.15) (layer "B.Cu") (net 341))
  (segment (start 78.574999 125.924999) (end 78.2 125.55) (width 0.15) (layer "B.Cu") (net 341))
  (segment (start 91.75 147.25) (end 92.65 146.35) (width 0.155) (layer "B.Cu") (net 341))
  (segment (start 80.284999 125.924999) (end 78.574999 125.924999) (width 0.15) (layer "B.Cu") (net 341))
  (segment (start 85.45 124.185) (end 84.385 124.185) (width 0.15) (layer "F.Cu") (net 342))
  (segment (start 151.37 107.95) (end 150.435 107.95) (width 0.15) (layer "F.Cu") (net 343))
  (segment (start 153.747499 106.602501) (end 150.252501 106.602501) (width 0.155) (layer "F.Cu") (net 343))
  (segment (start 149.95 106.3) (end 149.95 107.465) (width 0.15) (layer "F.Cu") (net 343))
  (segment (start 149.95 107.465) (end 150.385 107.9) (width 0.15) (layer "F.Cu") (net 343))
  (segment (start 149.95 94.3) (end 149.95 95.215) (width 0.15) (layer "F.Cu") (net 344))
  (segment (start 149.95 95.215) (end 150.635 95.9) (width 0.15) (layer "F.Cu") (net 344))
  (segment (start 151.62 95.9) (end 150.635 95.9) (width 0.15) (layer "F.Cu") (net 344))
  (segment (start 154.05 94.3) (end 149.95 94.3) (width 0.155) (layer "F.Cu") (net 344))
  (segment (start 149.95 100.3) (end 149.95 101.465) (width 0.15) (layer "F.Cu") (net 345))
  (segment (start 154.05 100.3) (end 149.95 100.3) (width 0.155) (layer "F.Cu") (net 345))
  (segment (start 151.35 101.9) (end 150.385 101.9) (width 0.15) (layer "F.Cu") (net 345))
  (segment (start 149.95 101.465) (end 150.385 101.9) (width 0.15) (layer "F.Cu") (net 345))
  (segment (start 150.5 112.3) (end 149.95 112.3) (width 0.155) (layer "F.Cu") (net 346))
  (segment (start 154.05 112.3) (end 150.5 112.3) (width 0.155) (layer "F.Cu") (net 346))
  (segment (start 149.95 113.465) (end 150.385 113.9) (width 0.15) (layer "F.Cu") (net 346))
  (segment (start 151.37 113.9) (end 150.385 113.9) (width 0.15) (layer "F.Cu") (net 346))
  (segment (start 149.95 112.3) (end 149.95 113.465) (width 0.15) (layer "F.Cu") (net 346))
  (segment (start 81.615 103.665) (end 84.05 106.1) (width 0.2) (layer "F.Cu") (net 347))
  (segment (start 84.05 106.1) (end 84.5 106.1) (width 0.2) (layer "F.Cu") (net 347))
  (segment (start 85.45 123.215) (end 84.515 123.215) (width 0.15) (layer "F.Cu") (net 348))
  (segment (start 84.515 123.215) (end 84.3 123) (width 0.15) (layer "F.Cu") (net 348))
  (via (at 84.3 123) (size 0.6) (drill 0.25) (layers "F.Cu" "B.Cu") (net 348))
  (segment (start 84.2 121.95) (end 84.2 122.9) (width 0.15) (layer "B.Cu") (net 348))
  (segment (start 84.2 122.9) (end 84.3 123) (width 0.15) (layer "B.Cu") (net 348))
  (segment (start 98.75 113.75) (end 98.7 113.8) (width 0.15) (layer "F.Cu") (net 349))
  (segment (start 98.75 112.45) (end 98.75 113.75) (width 0.15) (layer "F.Cu") (net 349))
  (via (at 121.1 132.1) (size 0.6) (drill 0.25) (layers "F.Cu" "B.Cu") (net 349))
  (via (at 98.7 113.8) (size 0.6) (drill 0.25) (layers "F.Cu" "B.Cu") (net 349))
  (segment (start 121.399999 131.800001) (end 121.1 132.1) (width 0.15) (layer "In2.Cu") (net 349))
  (segment (start 112.7 116.7) (end 112.7 120.4) (width 0.15) (layer "In2.Cu") (net 349))
  (segment (start 111.2 115.6) (end 111.6 115.6) (width 0.15) (layer "In2.Cu") (net 349))
  (segment (start 98.2 117.8) (end 96.2 117.8) (width 0.15) (layer "In2.Cu") (net 349))
  (segment (start 113.7 121.4) (end 121.1 121.4) (width 0.15) (layer "In2.Cu") (net 349))
  (segment (start 121.399999 121.699999) (end 121.399999 131.800001) (width 0.15) (layer "In2.Cu") (net 349))
  (segment (start 95.8 117.4) (end 95.8 114.1) (width 0.15) (layer "In2.Cu") (net 349))
  (segment (start 112.7 120.4) (end 113.7 121.4) (width 0.15) (layer "In2.Cu") (net 349))
  (segment (start 96.1 113.8) (end 98.7 113.8) (width 0.15) (layer "In2.Cu") (net 349))
  (segment (start 98.2 117.8) (end 98.6 117.4) (width 0.15) (layer "In2.Cu") (net 349))
  (segment (start 98.6 116.2) (end 98.6 117.4) (width 0.15) (layer "In2.Cu") (net 349))
  (segment (start 111.6 115.6) (end 112.7 116.7) (width 0.15) (layer "In2.Cu") (net 349))
  (segment (start 99.2 115.6) (end 98.6 116.2) (width 0.15) (layer "In2.Cu") (net 349))
  (segment (start 111.2 115.6) (end 99.2 115.6) (width 0.15) (layer "In2.Cu") (net 349))
  (segment (start 95.8 114.1) (end 96.1 113.8) (width 0.15) (layer "In2.Cu") (net 349))
  (segment (start 96.2 117.8) (end 95.8 117.4) (width 0.15) (layer "In2.Cu") (net 349))
  (segment (start 121.1 121.4) (end 121.399999 121.699999) (width 0.15) (layer "In2.Cu") (net 349))
  (segment (start 144.7 136.6) (end 146 136.6) (width 0.15) (layer "B.Cu") (net 349))
  (segment (start 137.067049 133.96999) (end 143.96999 133.96999) (width 0.15) (layer "B.Cu") (net 349))
  (segment (start 121.2 132.1) (end 121.42499 131.87501) (width 0.15) (layer "B.Cu") (net 349))
  (segment (start 144.3 134.3) (end 144.3 136.2) (width 0.15) (layer "B.Cu") (net 349))
  (segment (start 146.15 136.75) (end 146.15 137.25) (width 0.15) (layer "B.Cu") (net 349))
  (segment (start 143.96999 133.96999) (end 144.3 134.3) (width 0.15) (layer "B.Cu") (net 349))
  (segment (start 146 136.6) (end 146.15 136.75) (width 0.15) (layer "B.Cu") (net 349))
  (segment (start 121.42499 131.87501) (end 134.972069 131.87501) (width 0.15) (layer "B.Cu") (net 349))
  (segment (start 144.3 136.2) (end 144.7 136.6) (width 0.15) (layer "B.Cu") (net 349))
  (segment (start 121.1 132.1) (end 121.2 132.1) (width 0.15) (layer "B.Cu") (net 349))
  (segment (start 134.972069 131.87501) (end 137.067049 133.96999) (width 0.15) (layer "B.Cu") (net 349))
  (segment (start 131.666362 113.85864) (end 131.112436 113.85864) (width 0.15) (layer "F.Cu") (net 350))
  (segment (start 132.25 112.45) (end 132.25 113.275002) (width 0.15) (layer "F.Cu") (net 350))
  (segment (start 130 114.971076) (end 130 115.2) (width 0.15) (layer "F.Cu") (net 350))
  (segment (start 132.25 113.275002) (end 131.666362 113.85864) (width 0.15) (layer "F.Cu") (net 350))
  (segment (start 131.112436 113.85864) (end 130 114.971076) (width 0.15) (layer "F.Cu") (net 350))
  (via (at 130 115.2) (size 0.6) (drill 0.25) (layers "F.Cu" "B.Cu") (net 350))
  (via (at 145.3 134.5) (size 0.6) (drill 0.25) (layers "F.Cu" "B.Cu") (net 350))
  (segment (start 130 115.2) (end 130 115.711078) (width 0.15) (layer "In2.Cu") (net 350))
  (segment (start 144.099999 133.999999) (end 144.099999 131.459999) (width 0.15) (layer "In2.Cu") (net 350))
  (segment (start 136 118.9) (end 133.5 118.9) (width 0.125) (layer "In2.Cu") (net 350))
  (segment (start 138.5 120.6) (end 136.8 118.9) (width 0.15) (layer "In2.Cu") (net 350))
  (segment (start 132.640324 118.06248) (end 132.66248 118.06248) (width 0.15) (layer "In2.Cu") (net 350))
  (segment (start 132.66248 118.06248) (end 133.5 118.9) (width 0.15) (layer "In2.Cu") (net 350))
  (segment (start 144.099999 131.459999) (end 144.100001 131.459997) (width 0.15) (layer "In2.Cu") (net 350))
  (segment (start 130 115.711078) (end 130.67501 116.386088) (width 0.15) (layer "In2.Cu") (net 350))
  (segment (start 132.627824 118.04998) (end 132.640324 118.06248) (width 0.15) (layer "In2.Cu") (net 350))
  (segment (start 130.67501 117.757333) (end 130.967657 118.04998) (width 0.15) (layer "In2.Cu") (net 350))
  (segment (start 130.67501 116.386088) (end 130.67501 117.757333) (width 0.15) (layer "In2.Cu") (net 350))
  (segment (start 144.100001 131.459997) (end 144.100001 121.300001) (width 0.15) (layer "In2.Cu") (net 350))
  (segment (start 144.100001 121.300001) (end 143.4 120.6) (width 0.15) (layer "In2.Cu") (net 350))
  (segment (start 143.4 120.6) (end 138.5 120.6) (width 0.15) (layer "In2.Cu") (net 350))
  (segment (start 136 118.9) (end 136.6 118.9) (width 0.15) (layer "In2.Cu") (net 350))
  (segment (start 136.8 118.9) (end 136.6 118.9) (width 0.15) (layer "In2.Cu") (net 350))
  (segment (start 136.6 118.9) (end 133.5 118.9) (width 0.15) (layer "In2.Cu") (net 350))
  (segment (start 144.6 134.5) (end 144.099999 133.999999) (width 0.15) (layer "In2.Cu") (net 350))
  (segment (start 130.967657 118.04998) (end 132.627824 118.04998) (width 0.15) (layer "In2.Cu") (net 350))
  (segment (start 145.3 134.5) (end 144.6 134.5) (width 0.15) (layer "In2.Cu") (net 350))
  (segment (start 145.55 134.25) (end 145.3 134.5) (width 0.125) (layer "B.Cu") (net 350))
  (segment (start 146.15 134.25) (end 145.55 134.25) (width 0.125) (layer "B.Cu") (net 350))
  (segment (start 113.75 112.45) (end 113.75 113.428296) (width 0.155) (layer "F.Cu") (net 351))
  (segment (start 89.825 135.025) (end 90.49 135.025) (width 0.15) (layer "F.Cu") (net 351))
  (segment (start 113.75 113.428296) (end 113.515299 113.662997) (width 0.155) (layer "F.Cu") (net 351))
  (segment (start 88.98 135.025) (end 89.825 135.025) (width 0.15) (layer "F.Cu") (net 351))
  (via (at 89.825 135.025) (size 0.6) (drill 0.25) (layers "F.Cu" "B.Cu") (net 351))
  (via (at 113.515299 113.662997) (size 0.6) (drill 0.25) (layers "F.Cu" "B.Cu") (net 351))
  (via (at 111 124.700001) (size 0.6) (drill 0.25) (layers "F.Cu" "B.Cu") (net 351))
  (via (at 96.458284 129.707001) (size 0.6) (drill 0.25) (layers "F.Cu" "B.Cu") (net 351))
  (segment (start 110.4 124.21908) (end 110.880921 124.700001) (width 0.15) (layer "In2.Cu") (net 351))
  (segment (start 110.880921 124.700001) (end 111 124.700001) (width 0.15) (layer "In2.Cu") (net 351))
  (segment (start 97.37501 128.913912) (end 97.37501 128.202834) (width 0.15) (layer "In2.Cu") (net 351))
  (segment (start 98.45002 126.127824) (end 98.45002 124.44998) (width 0.15) (layer "In2.Cu") (net 351))
  (segment (start 96.458284 129.707001) (end 96.992999 129.707001) (width 0.15) (layer "In2.Cu") (net 351))
  (segment (start 97.65002 127.327824) (end 97.92503 127.052814) (width 0.15) (layer "In2.Cu") (net 351))
  (segment (start 97.92503 126.652814) (end 98.45002 126.127824) (width 0.15) (layer "In2.Cu") (net 351))
  (segment (start 110.4 124.2) (end 110.4 124.21908) (width 0.15) (layer "In2.Cu") (net 351))
  (segment (start 98.45002 124.44998) (end 98.725381 124.174619) (width 0.15) (layer "In2.Cu") (net 351))
  (segment (start 97.92503 127.052814) (end 97.92503 126.652814) (width 0.15) (layer "In2.Cu") (net 351))
  (segment (start 98.725381 124.174619) (end 110.374619 124.174619) (width 0.15) (layer "In2.Cu") (net 351))
  (segment (start 110.374619 124.174619) (end 110.4 124.2) (width 0.15) (layer "In2.Cu") (net 351))
  (segment (start 97.37501 128.202834) (end 97.65002 127.927824) (width 0.15) (layer "In2.Cu") (net 351))
  (segment (start 97.1 129.6) (end 97.1 129.188922) (width 0.15) (layer "In2.Cu") (net 351))
  (segment (start 97.65002 127.927824) (end 97.65002 127.327824) (width 0.15) (layer "In2.Cu") (net 351))
  (segment (start 96.992999 129.707001) (end 97.1 129.6) (width 0.15) (layer "In2.Cu") (net 351))
  (segment (start 97.1 129.188922) (end 97.37501 128.913912) (width 0.15) (layer "In2.Cu") (net 351))
  (segment (start 110.4 117.692458) (end 110.4 121.140002) (width 0.15) (layer "B.Cu") (net 351))
  (segment (start 110.4 124.100001) (end 111 124.700001) (width 0.155) (layer "B.Cu") (net 351))
  (segment (start 113.515299 113.662997) (end 113.515299 114.577159) (width 0.15) (layer "B.Cu") (net 351))
  (segment (start 96.3 129.865285) (end 96.3 134.4) (width 0.15) (layer "B.Cu") (net 351))
  (segment (start 89.8508 135.0508) (end 89.825 135.025) (width 0.15) (layer "B.Cu") (net 351))
  (segment (start 113.515299 114.577159) (end 110.4 117.692458) (width 0.15) (layer "B.Cu") (net 351))
  (segment (start 110.4 121.140002) (end 110.4 124.100001) (width 0.155) (layer "B.Cu") (net 351))
  (segment (start 96.3 134.4) (end 95.6492 135.0508) (width 0.15) (layer "B.Cu") (net 351))
  (segment (start 96.458284 129.707001) (end 96.3 129.865285) (width 0.15) (layer "B.Cu") (net 351))
  (segment (start 95.6492 135.0508) (end 89.8508 135.0508) (width 0.15) (layer "B.Cu") (net 351))
  (segment (start 132.415 138.9) (end 130.5 138.9) (width 0.2) (layer "F.Cu") (net 352))
  (segment (start 118.2 94.55) (end 118.3 94.45) (width 0.2) (layer "F.Cu") (net 353))
  (segment (start 118.3 96.3) (end 118.3 102.6) (width 0.5) (layer "F.Cu") (net 353))
  (segment (start 118.3 94.45) (end 118.3 93.5) (width 0.2) (layer "F.Cu") (net 353))
  (segment (start 117.85 94.55) (end 118.2 94.55) (width 0.2) (layer "F.Cu") (net 353))
  (via (at 117.85 94.55) (size 0.6) (drill 0.25) (layers "F.Cu" "B.Cu") (net 353))
  (segment (start 117.35 94.55) (end 117.85 94.55) (width 0.2) (layer "B.Cu") (net 353))
  (segment (start 73.297601 125.150001) (end 72.749999 125.150001) (width 0.15) (layer "F.Cu") (net 354))
  (segment (start 72.549999 125.150001) (end 72.5 125.2) (width 0.15) (layer "F.Cu") (net 354))
  (segment (start 72.1 125.2) (end 72.5 125.2) (width 0.15) (layer "F.Cu") (net 354))
  (segment (start 78.324992 138.224992) (end 78.5 138.4) (width 0.15) (layer "F.Cu") (net 354))
  (segment (start 71.850018 133.03894) (end 71.850018 125.449982) (width 0.15) (layer "F.Cu") (net 354))
  (segment (start 73.036067 134.224989) (end 78.024989 134.224989) (width 0.15) (layer "F.Cu") (net 354))
  (segment (start 73.036067 134.224989) (end 71.850018 133.03894) (width 0.15) (layer "F.Cu") (net 354))
  (segment (start 72.749999 125.150001) (end 72.5 125.4) (width 0.15) (layer "F.Cu") (net 354))
  (segment (start 73.297601 125.150001) (end 72.549999 125.150001) (width 0.15) (layer "F.Cu") (net 354))
  (segment (start 78.324992 134.524992) (end 78.324992 138.224992) (width 0.15) (layer "F.Cu") (net 354))
  (segment (start 78.024989 134.224989) (end 78.324992 134.524992) (width 0.15) (layer "F.Cu") (net 354))
  (segment (start 71.850018 125.449982) (end 72.1 125.2) (width 0.15) (layer "F.Cu") (net 354))
  (via (at 78.5 138.4) (size 0.6) (drill 0.25) (layers "F.Cu" "B.Cu") (net 354))
  (via (at 72.5 125.2) (size 0.6) (drill 0.25) (layers "F.Cu" "B.Cu") (net 354))
  (segment (start 78.2458 137.724979) (end 78.2458 138.1458) (width 0.15) (layer "B.Cu") (net 354))
  (segment (start 77.8418 136.425007) (end 77.75 136.516807) (width 0.15) (layer "B.Cu") (net 354))
  (segment (start 72.5 125.2) (end 71.1 126.6) (width 0.15) (layer "B.Cu") (net 354))
  (segment (start 72.5 125.2) (end 72.55 125.15) (width 0.15) (layer "B.Cu") (net 354))
  (segment (start 77.824979 137.724979) (end 78.2458 137.724979) (width 0.15) (layer "B.Cu") (net 354))
  (segment (start 72.55 125.15) (end 73.115 125.15) (width 0.15) (layer "B.Cu") (net 354))
  (segment (start 77.75 137.65) (end 77.824979 137.724979) (width 0.15) (layer "B.Cu") (net 354))
  (segment (start 71.1 126.6) (end 70.8 126.6) (width 0.15) (layer "B.Cu") (net 354))
  (segment (start 78.2458 138.1458) (end 78.5 138.4) (width 0.15) (layer "B.Cu") (net 354))
  (segment (start 78.2458 136.425007) (end 77.8418 136.425007) (width 0.15) (layer "B.Cu") (net 354))
  (segment (start 77.75 136.516807) (end 77.75 137.65) (width 0.15) (layer "B.Cu") (net 354))
  (segment (start 73.297601 124.15) (end 72.3 124.15) (width 0.155) (layer "F.Cu") (net 355))
  (segment (start 72.3 124.15) (end 71.709998 124.15) (width 0.15) (layer "F.Cu") (net 355))
  (segment (start 71.299999 124.559999) (end 71.3 133.266766) (width 0.15) (layer "F.Cu") (net 355))
  (segment (start 72.816617 134.783383) (end 73.383383 134.783383) (width 0.15) (layer "F.Cu") (net 355))
  (segment (start 73.383383 134.783383) (end 73.6 135) (width 0.15) (layer "F.Cu") (net 355))
  (segment (start 71.709998 124.15) (end 71.299999 124.559999) (width 0.15) (layer "F.Cu") (net 355))
  (segment (start 71.3 133.266766) (end 72.816617 134.783383) (width 0.15) (layer "F.Cu") (net 355))
  (via (at 72.3 124.15) (size 0.6) (drill 0.25) (layers "F.Cu" "B.Cu") (net 355))
  (via (at 73.6 135) (size 0.6) (drill 0.25) (layers "F.Cu" "B.Cu") (net 355))
  (via (at 83.325 138.375) (size 0.6) (drill 0.25) (layers "F.Cu" "B.Cu") (net 355))
  (segment (start 74.640003 135.299999) (end 73.899999 135.299999) (width 0.15) (layer "In2.Cu") (net 355))
  (segment (start 74.500001 135.299999) (end 74.640003 135.299999) (width 0.15) (layer "In2.Cu") (net 355))
  (segment (start 83.325 137.525) (end 80.549999 134.749999) (width 0.15) (layer "In2.Cu") (net 355))
  (segment (start 75.190003 134.749999) (end 74.640003 135.299999) (width 0.15) (layer "In2.Cu") (net 355))
  (segment (start 76.625001 134.749999) (end 75.190003 134.749999) (width 0.15) (layer "In2.Cu") (net 355))
  (segment (start 73.899999 135.299999) (end 74.500001 135.299999) (width 0.15) (layer "In2.Cu") (net 355))
  (segment (start 73.6 135) (end 73.899999 135.299999) (width 0.15) (layer "In2.Cu") (net 355))
  (segment (start 83.325 138.375) (end 83.325 137.525) (width 0.15) (layer "In2.Cu") (net 355))
  (segment (start 80.549999 134.749999) (end 76.625001 134.749999) (width 0.15) (layer "In2.Cu") (net 355))
  (segment (start 73.115 124.15) (end 72.3 124.15) (width 0.155) (layer "B.Cu") (net 355))
  (segment (start 82.825 137.608179) (end 82.9418 137.724979) (width 0.15) (layer "B.Cu") (net 355))
  (segment (start 83.3458 136.425007) (end 82.9418 136.425007) (width 0.15) (layer "B.Cu") (net 355))
  (segment (start 83.325 138.375) (end 83.325 137.745779) (width 0.15) (layer "B.Cu") (net 355))
  (segment (start 72.3 124.15) (end 71.709998 124.15) (width 0.15) (layer "B.Cu") (net 355))
  (segment (start 82.9418 136.425007) (end 82.825 136.541807) (width 0.15) (layer "B.Cu") (net 355))
  (segment (start 71.709998 124.15) (end 70.859998 125) (width 0.15) (layer "B.Cu") (net 355))
  (segment (start 82.9418 137.724979) (end 83.3458 137.724979) (width 0.15) (layer "B.Cu") (net 355))
  (segment (start 82.825 136.541807) (end 82.825 137.608179) (width 0.15) (layer "B.Cu") (net 355))
  (segment (start 85.55 100.335) (end 84.385 100.335) (width 0.15) (layer "F.Cu") (net 356))
  (segment (start 84.385 100.335) (end 84.1 100.05) (width 0.15) (layer "F.Cu") (net 356))
  (segment (start 83.15 98.75) (end 83.5 99.1) (width 0.15) (layer "F.Cu") (net 357))
  (segment (start 83.5 99.1) (end 85.285 99.1) (width 0.15) (layer "F.Cu") (net 357))
  (segment (start 85.285 99.1) (end 85.55 99.365) (width 0.15) (layer "F.Cu") (net 357))
  (segment (start 83.15 97.45) (end 83.15 98.75) (width 0.15) (layer "F.Cu") (net 357))
  (segment (start 73.065 113.035) (end 73.35 112.75) (width 0.155) (layer "F.Cu") (net 358))
  (segment (start 73.065 114.2) (end 73.065 113.035) (width 0.155) (layer "F.Cu") (net 358))
  (segment (start 75.95 111.8) (end 74.6 111.8) (width 0.155) (layer "F.Cu") (net 359))
  (segment (start 74.2 112.2) (end 74.2 114.035) (width 0.155) (layer "F.Cu") (net 359))
  (segment (start 74.6 111.8) (end 74.2 112.2) (width 0.155) (layer "F.Cu") (net 359))
  (segment (start 124.4 120.6) (end 124.4 121.4) (width 0.15) (layer "B.Cu") (net 360))
  (segment (start 121.365 120.9) (end 121.88501 120.37999) (width 0.15) (layer "B.Cu") (net 360))
  (segment (start 124.95 121.95) (end 126.15 121.95) (width 0.15) (layer "B.Cu") (net 360))
  (segment (start 124.17999 120.37999) (end 124.4 120.6) (width 0.15) (layer "B.Cu") (net 360))
  (segment (start 124.4 121.4) (end 124.95 121.95) (width 0.15) (layer "B.Cu") (net 360))
  (segment (start 121.88501 120.37999) (end 124.17999 120.37999) (width 0.15) (layer "B.Cu") (net 360))
  (segment (start 123.55 121) (end 122.435 121) (width 0.15) (layer "B.Cu") (net 361))
  (segment (start 73.3 118.6) (end 72.515 118.6) (width 0.15) (layer "F.Cu") (net 362))
  (segment (start 72.515 118.6) (end 72 119.115) (width 0.15) (layer "F.Cu") (net 362))
  (segment (start 75.9 117.65) (end 74.75 117.65) (width 0.155) (layer "F.Cu") (net 363))
  (segment (start 74.4 118.810002) (end 74.4 118.8) (width 0.15) (layer "F.Cu") (net 363))
  (segment (start 74.75 117.65) (end 74.4 118) (width 0.155) (layer "F.Cu") (net 363))
  (segment (start 72.9 119.2) (end 74.010002 119.2) (width 0.15) (layer "F.Cu") (net 363))
  (segment (start 72.015 120.085) (end 72.9 119.2) (width 0.15) (layer "F.Cu") (net 363))
  (segment (start 74.010002 119.2) (end 74.4 118.810002) (width 0.15) (layer "F.Cu") (net 363))
  (segment (start 74.4 118) (end 74.4 118.8) (width 0.155) (layer "F.Cu") (net 363))
  (segment (start 81.5 140.3) (end 81.5 139.735) (width 0.15) (layer "F.Cu") (net 364))
  (segment (start 83.2 140.4) (end 83.2 139.585) (width 0.15) (layer "F.Cu") (net 364))
  (segment (start 81.935 139.3) (end 82.915 139.3) (width 0.15) (layer "F.Cu") (net 364))
  (segment (start 81.5 139.735) (end 81.935 139.3) (width 0.15) (layer "F.Cu") (net 364))
  (segment (start 83.2 139.585) (end 82.915 139.3) (width 0.15) (layer "F.Cu") (net 364))
  (segment (start 80.69 138.05) (end 81.17 137.57) (width 0.15) (layer "F.Cu") (net 365))
  (segment (start 81.17 137.57) (end 81.32 137.57) (width 0.15) (layer "F.Cu") (net 365))
  (segment (start 81.32 137.57) (end 81.84 137.05) (width 0.15) (layer "F.Cu") (net 365))
  (segment (start 138.25 148.425) (end 138.81 148.425) (width 0.15) (layer "B.Cu") (net 366))
  (segment (start 138.81 148.425) (end 139.25 147.985) (width 0.15) (layer "B.Cu") (net 366))
  (segment (start 73.297601 123.15) (end 72.6 123.15) (width 0.155) (layer "F.Cu") (net 367))
  (segment (start 72.6 123.15) (end 72.4 122.95) (width 0.155) (layer "F.Cu") (net 367))
  (via (at 72.4 122.95) (size 0.6) (drill 0.25) (layers "F.Cu" "B.Cu") (net 367))
  (via (at 71.9 108) (size 0.6) (drill 0.25) (layers "F.Cu" "B.Cu") (net 367))
  (segment (start 72.7 108.2) (end 72.1 108.2) (width 0.15) (layer "In3.Cu") (net 367))
  (segment (start 72.4 122.9) (end 72.12501 122.62501) (width 0.15) (layer "In3.Cu") (net 367))
  (segment (start 73.2 120.7) (end 73.2 108.7) (width 0.15) (layer "In3.Cu") (net 367))
  (segment (start 72.12501 121.77499) (end 73.2 120.7) (width 0.15) (layer "In3.Cu") (net 367))
  (segment (start 72.12501 122.62501) (end 72.12501 121.77499) (width 0.15) (layer "In3.Cu") (net 367))
  (segment (start 72.4 122.95) (end 72.4 122.9) (width 0.15) (layer "In3.Cu") (net 367))
  (segment (start 73.2 108.7) (end 72.7 108.2) (width 0.15) (layer "In3.Cu") (net 367))
  (segment (start 72.1 108.2) (end 71.9 108) (width 0.15) (layer "In3.Cu") (net 367))
  (segment (start 73.115 123.15) (end 72.6 123.15) (width 0.155) (layer "B.Cu") (net 367))
  (segment (start 72.6 123.15) (end 72.4 122.95) (width 0.155) (layer "B.Cu") (net 367))
  (segment (start 73.8 107.3) (end 73.8 107.5) (width 0.15) (layer "B.Cu") (net 367))
  (segment (start 73.3042 105.925007) (end 73.7082 105.925007) (width 0.15) (layer "B.Cu") (net 367))
  (segment (start 73.625021 107.224979) (end 73.3042 107.224979) (width 0.15) (layer "B.Cu") (net 367))
  (segment (start 73.8 106.9) (end 73.8 107.05) (width 0.15) (layer "B.Cu") (net 367))
  (segment (start 73.8 107.1) (end 73.675007 107.224993) (width 0.15) (layer "B.Cu") (net 367))
  (segment (start 72.3 108.4) (end 71.9 108) (width 0.15) (layer "B.Cu") (net 367))
  (segment (start 71.05 122.95) (end 70.8 123.2) (width 0.15) (layer "B.Cu") (net 367))
  (segment (start 73.7082 105.925007) (end 73.8 106.016807) (width 0.15) (layer "B.Cu") (net 367))
  (segment (start 73.675007 107.224993) (end 73.724993 107.224993) (width 0.15) (layer "B.Cu") (net 367))
  (segment (start 73.8 107.349986) (end 73.675007 107.224993) (width 0.15) (layer "B.Cu") (net 367))
  (segment (start 73.3042 107.224993) (end 73.675007 107.224993) (width 0.15) (layer "B.Cu") (net 367))
  (segment (start 73.8 106.016807) (end 73.8 106.9) (width 0.15) (layer "B.Cu") (net 367))
  (segment (start 73.8 107.5) (end 73.8 108.2) (width 0.15) (layer "B.Cu") (net 367))
  (segment (start 73.724993 107.224993) (end 73.8 107.3) (width 0.15) (layer "B.Cu") (net 367))
  (segment (start 72.4 122.95) (end 71.05 122.95) (width 0.15) (layer "B.Cu") (net 367))
  (segment (start 73.8 108.2) (end 73.6 108.4) (width 0.15) (layer "B.Cu") (net 367))
  (segment (start 73.8 106.9) (end 73.8 107.1) (width 0.15) (layer "B.Cu") (net 367))
  (segment (start 73.8 107.5) (end 73.8 107.349986) (width 0.15) (layer "B.Cu") (net 367))
  (segment (start 73.8 106.9) (end 73.8 107.3) (width 0.15) (layer "B.Cu") (net 367))
  (segment (start 73.6 108.4) (end 72.3 108.4) (width 0.15) (layer "B.Cu") (net 367))
  (segment (start 95.1125 141.9) (end 95.8875 141.9) (width 0.15) (layer "B.Cu") (net 368))
  (segment (start 95.1125 143.9) (end 95.8875 143.9) (width 0.15) (layer "B.Cu") (net 369))
  (segment (start 114.85 138.3125) (end 114.85 139.0875) (width 0.2) (layer "F.Cu") (net 370))
  (segment (start 151.285 138) (end 152.25 138) (width 0.2) (layer "F.Cu") (net 371))
  (segment (start 151.285 141.8) (end 152.25 141.8) (width 0.2) (layer "F.Cu") (net 372))
  (segment (start 146.7 94.4) (end 145.435 94.4) (width 0.15) (layer "F.Cu") (net 373))
  (segment (start 148.2 93.8) (end 148 93.6) (width 0.15) (layer "F.Cu") (net 374))
  (segment (start 148.2 94.4) (end 148.2 93.8) (width 0.15) (layer "F.Cu") (net 374))
  (via (at 141 107.5) (size 0.6) (drill 0.25) (layers "F.Cu" "B.Cu") (net 374))
  (via (at 148 93.6) (size 0.6) (drill 0.25) (layers "F.Cu" "B.Cu") (net 374))
  (segment (start 141 100.177844) (end 141 107.5) (width 0.15) (layer "In2.Cu") (net 374))
  (segment (start 148 93.6) (end 147.150018 93.6) (width 0.15) (layer "In2.Cu") (net 374))
  (segment (start 147.150018 93.6) (end 146.850018 93.9) (width 0.15) (layer "In2.Cu") (net 374))
  (segment (start 146.850018 93.9) (end 146.850018 94.327826) (width 0.15) (layer "In2.Cu") (net 374))
  (segment (start 146.850018 94.327826) (end 141 100.177844) (width 0.15) (layer "In2.Cu") (net 374))
  (segment (start 142.85 107.35) (end 141.15 107.35) (width 0.2) (layer "B.Cu") (net 374))
  (segment (start 141.15 107.35) (end 141 107.5) (width 0.2) (layer "B.Cu") (net 374))
  (segment (start 80.3 150.95) (end 81.25 150.95) (width 0.2) (layer "F.Cu") (net 375))
  (via (at 80.3 150.95) (size 0.6) (drill 0.25) (layers "F.Cu" "B.Cu") (net 375))
  (segment (start 80.765 150.485) (end 80.3 150.95) (width 0.2) (layer "B.Cu") (net 375))
  (segment (start 81.25 150.485) (end 80.765 150.485) (width 0.2) (layer "B.Cu") (net 375))
  (segment (start 93.4 150.95) (end 94.25 150.95) (width 0.2) (layer "F.Cu") (net 376))
  (via (at 94.25 150.95) (size 0.6) (drill 0.25) (layers "F.Cu" "B.Cu") (net 376))
  (segment (start 94.25 150.95) (end 93.615 150.95) (width 0.2) (layer "B.Cu") (net 376))
  (segment (start 93.615 150.95) (end 93.4 150.735) (width 0.2) (layer "B.Cu") (net 376))
  (segment (start 81.5 105.55) (end 83.25 107.3) (width 0.2) (layer "F.Cu") (net 377))
  (segment (start 81.5 104.635) (end 81.5 105.55) (width 0.2) (layer "F.Cu") (net 377))
  (segment (start 74.95 130.685) (end 73.885 130.685) (width 0.2) (layer "F.Cu") (net 378))
  (segment (start 60.9 122.75) (end 63.55 122.75) (width 0.25) (layer "F.Cu") (net 379))
  (via (at 60.9 122.75) (size 0.6) (drill 0.25) (layers "F.Cu" "B.Cu") (net 379))
  (via (at 63.55 122.75) (size 0.6) (drill 0.25) (layers "F.Cu" "B.Cu") (net 379))
  (segment (start 59.325 122.75) (end 60.9 122.75) (width 0.25) (layer "B.Cu") (net 379))
  (segment (start 63.55 122.75) (end 64.925 122.75) (width 0.25) (layer "B.Cu") (net 379))
  (segment (start 59.325 122.75) (end 59.325 120.925) (width 0.25) (layer "B.Cu") (net 379))
  (segment (start 58.95 120.55) (end 58.25 120.55) (width 0.25) (layer "B.Cu") (net 379))
  (segment (start 59.325 120.925) (end 58.95 120.55) (width 0.25) (layer "B.Cu") (net 379))
  (segment (start 67.95 119.25) (end 68.6 119.25) (width 0.15) (layer "F.Cu") (net 380))
  (via (at 67.95 119.25) (size 0.6) (drill 0.25) (layers "F.Cu" "B.Cu") (net 380))
  (segment (start 68.7 119.25) (end 67.95 119.25) (width 0.2) (layer "B.Cu") (net 380))
  (segment (start 68.7 119.25) (end 68.7 121.075) (width 0.2) (layer "B.Cu") (net 380))
  (segment (start 91.235 132.65) (end 92.8 132.65) (width 0.2) (layer "F.Cu") (net 381))
  (segment (start 91.235 131.6) (end 92.8 131.6) (width 0.2) (layer "F.Cu") (net 382))
  (segment (start 91.235 130.55) (end 92.8 130.55) (width 0.2) (layer "F.Cu") (net 383))
  (segment (start 61.2 105.2) (end 58.6 102.6) (width 0.2) (layer "F.Cu") (net 384))
  (segment (start 58.6 102.6) (end 57.6 102.6) (width 0.2) (layer "F.Cu") (net 384))
  (via (at 61.2 105.2) (size 0.6) (drill 0.25) (layers "F.Cu" "B.Cu") (net 384))
  (via (at 57.6 102.6) (size 0.6) (drill 0.25) (layers "F.Cu" "B.Cu") (net 384))
  (segment (start 61.335 105.335) (end 61.2 105.2) (width 0.2) (layer "B.Cu") (net 384))
  (segment (start 61.335 106.788) (end 61.335 105.335) (width 0.2) (layer "B.Cu") (net 384))
  (segment (start 57.6 102.6) (end 56.5 101.5) (width 0.2) (layer "B.Cu") (net 384))
  (segment (start 150.2 138.7) (end 148.4 138.7) (width 0.2) (layer "F.Cu") (net 385))
  (segment (start 150.315 138) (end 150.315 138.585) (width 0.2) (layer "F.Cu") (net 385))
  (segment (start 150.315 138.585) (end 150.2 138.7) (width 0.2) (layer "F.Cu") (net 385))
  (via (at 148.4 138.7) (size 0.6) (drill 0.25) (layers "F.Cu" "B.Cu") (net 385))
  (segment (start 147.95 139.15) (end 148.4 138.7) (width 0.2) (layer "B.Cu") (net 385))
  (segment (start 146.8 139.15) (end 147.95 139.15) (width 0.2) (layer "B.Cu") (net 385))
  (segment (start 149.7 141.8) (end 150.315 141.8) (width 0.2) (layer "F.Cu") (net 386))
  (via (at 149.7 141.8) (size 0.6) (drill 0.25) (layers "F.Cu" "B.Cu") (net 386))
  (segment (start 150.35 141.8) (end 149.7 141.8) (width 0.2) (layer "B.Cu") (net 386))
  (segment (start 150.315 134.2) (end 149.2 134.2) (width 0.2) (layer "F.Cu") (net 387))
  (segment (start 148.6 134.2) (end 149.2 134.2) (width 0.2) (layer "F.Cu") (net 387))
  (segment (start 148.4 135) (end 148.4 134.4) (width 0.2) (layer "F.Cu") (net 387))
  (segment (start 148.4 134.4) (end 148.6 134.2) (width 0.2) (layer "F.Cu") (net 387))
  (via (at 148.4 135) (size 0.6) (drill 0.25) (layers "F.Cu" "B.Cu") (net 387))
  (segment (start 146.8 135.4) (end 146.8 136.15) (width 0.2) (layer "B.Cu") (net 387))
  (segment (start 148.4 135) (end 147.2 135) (width 0.2) (layer "B.Cu") (net 387))
  (segment (start 147.2 135) (end 146.8 135.4) (width 0.2) (layer "B.Cu") (net 387))
  (segment (start 78.75 147.1) (end 78.75 148.25) (width 0.2) (layer "B.Cu") (net 388))
  (segment (start 78.75 148.25) (end 80.015 149.515) (width 0.2) (layer "B.Cu") (net 388))
  (segment (start 80.015 149.515) (end 81.25 149.515) (width 0.2) (layer "B.Cu") (net 388))
  (segment (start 94.05 149.115) (end 93.4 149.765) (width 0.2) (layer "B.Cu") (net 389))
  (segment (start 94.05 147.4) (end 94.05 149.115) (width 0.2) (layer "B.Cu") (net 389))
  (segment (start 73.15 119.65) (end 73.15 120.965) (width 0.15) (layer "B.Cu") (net 390))
  (segment (start 73.15 120.965) (end 73.115 121) (width 0.15) (layer "B.Cu") (net 390))
  (segment (start 81.04 136.05) (end 81.04 137.05) (width 0.155) (layer "F.Cu") (net 391))
  (segment (start 80.05 135.95) (end 79.6 135.5) (width 0.15) (layer "F.Cu") (net 391))
  (segment (start 80.05 136.04) (end 81.03 136.04) (width 0.155) (layer "F.Cu") (net 391))
  (via (at 80.7 142.4) (size 0.6) (drill 0.25) (layers "F.Cu" "B.Cu") (net 391))
  (via (at 79.6 135.5) (size 0.6) (drill 0.25) (layers "F.Cu" "B.Cu") (net 391))
  (segment (start 80.7 136.6) (end 79.6 135.5) (width 0.15) (layer "In3.Cu") (net 391))
  (segment (start 80.7 142.4) (end 80.7 136.6) (width 0.15) (layer "In3.Cu") (net 391))
  (segment (start 81.36 142.435) (end 80.735 142.435) (width 0.155) (layer "B.Cu") (net 391))
  (segment (start 80.735 142.435) (end 80.7 142.4) (width 0.155) (layer "B.Cu") (net 391))
  (segment (start 150.985 85.5) (end 148.485 83) (width 0.23) (layer "B.Cu") (net 392))
  (segment (start 93.964173 106.257734) (end 93.749173 106.472734) (width 0.15) (layer "B.Cu") (net 393))
  (segment (start 95.371917 106.257734) (end 93.964173 106.257734) (width 0.15) (layer "B.Cu") (net 393))
  (segment (start 96.171211 105.45844) (end 95.371917 106.257734) (width 0.15) (layer "B.Cu") (net 393))
  (segment (start 96.171211 105.10344) (end 96.171211 105.45844) (width 0.15) (layer "B.Cu") (net 393))
  (segment (start 93.749174 106.472733) (end 92.978067 106.472733) (width 0.125) (layer "B.Cu") (net 393))
  (segment (start 144.47322 126.8) (end 145.974997 126.8) (width 0.2) (layer "F.Cu") (net 394))
  (segment (start 145.974997 126.8) (end 146.1 126.674997) (width 0.2) (layer "F.Cu") (net 394))
  (via (at 146.1 126.674997) (size 0.6) (drill 0.25) (layers "F.Cu" "B.Cu") (net 394))
  (segment (start 144.585 128.137998) (end 146.048001 126.674997) (width 0.2) (layer "B.Cu") (net 394))
  (segment (start 146.048001 126.674997) (end 146.1 126.674997) (width 0.2) (layer "B.Cu") (net 394))
  (segment (start 136.8 130.2) (end 137.09999 129.90001) (width 0.125) (layer "F.Cu") (net 395))
  (segment (start 136.1 130.2) (end 136.8 130.2) (width 0.125) (layer "F.Cu") (net 395))
  (segment (start 138.77322 128.5) (end 138.77322 129.411602) (width 0.125) (layer "F.Cu") (net 395))
  (segment (start 148.2 141) (end 148.2 141.915) (width 0.125) (layer "F.Cu") (net 395))
  (segment (start 138.77322 129.411602) (end 138.284812 129.90001) (width 0.125) (layer "F.Cu") (net 395))
  (segment (start 138.284812 129.90001) (end 137.09999 129.90001) (width 0.125) (layer "F.Cu") (net 395))
  (via (at 136.1 130.2) (size 0.6) (drill 0.25) (layers "F.Cu" "B.Cu") (net 395))
  (via (at 148.2 141) (size 0.6) (drill 0.25) (layers "F.Cu" "B.Cu") (net 395))
  (segment (start 135.2 130.817678) (end 135.208839 130.808839) (width 0.15) (layer "In2.Cu") (net 395))
  (segment (start 135.2 131.8) (end 135.2 130.8) (width 0.125) (layer "In2.Cu") (net 395))
  (segment (start 139.8 137) (end 139.8 135.3) (width 0.15) (layer "In2.Cu") (net 395))
  (segment (start 135.2 130.817678) (end 135.658839 130.358839) (width 0.15) (layer "In2.Cu") (net 395))
  (segment (start 135.2 131.8) (end 135.2 130.817678) (width 0.15) (layer "In2.Cu") (net 395))
  (segment (start 139.8 135.3) (end 139.8 134.1) (width 0.15) (layer "In2.Cu") (net 395))
  (segment (start 139.8 135) (end 139.8 134.2) (width 0.125) (layer "In2.Cu") (net 395))
  (segment (start 148.2 141) (end 148.2 139.8) (width 0.15) (layer "In2.Cu") (net 395))
  (segment (start 139.8 138.7) (end 139.8 137) (width 0.15) (layer "In2.Cu") (net 395))
  (segment (start 139.6 133.9) (end 137.3 133.9) (width 0.15) (layer "In2.Cu") (net 395))
  (segment (start 139.8 134.1) (end 139.6 133.9) (width 0.15) (layer "In2.Cu") (net 395))
  (segment (start 135.2 130.8) (end 135.8 130.2) (width 0.125) (layer "In2.Cu") (net 395))
  (segment (start 140.1 139.5) (end 139.8 139.2) (width 0.15) (layer "In2.Cu") (net 395))
  (segment (start 148.2 139.8) (end 147.9 139.5) (width 0.15) (layer "In2.Cu") (net 395))
  (segment (start 147.9 139.5) (end 140.1 139.5) (width 0.15) (layer "In2.Cu") (net 395))
  (segment (start 136.5 133.1) (end 135.2 131.8) (width 0.125) (layer "In2.Cu") (net 395))
  (segment (start 137.3 133.9) (end 136.5 133.1) (width 0.15) (layer "In2.Cu") (net 395))
  (segment (start 135.8 130.2) (end 136.1 130.2) (width 0.125) (layer "In2.Cu") (net 395))
  (segment (start 135.817678 130.2) (end 135.658839 130.358839) (width 0.15) (layer "In2.Cu") (net 395))
  (segment (start 136.1 130.2) (end 135.817678 130.2) (width 0.15) (layer "In2.Cu") (net 395))
  (segment (start 139.8 135.3) (end 139.8 135) (width 0.15) (layer "In2.Cu") (net 395))
  (segment (start 139.8 138.5) (end 139.8 135) (width 0.125) (layer "In2.Cu") (net 395))
  (segment (start 139.8 138.7) (end 139.8 138.5) (width 0.15) (layer "In2.Cu") (net 395))
  (segment (start 139.8 139.2) (end 139.8 138.7) (width 0.15) (layer "In2.Cu") (net 395))
  (segment (start 136.6 133.2) (end 136.5 133.1) (width 0.125) (layer "In2.Cu") (net 395))
  (segment (start 136.6 133.2) (end 135.2 131.8) (width 0.15) (layer "In2.Cu") (net 395))
  (segment (start 136.1 130.2) (end 138.594498 130.2) (width 0.125) (layer "B.Cu") (net 395))
  (segment (start 138.594498 130.2) (end 139.388164 129.406334) (width 0.125) (layer "B.Cu") (net 395))
  (segment (start 110.05 144.75) (end 110.05 145.93) (width 0.125) (layer "B.Cu") (net 396))
  (segment (start 110.05 145.93) (end 110.52 146.4) (width 0.125) (layer "B.Cu") (net 396))
  (segment (start 147.2 103.4) (end 147.2 109.8) (width 0.15) (layer "F.Cu") (net 397))
  (segment (start 147.2 103.4) (end 146.8 103) (width 0.15) (layer "F.Cu") (net 397))
  (segment (start 137.685 103) (end 145.7 103) (width 0.15) (layer "F.Cu") (net 397))
  (segment (start 147.2 109.8) (end 147.2 110.75) (width 0.15) (layer "F.Cu") (net 397))
  (segment (start 145.7 103) (end 146.8 103) (width 0.15) (layer "F.Cu") (net 397))
  (segment (start 96.75 119.865) (end 96.5 120.115) (width 0.2) (layer "F.Cu") (net 398))
  (segment (start 96.75 118.55) (end 96.75 119.865) (width 0.2) (layer "F.Cu") (net 398))
  (segment (start 79.415 122.9) (end 78.465 122.9) (width 0.15) (layer "F.Cu") (net 399))
  (segment (start 77.754799 123.649999) (end 78.45 122.954798) (width 0.15) (layer "F.Cu") (net 399))
  (segment (start 77.202399 123.649999) (end 77.754799 123.649999) (width 0.15) (layer "F.Cu") (net 399))
  (segment (start 77.202399 122.347601) (end 77.635 121.915) (width 0.15) (layer "F.Cu") (net 400))
  (segment (start 77.635 121.915) (end 78.45 121.915) (width 0.15) (layer "F.Cu") (net 400))
  (segment (start 77.202399 123.15) (end 77.202399 122.347601) (width 0.15) (layer "F.Cu") (net 400))
  (segment (start 79.415 121.9) (end 78.465 121.9) (width 0.15) (layer "F.Cu") (net 400))
  (segment (start 77.202399 124.65) (end 78.215 124.65) (width 0.15) (layer "F.Cu") (net 401))
  (segment (start 79.415 124.9) (end 78.465 124.9) (width 0.15) (layer "F.Cu") (net 401))
  (segment (start 78.215 124.65) (end 78.45 124.885) (width 0.15) (layer "F.Cu") (net 401))
  (segment (start 77.202399 125.65) (end 77.202399 126.302399) (width 0.15) (layer "F.Cu") (net 402))
  (segment (start 79.415 126.9) (end 78.465 126.9) (width 0.15) (layer "F.Cu") (net 402))
  (segment (start 77.202399 126.302399) (end 77.785 126.885) (width 0.15) (layer "F.Cu") (net 402))
  (segment (start 77.785 126.885) (end 78.45 126.885) (width 0.15) (layer "F.Cu") (net 402))
  (segment (start 77.202399 125.150001) (end 77.685001 125.150001) (width 0.15) (layer "F.Cu") (net 403))
  (segment (start 77.685001 125.150001) (end 78.45 125.915) (width 0.15) (layer "F.Cu") (net 403))
  (segment (start 79.415 125.9) (end 78.465 125.9) (width 0.15) (layer "F.Cu") (net 403))
  (segment (start 76.5 126.352399) (end 76.5 127.515) (width 0.125) (layer "F.Cu") (net 404))
  (segment (start 80.985 119.915) (end 80.65 120.25) (width 0.15) (layer "B.Cu") (net 405))
  (segment (start 81.35 119.915) (end 81.8642 119.915) (width 0.15) (layer "B.Cu") (net 405))
  (segment (start 79.8 120.6) (end 79.25 120.05) (width 0.15) (layer "B.Cu") (net 405))
  (segment (start 80.65 120.25) (end 80.3 120.6) (width 0.15) (layer "B.Cu") (net 405))
  (segment (start 79.25 120.05) (end 76.285 120.05) (width 0.15) (layer "B.Cu") (net 405))
  (segment (start 81.8642 119.915) (end 82.4 120.4508) (width 0.15) (layer "B.Cu") (net 405))
  (segment (start 81.35 119.915) (end 80.985 119.915) (width 0.15) (layer "B.Cu") (net 405))
  (segment (start 76.085 121.25) (end 76.085 122.315) (width 0.15) (layer "B.Cu") (net 406))
  (segment (start 74.635 121.8) (end 74.085 121.25) (width 0.15) (layer "B.Cu") (net 406))
  (segment (start 77.35 120.6) (end 76.735 120.6) (width 0.15) (layer "B.Cu") (net 406))
  (segment (start 76 122.4) (end 75.235 122.4) (width 0.15) (layer "B.Cu") (net 406))
  (segment (start 76.735 120.6) (end 76.085 121.25) (width 0.15) (layer "B.Cu") (net 406))
  (segment (start 75.235 122.4) (end 74.635 121.8) (width 0.15) (layer "B.Cu") (net 406))
  (segment (start 72 112.6) (end 72 111.885) (width 0.15) (layer "F.Cu") (net 407))
  (segment (start 73.35 111.8) (end 72.085 111.8) (width 0.155) (layer "F.Cu") (net 407))
  (segment (start 73.115 109.915) (end 73.3 110.1) (width 0.155) (layer "F.Cu") (net 407))
  (segment (start 74.105 111.8) (end 73.35 111.8) (width 0.155) (layer "F.Cu") (net 407))
  (segment (start 73.3 110.1) (end 74.1 110.1) (width 0.155) (layer "F.Cu") (net 407))
  (segment (start 74.4 110.4) (end 74.4 111.505) (width 0.155) (layer "F.Cu") (net 407))
  (segment (start 73.115 109.915) (end 73.115 109.45) (width 0.15) (layer "F.Cu") (net 407))
  (segment (start 74.4 111.505) (end 74.105 111.8) (width 0.155) (layer "F.Cu") (net 407))
  (segment (start 74.1 110.1) (end 74.4 110.4) (width 0.155) (layer "F.Cu") (net 407))
  (via (at 72 112.6) (size 0.6) (drill 0.25) (layers "F.Cu" "B.Cu") (net 407))
  (segment (start 72 111.6) (end 72 112.6) (width 0.15) (layer "B.Cu") (net 407))
  (segment (start 72.8 110.8) (end 72 111.6) (width 0.15) (layer "B.Cu") (net 407))
  (segment (start 77.8508 110.8) (end 72.8 110.8) (width 0.15) (layer "B.Cu") (net 407))
  (segment (start 78.4 110.2508) (end 77.8508 110.8) (width 0.15) (layer "B.Cu") (net 407))
  (segment (start 123.315 123.685) (end 123.549999 123.450001) (width 0.15) (layer "B.Cu") (net 408))
  (segment (start 124.3 121.95) (end 123.55 121.95) (width 0.15) (layer "B.Cu") (net 408))
  (segment (start 123.55 121.95) (end 122.385 121.95) (width 0.15) (layer "B.Cu") (net 408))
  (segment (start 124.4 123.360002) (end 124.4 122.05) (width 0.15) (layer "B.Cu") (net 408))
  (segment (start 123.315 124.35) (end 123.315 123.685) (width 0.15) (layer "B.Cu") (net 408))
  (segment (start 123.315 124.35) (end 123.315 126.1658) (width 0.15) (layer "B.Cu") (net 408))
  (segment (start 124.310001 123.450001) (end 124.4 123.360002) (width 0.15) (layer "B.Cu") (net 408))
  (segment (start 124.4 122.05) (end 124.3 121.95) (width 0.15) (layer "B.Cu") (net 408))
  (segment (start 123.549999 123.450001) (end 124.310001 123.450001) (width 0.15) (layer "B.Cu") (net 408))
  (segment (start 83.45 101.315) (end 85.585 101.315) (width 0.155) (layer "F.Cu") (net 409))
  (segment (start 85.585 101.315) (end 88.4 98.5) (width 0.155) (layer "F.Cu") (net 409))
  (segment (start 88.4 98.5) (end 88.4 98.2) (width 0.155) (layer "F.Cu") (net 409))
  (segment (start 83.15 101.015) (end 83.45 101.315) (width 0.155) (layer "F.Cu") (net 409))
  (segment (start 83.15 100.05) (end 83.15 101.015) (width 0.155) (layer "F.Cu") (net 409))
  (via (at 88.4 98.2) (size 0.6) (drill 0.25) (layers "F.Cu" "B.Cu") (net 409))
  (segment (start 88.4 98.2) (end 87.4508 98.2) (width 0.155) (layer "B.Cu") (net 409))
  (segment (start 72.05 110.835) (end 71.05 110.835) (width 0.155) (layer "F.Cu") (net 410))
  (segment (start 73.35 110.85) (end 72.065 110.85) (width 0.155) (layer "F.Cu") (net 410))
  (segment (start 84.9 134) (end 83.885 134) (width 0.2) (layer "F.Cu") (net 411))
  (segment (start 83.885 133) (end 83.885 134) (width 0.2) (layer "F.Cu") (net 411))
  (segment (start 85.12 135.025) (end 85.12 134.22) (width 0.2) (layer "F.Cu") (net 411))
  (segment (start 85.12 134.22) (end 84.9 134) (width 0.2) (layer "F.Cu") (net 411))
  (segment (start 114.35 138.3125) (end 114.35 139.0875) (width 0.2) (layer "F.Cu") (net 412))
  (segment (start 140.6 100.0508) (end 141.3008 99.35) (width 0.15) (layer "B.Cu") (net 415))
  (segment (start 141.3008 99.35) (end 142.85 99.35) (width 0.15) (layer "B.Cu") (net 415))
  (segment (start 139.6 100.0508) (end 140.6 100.0508) (width 0.15) (layer "B.Cu") (net 415))
  (segment (start 139.6 101.4508) (end 141.2008 99.85) (width 0.15) (layer "B.Cu") (net 416))
  (segment (start 142.85 99.85) (end 141.45 99.85) (width 0.15) (layer "B.Cu") (net 416))
  (segment (start 141.2008 99.85) (end 141.45 99.85) (width 0.15) (layer "B.Cu") (net 416))
  (segment (start 142.8 104) (end 137.685 104) (width 0.15) (layer "F.Cu") (net 417))
  (segment (start 146.2 104.4) (end 146.2 109.8) (width 0.15) (layer "F.Cu") (net 417))
  (segment (start 142.8 104) (end 145.8 104) (width 0.15) (layer "F.Cu") (net 417))
  (segment (start 146.2 109.8) (end 146.2 110.75) (width 0.15) (layer "F.Cu") (net 417))
  (segment (start 145.8 104) (end 146.2 104.4) (width 0.15) (layer "F.Cu") (net 417))
  (segment (start 122 116) (end 122 115.2) (width 0.15) (layer "F.Cu") (net 418))
  (segment (start 121.8 116.2) (end 122 116) (width 0.15) (layer "F.Cu") (net 418))
  (segment (start 122.2 115) (end 122.7 115) (width 0.15) (layer "F.Cu") (net 418))
  (segment (start 100.25 112.45) (end 100.25 115.85) (width 0.15) (layer "F.Cu") (net 418))
  (segment (start 100.6 116.2) (end 121.8 116.2) (width 0.15) (layer "F.Cu") (net 418))
  (segment (start 122 115.2) (end 122.2 115) (width 0.15) (layer "F.Cu") (net 418))
  (segment (start 100.25 115.85) (end 100.6 116.2) (width 0.15) (layer "F.Cu") (net 418))
  (segment (start 146.2 116.65) (end 146.2 115.4) (width 0.15) (layer "F.Cu") (net 418))
  (via (at 146.2 115.4) (size 0.6) (drill 0.25) (layers "F.Cu" "B.Cu") (net 418))
  (via (at 122.7 115) (size 0.6) (drill 0.25) (layers "F.Cu" "B.Cu") (net 418))
  (segment (start 143.18 110.4) (end 128.15 110.4) (width 0.15) (layer "B.Cu") (net 418))
  (segment (start 122.702159 112.102159) (end 122.702159 114.573577) (width 0.15) (layer "B.Cu") (net 418))
  (segment (start 146.2 115.4) (end 146.2 113.42) (width 0.15) (layer "B.Cu") (net 418))
  (segment (start 126.8 110.4) (end 125.4 111.8) (width 0.15) (layer "B.Cu") (net 418))
  (segment (start 128.15 110.4) (end 126.8 110.4) (width 0.15) (layer "B.Cu") (net 418))
  (segment (start 122.7 114.575736) (end 122.7 115) (width 0.15) (layer "B.Cu") (net 418))
  (segment (start 122.702159 114.573577) (end 122.7 114.575736) (width 0.15) (layer "B.Cu") (net 418))
  (segment (start 123.004318 111.8) (end 122.702159 112.102159) (width 0.15) (layer "B.Cu") (net 418))
  (segment (start 146.2 113.42) (end 143.18 110.4) (width 0.15) (layer "B.Cu") (net 418))
  (segment (start 125.4 111.8) (end 123.004318 111.8) (width 0.15) (layer "B.Cu") (net 418))
  (segment (start 101.25 83.45) (end 101.25 85.6) (width 0.15) (layer "F.Cu") (net 419))
  (segment (start 101.25 85.6) (end 101.3 85.65) (width 0.15) (layer "F.Cu") (net 419))
  (segment (start 100.576841 88.076841) (end 100.576841 88.3) (width 0.15) (layer "F.Cu") (net 419))
  (segment (start 98.2 85.7) (end 100.576841 88.076841) (width 0.15) (layer "F.Cu") (net 419))
  (segment (start 147.2 116.65) (end 147.2 114.1125) (width 0.15) (layer "F.Cu") (net 419))
  (via (at 98.2 85.7) (size 0.6) (drill 0.25) (layers "F.Cu" "B.Cu") (net 419))
  (via (at 100.6 91.2) (size 0.6) (drill 0.25) (layers "F.Cu" "B.Cu") (net 419))
  (via (at 101.3 85.65) (size 0.6) (drill 0.25) (layers "F.Cu" "B.Cu") (net 419))
  (via (at 126.4 87.2) (size 0.6) (drill 0.25) (layers "F.Cu" "B.Cu") (net 419))
  (via (at 147.2 114.1125) (size 0.6) (drill 0.25) (layers "F.Cu" "B.Cu") (net 419))
  (via (at 100.576841 88.3) (size 0.6) (drill 0.25) (layers "F.Cu" "B.Cu") (net 419))
  (segment (start 106.2 90) (end 106 90.2) (width 0.15) (layer "In2.Cu") (net 419))
  (segment (start 126 90) (end 106.2 90) (width 0.15) (layer "In2.Cu") (net 419))
  (segment (start 100.6 91.2) (end 105.8 91.2) (width 0.15) (layer "In2.Cu") (net 419))
  (segment (start 126.4 87.2) (end 126.4 89.6) (width 0.15) (layer "In2.Cu") (net 419))
  (segment (start 106 91) (end 105.8 91.2) (width 0.15) (layer "In2.Cu") (net 419))
  (segment (start 106 90.2) (end 106 91) (width 0.15) (layer "In2.Cu") (net 419))
  (segment (start 126.4 89.6) (end 126 90) (width 0.15) (layer "In2.Cu") (net 419))
  (segment (start 138.32499 110.12499) (end 138 109.8) (width 0.15) (layer "B.Cu") (net 419))
  (segment (start 143.293898 110.12499) (end 138.32499 110.12499) (width 0.15) (layer "B.Cu") (net 419))
  (segment (start 137.4 87.8) (end 126.6 87.8) (width 0.15) (layer "B.Cu") (net 419))
  (segment (start 100.576841 90.976841) (end 100.576841 88.3) (width 0.15) (layer "B.Cu") (net 419))
  (segment (start 147.2 114) (end 147.168908 114) (width 0.15) (layer "B.Cu") (net 419))
  (segment (start 126.6 87.8) (end 126.4 87.6) (width 0.15) (layer "B.Cu") (net 419))
  (segment (start 147.168908 114) (end 143.293898 110.12499) (width 0.15) (layer "B.Cu") (net 419))
  (segment (start 98.2 85.7) (end 101.25 85.7) (width 0.15) (layer "B.Cu") (net 419))
  (segment (start 100.576841 90.976841) (end 100.576841 91.176841) (width 0.15) (layer "B.Cu") (net 419))
  (segment (start 126.4 87.6) (end 126.4 87.2) (width 0.15) (layer "B.Cu") (net 419))
  (segment (start 101.25 85.7) (end 101.3 85.65) (width 0.15) (layer "B.Cu") (net 419))
  (segment (start 138 109.8) (end 138 88.4) (width 0.15) (layer "B.Cu") (net 419))
  (segment (start 100.576841 91.176841) (end 100.6 91.2) (width 0.15) (layer "B.Cu") (net 419))
  (segment (start 138 88.4) (end 137.4 87.8) (width 0.15) (layer "B.Cu") (net 419))
  (segment (start 93.25 120.715) (end 93.75 121.215) (width 0.15) (layer "F.Cu") (net 420))
  (segment (start 93.25 118.55) (end 93.25 120.715) (width 0.15) (layer "F.Cu") (net 420))
  (segment (start 92.75 118.55) (end 92.75 121.215) (width 0.15) (layer "F.Cu") (net 421))
  (segment (start 91.75 118.55) (end 91.75 121.215) (width 0.15) (layer "F.Cu") (net 422))
  (segment (start 91.25 120.715) (end 90.75 121.215) (width 0.15) (layer "F.Cu") (net 423))
  (segment (start 91.25 118.55) (end 91.25 120.715) (width 0.15) (layer "F.Cu") (net 423))
  (segment (start 90.3 97.9) (end 89.9 97.5) (width 0.2) (layer "F.Cu") (net 424))
  (segment (start 89.257844 100.142156) (end 90.3 99.1) (width 0.2) (layer "F.Cu") (net 424))
  (segment (start 86.7684 83.9816) (end 86.7684 83.2) (width 0.155) (layer "F.Cu") (net 424))
  (segment (start 93.75 123) (end 93.75 122.185) (width 0.15) (layer "F.Cu") (net 424))
  (segment (start 89.257844 113.742156) (end 89.257844 100.142156) (width 0.2) (layer "F.Cu") (net 424))
  (segment (start 87.2 92.7) (end 87.2 91.9029) (width 0.2) (layer "F.Cu") (net 424))
  (segment (start 88.6 94.1) (end 87.2 92.7) (width 0.2) (layer "F.Cu") (net 424))
  (segment (start 89.9 97.5) (end 89.3 97.5) (width 0.2) (layer "F.Cu") (net 424))
  (segment (start 86.7684 83.7684) (end 86.7684 83.9816) (width 0.155) (layer "F.Cu") (net 424))
  (segment (start 89.3 97.5) (end 88.6 96.8) (width 0.2) (layer "F.Cu") (net 424))
  (segment (start 90.3 99.1) (end 90.3 97.9) (width 0.2) (layer "F.Cu") (net 424))
  (segment (start 93.75 122.185) (end 91.75 122.185) (width 0.15) (layer "F.Cu") (net 424))
  (segment (start 89.2 113.8) (end 89.257844 113.742156) (width 0.2) (layer "F.Cu") (net 424))
  (segment (start 88.6 96.8) (end 88.6 94.1) (width 0.2) (layer "F.Cu") (net 424))
  (via (at 86.7684 83.7684) (size 0.6) (drill 0.25) (layers "F.Cu" "B.Cu") (net 424))
  (via (at 93.75 123) (size 0.6) (drill 0.25) (layers "F.Cu" "B.Cu") (net 424))
  (via (at 89.2 113.8) (size 0.6) (drill 0.25) (layers "F.Cu" "B.Cu") (net 424))
  (segment (start 84.75 84) (end 82.25 86.5) (width 0.155) (layer "B.Cu") (net 424))
  (segment (start 93.75 123) (end 93.224999 122.474999) (width 0.2) (layer "B.Cu") (net 424))
  (segment (start 86.7684 83.7684) (end 84.9816 83.7684) (width 0.155) (layer "B.Cu") (net 424))
  (segment (start 89.2 113.8) (end 89.8 113.8) (width 0.2) (layer "B.Cu") (net 424))
  (segment (start 93.224999 117.224999) (end 89.8 113.8) (width 0.2) (layer "B.Cu") (net 424))
  (segment (start 84.9816 83.7684) (end 84.75 84) (width 0.155) (layer "B.Cu") (net 424))
  (segment (start 93.224999 122.474999) (end 93.224999 117.224999) (width 0.2) (layer "B.Cu") (net 424))
  (segment (start 85.12 138.48) (end 84.3 139.3) (width 0.15) (layer "F.Cu") (net 466))
  (segment (start 84.3 139.3) (end 83.885 139.3) (width 0.15) (layer "F.Cu") (net 466))
  (segment (start 85.12 137.525) (end 85.12 138.48) (width 0.15) (layer "F.Cu") (net 466))
  (segment (start 84.15 136.05) (end 82.01 136.05) (width 0.155) (layer "F.Cu") (net 467))
  (segment (start 84.225 136.05) (end 84.15 136.05) (width 0.15) (layer "F.Cu") (net 467))
  (segment (start 84.7 136.525) (end 84.225 136.05) (width 0.15) (layer "F.Cu") (net 467))
  (segment (start 85.12 136.525) (end 84.7 136.525) (width 0.15) (layer "F.Cu") (net 467))
  (segment (start 87.3 133.185) (end 87 132.885) (width 0.2) (layer "F.Cu") (net 468))
  (segment (start 87.3 134.345) (end 87.3 133.185) (width 0.2) (layer "F.Cu") (net 468))
  (segment (start 147.4875 88.5615) (end 147.4875 83.2395) (width 0.125) (layer "F.Cu") (net 661))
  (segment (start 90.343499 85.508501) (end 90.343499 88.294499) (width 0.125) (layer "B.Cu") (net 664))
  (segment (start 119.198 85.05) (end 119.198 88.75) (width 0.125) (layer "B.Cu") (net 665))

  (zone (net 66) (net_name "USB_VBUS") (layer "F.Cu") (hatch edge 0.508)
    (connect_pads yes (clearance 0.125))
    (min_thickness 0.125) (filled_areas_thickness no)
    (fill yes (thermal_gap 0.508) (thermal_bridge_width 0.508))
    (polygon
      (pts
        (xy 92.95 113.4)
        (xy 95.1 113.4)
        (xy 95.1 115.9)
        (xy 90.5 115.9)
        (xy 90.5 111.6)
        (xy 92.95 111.6)
      )
    )
  )
  (zone (net 73) (net_name "/PoE/VDD_POE") (layer "F.Cu") (hatch edge 0.508)
    (connect_pads yes (clearance 0.5))
    (min_thickness 0.125) (filled_areas_thickness no)
    (fill yes (thermal_gap 0.15) (thermal_bridge_width 0.15) (smoothing fillet) (radius 0.125))
    (polygon
      (pts
        (xy 68.4 126)
        (xy 64 126)
        (xy 64 118)
        (xy 64 107)
        (xy 56.6 99.7)
        (xy 56.6 96.3)
        (xy 59.1 96.3)
        (xy 59.1 97.9)
        (xy 65.5 104.3)
        (xy 68.4 107.2)
      )
    )
  )
  (zone (net 7) (net_name "GNDD") (layer "F.Cu") (hatch edge 0.508)
    (connect_pads yes (clearance 0.5))
    (min_thickness 0.125) (filled_areas_thickness no)
    (fill yes (thermal_gap 0.15) (thermal_bridge_width 0.15) (smoothing fillet) (radius 0.125))
    (polygon
      (pts
        (xy 60 126)
        (xy 55 126)
        (xy 55 105)
        (xy 60 105)
      )
    )
  )
  (zone (net 1) (net_name "GND") (layer "F.Cu") (hatch edge 0.508)
    (priority 1)
    (connect_pads yes (clearance 0.125))
    (min_thickness 0.125) (filled_areas_thickness no)
    (fill yes (thermal_gap 0.508) (thermal_bridge_width 0.508))
    (polygon
      (pts
        (xy 89.15 140.75)
        (xy 88.65 140.75)
        (xy 88.65 142.35)
        (xy 86.85 142.35)
        (xy 86.85 140.75)
        (xy 85.55 140.75)
        (xy 85.55 140)
        (xy 89.15 140)
      )
    )
  )
  (zone (net 107) (net_name "/USB-PD/PD_VBUS") (layer "F.Cu") (hatch edge 0.508)
    (priority 1)
    (connect_pads yes (clearance 0.125))
    (min_thickness 0.125) (filled_areas_thickness no)
    (fill yes (thermal_gap 0.508) (thermal_bridge_width 0.508))
    (polygon
      (pts
        (xy 88.8 143.4)
        (xy 89.2 143.4)
        (xy 89.2 142.5)
        (xy 90.2 142.5)
        (xy 90.2 141)
        (xy 88.8 141)
      )
    )
  )
  (zone (net 107) (net_name "/USB-PD/PD_VBUS") (layer "F.Cu") (hatch edge 0.508)
    (priority 1)
    (connect_pads yes (clearance 0.125))
    (min_thickness 0.125) (filled_areas_thickness no)
    (fill yes (thermal_gap 0.508) (thermal_bridge_width 0.508))
    (polygon
      (pts
        (xy 86.45 144.35)
        (xy 86.05 144.35)
        (xy 86.05 145.25)
        (xy 85.05 145.25)
        (xy 85.05 146.75)
        (xy 86.45 146.75)
      )
    )
  )
  (zone (net 107) (net_name "/USB-PD/PD_VBUS") (layer "F.Cu") (hatch edge 0.508)
    (priority 1)
    (connect_pads yes (clearance 0.125))
    (min_thickness 0.125) (filled_areas_thickness no)
    (fill yes (thermal_gap 0.508) (thermal_bridge_width 0.508))
    (polygon
      (pts
        (xy 88.55 144.35)
        (xy 88.95 144.35)
        (xy 88.95 145.25)
        (xy 89.95 145.25)
        (xy 89.95 146.75)
        (xy 88.55 146.75)
      )
    )
  )
  (zone (net 107) (net_name "/USB-PD/PD_VBUS") (layer "F.Cu") (hatch edge 0.508)
    (priority 1)
    (connect_pads yes (clearance 0.125))
    (min_thickness 0.125) (filled_areas_thickness no)
    (fill yes (thermal_gap 0.508) (thermal_bridge_width 0.508))
    (polygon
      (pts
        (xy 86.7 143.4)
        (xy 86.3 143.4)
        (xy 86.3 142.5)
        (xy 85.3 142.5)
        (xy 85.3 141)
        (xy 86.7 141)
      )
    )
  )
  (zone (net 228) (net_name "/USB-C Interface /5V0_DBG") (layer "F.Cu") (hatch edge 0.508)
    (priority 1)
    (connect_pads yes (clearance 0.125))
    (min_thickness 0.125) (filled_areas_thickness no)
    (fill yes (thermal_gap 0.508) (thermal_bridge_width 0.508))
    (polygon
      (pts
        (xy 126.3 140.2)
        (xy 126.1 140.4)
        (xy 126.1 141.5)
        (xy 125 141.5)
        (xy 125 139.7)
        (xy 126.3 139.7)
      )
    )
  )
  (zone (net 228) (net_name "/USB-C Interface /5V0_DBG") (layer "F.Cu") (hatch edge 0.508)
    (priority 1)
    (connect_pads yes (clearance 0.125))
    (min_thickness 0.125) (filled_areas_thickness no)
    (fill yes (thermal_gap 0.508) (thermal_bridge_width 0.508))
    (polygon
      (pts
        (xy 123.8 135.8)
        (xy 123.8 135.2)
        (xy 124.5 135.2)
        (xy 124.5 136.3)
        (xy 125.6 136.3)
        (xy 125.6 137.1)
        (xy 123.8 137.1)
        (xy 123.8 136.3)
      )
    )
  )
  (zone (net 133) (net_name "5V_SYS") (layer "F.Cu") (hatch edge 0.508)
    (priority 1)
    (connect_pads yes (clearance 0.125))
    (min_thickness 0.125) (filled_areas_thickness no)
    (fill yes (thermal_gap 0.508) (thermal_bridge_width 0.508))
    (polygon
      (pts
        (xy 124.5 133.4)
        (xy 124.5 134)
        (xy 123.9 134)
        (xy 123.9 133.4)
        (xy 123.5 133)
        (xy 123.5 132.2)
        (xy 125 132.2)
        (xy 125 132.9)
      )
    )
  )
  (zone (net 357) (net_name "Net-(C132-Pad2)") (layer "F.Cu") (hatch edge 0.508)
    (priority 1)
    (connect_pads yes (clearance 0.127))
    (min_thickness 0.125) (filled_areas_thickness no)
    (fill yes (thermal_gap 0.15) (thermal_bridge_width 0.15) (smoothing fillet) (radius 0.125))
    (polygon
      (pts
        (xy 85 95.2)
        (xy 85 96.3)
        (xy 83.85 96.3)
        (xy 83.55 96.6)
        (xy 83.55 98.1)
        (xy 82.75 98.1)
        (xy 82.75 96.6)
        (xy 82.45 96.3)
        (xy 81.59 96.3)
        (xy 81.59 95.2)
      )
    )
  )
  (zone (net 1) (net_name "GND") (layer "F.Cu") (hatch edge 0.508)
    (priority 1)
    (connect_pads yes (clearance 0.127))
    (min_thickness 0.125) (filled_areas_thickness no)
    (fill yes (thermal_gap 0.15) (thermal_bridge_width 0.15) (smoothing fillet) (radius 0.125))
    (polygon
      (pts
        (xy 85.15 96.8)
        (xy 85.15 98.9)
        (xy 83.7 98.9)
        (xy 83.7 96.8)
      )
    )
  )
  (zone (net 363) (net_name "Net-(C138-Pad2)") (layer "F.Cu") (hatch edge 0.508)
    (priority 1)
    (connect_pads yes (clearance 0.127))
    (min_thickness 0.125) (filled_areas_thickness no)
    (fill yes (thermal_gap 0.15) (thermal_bridge_width 0.15) (smoothing fillet) (radius 0.125))
    (polygon
      (pts
        (xy 78.15 119.77)
        (xy 77.05 119.77)
        (xy 77.05 118.35)
        (xy 76.75 118.05)
        (xy 75.25 118.05)
        (xy 75.25 117.25)
        (xy 76.75 117.25)
        (xy 77.05 116.95)
        (xy 77.05 116.26)
        (xy 78.15 116.26)
      )
    )
  )
  (zone (net 1) (net_name "GND") (layer "F.Cu") (hatch edge 0.508)
    (priority 1)
    (connect_pads yes (clearance 0.127))
    (min_thickness 0.125) (filled_areas_thickness no)
    (fill yes (thermal_gap 0.15) (thermal_bridge_width 0.15) (smoothing fillet) (radius 0.125))
    (polygon
      (pts
        (xy 81.56 120.45)
        (xy 83.86 120.45)
        (xy 83.86 122.55)
        (xy 81.56 122.55)
      )
    )
  )
  (zone (net 74) (net_name "VDD") (layer "F.Cu") (hatch edge 0.508)
    (priority 1)
    (connect_pads yes (clearance 0.127))
    (min_thickness 0.125) (filled_areas_thickness no)
    (fill yes (thermal_gap 0.15) (thermal_bridge_width 0.15) (smoothing fillet) (radius 0.125))
    (polygon
      (pts
        (xy 76.65 108.14)
        (xy 76.65 111.25)
        (xy 74.65 111.25)
        (xy 74.65 109.8)
        (xy 73.75 109.8)
        (xy 73.75 109.1)
        (xy 74.65 109.1)
        (xy 74.65 108.14)
      )
    )
  )
  (zone (net 1) (net_name "GND") (layer "F.Cu") (hatch edge 0.508)
    (priority 1)
    (connect_pads yes (clearance 0.127))
    (min_thickness 0.125) (filled_areas_thickness no)
    (fill yes (thermal_gap 0.15) (thermal_bridge_width 0.15) (smoothing fillet) (radius 0.125))
    (polygon
      (pts
        (xy 76.55 119.75)
        (xy 74.55 119.75)
        (xy 74.55 118.25)
        (xy 76.55 118.25)
      )
    )
  )
  (zone (net 1) (net_name "GND") (layer "F.Cu") (hatch edge 0.508)
    (priority 1)
    (connect_pads yes (clearance 0.127))
    (min_thickness 0.125) (filled_areas_thickness no)
    (fill yes (thermal_gap 0.15) (thermal_bridge_width 0.15) (smoothing fillet) (radius 0.125))
    (polygon
      (pts
        (xy 83.75 108.95)
        (xy 79.45 108.95)
        (xy 79.45 109.55)
        (xy 77.3 109.55)
        (xy 77.3 108.14)
        (xy 78.14 108.14)
        (xy 78.19 108.25)
        (xy 83.75 108.25)
      )
    )
  )
  (zone (net 133) (net_name "5V_SYS") (layer "F.Cu") (hatch edge 0.508)
    (priority 1)
    (connect_pads yes (clearance 0.127))
    (min_thickness 0.125) (filled_areas_thickness no)
    (fill yes (thermal_gap 0.15) (thermal_bridge_width 0.15) (smoothing fillet) (radius 0.125))
    (polygon
      (pts
        (xy 121.6 104.1)
        (xy 123.4 104.1)
        (xy 123.4 106)
        (xy 119.7 106)
        (xy 119.7 101.4)
        (xy 121.6 101.4)
      )
    )
  )
  (zone (net 359) (net_name "Net-(C133-Pad2)") (layer "F.Cu") (hatch edge 0.508)
    (priority 1)
    (connect_pads yes (clearance 0.127))
    (min_thickness 0.125) (filled_areas_thickness no)
    (fill yes (thermal_gap 0.15) (thermal_bridge_width 0.15) (smoothing fillet) (radius 0.125))
    (polygon
      (pts
        (xy 78.2 113.39)
        (xy 77.1 113.39)
        (xy 77.1 112.5)
        (xy 76.8 112.2)
        (xy 75.3 112.2)
        (xy 75.3 111.4)
        (xy 76.8 111.4)
        (xy 77.1 111.1)
        (xy 77.1 109.98)
        (xy 78.2 109.98)
      )
    )
  )
  (zone (net 132) (net_name "VREG_S4A_1V8") (layer "F.Cu") (hatch edge 0.508)
    (connect_pads yes (clearance 0.127))
    (min_thickness 0.127) (filled_areas_thickness no)
    (fill yes (thermal_gap 0.508) (thermal_bridge_width 0.508))
    (polygon
      (pts
        (xy 101.925 113.275)
        (xy 100.575 113.275)
        (xy 100.575 111.625)
        (xy 101.925 111.625)
      )
    )
  )
  (zone (net 74) (net_name "VDD") (layer "F.Cu") (hatch edge 0.508)
    (connect_pads yes (clearance 0.127))
    (min_thickness 0.254) (filled_areas_thickness no)
    (fill yes (thermal_gap 0.508) (thermal_bridge_width 0.508))
    (polygon
      (pts
        (xy 82.6 99.3)
        (xy 81 99.3)
        (xy 81 96.8)
        (xy 82.6 96.8)
      )
    )
  )
  (zone (net 1) (net_name "GND") (layer "F.Cu") (hatch edge 0.508)
    (connect_pads yes (clearance 0.127))
    (min_thickness 0.254) (filled_areas_thickness no)
    (fill yes (thermal_gap 0.508) (thermal_bridge_width 0.508))
    (polygon
      (pts
        (xy 85.3 92.3)
        (xy 82.6 92.3)
        (xy 82.6 88.8)
        (xy 85.3 88.8)
      )
    )
  )
  (zone (net 1) (net_name "GND") (layer "F.Cu") (hatch edge 0.508)
    (priority 1)
    (connect_pads yes (clearance 0.127))
    (min_thickness 0.125) (filled_areas_thickness no)
    (fill yes (thermal_gap 0.15) (thermal_bridge_width 0.15) (smoothing fillet) (radius 0.125))
    (polygon
      (pts
        (xy 79.55 115.35)
        (xy 77.4 115.35)
        (xy 77.4 114.05)
        (xy 79.55 114.05)
      )
    )
  )
  (zone (net 231) (net_name "/Camera Interface/3V3_CAM") (layer "F.Cu") (hatch edge 0.508)
    (priority 1)
    (connect_pads yes (clearance 0.127))
    (min_thickness 0.125) (filled_areas_thickness no)
    (fill yes (thermal_gap 0.15) (thermal_bridge_width 0.15) (smoothing fillet) (radius 0.125))
    (polygon
      (pts
        (xy 117.2 93.9)
        (xy 115.7 93.9)
        (xy 115.7 91.6)
        (xy 117.2 91.6)
      )
    )
  )
  (zone (net 74) (net_name "VDD") (layer "F.Cu") (hatch edge 0.508)
    (priority 1)
    (connect_pads yes (clearance 0.127))
    (min_thickness 0.125) (filled_areas_thickness no)
    (fill yes (thermal_gap 0.15) (thermal_bridge_width 0.15) (smoothing fillet) (radius 0.125))
    (polygon
      (pts
        (xy 76.6 114.25)
        (xy 76.6 117.1)
        (xy 74.6 117.1)
        (xy 74.6 115.65)
        (xy 73.7 115.65)
        (xy 73.7 114.95)
        (xy 74.6 114.95)
        (xy 74.6 114.25)
      )
    )
  )
  (zone (net 131) (net_name "3V3_SYS") (layer "F.Cu") (hatch edge 0.508)
    (priority 1)
    (connect_pads yes (clearance 0.127))
    (min_thickness 0.125) (filled_areas_thickness no)
    (fill yes (thermal_gap 0.15) (thermal_bridge_width 0.15) (smoothing fillet) (radius 0.125))
    (polygon
      (pts
        (xy 120.1 91.9)
        (xy 118.6 91.9)
        (xy 118.6 92.4)
        (xy 118 92.4)
        (xy 118 91.1)
        (xy 120.1 91.1)
      )
    )
  )
  (zone (net 424) (net_name "/SoM/VBAT_SOM") (layer "F.Cu") (hatch edge 0.508)
    (connect_pads yes (clearance 0.127))
    (min_thickness 0.254) (filled_areas_thickness no)
    (fill yes (thermal_gap 0.508) (thermal_bridge_width 0.508))
    (polygon
      (pts
        (xy 94.45 82.625)
        (xy 94.95 82.625)
        (xy 94.95 86.7125)
        (xy 94.95 90.675)
        (xy 95.075 90.8)
        (xy 95.3 90.8)
        (xy 95.46 90.9)
        (xy 95.46 91.5)
        (xy 92.5 91.5)
        (xy 92.4 91.6)
        (xy 92.4 92.1)
        (xy 92.25 92.25)
        (xy 88.3 92.25)
        (xy 88.15 92.4)
        (xy 86.1 92.4)
        (xy 86.1 89.6)
        (xy 92.5 89.61)
        (xy 92.5 84.2)
        (xy 86.1 84.2)
        (xy 86.1 82.65)
      )
    )
  )
  (zone (net 106) (net_name "SD_LDO21A") (layer "F.Cu") (hatch edge 0.508)
    (connect_pads yes (clearance 0.125))
    (min_thickness 0.125) (filled_areas_thickness no)
    (fill yes (thermal_gap 0.508) (thermal_bridge_width 0.508))
    (polygon
      (pts
        (xy 96.95 90.6)
        (xy 99.6 90.6)
        (xy 99.6 92.15)
        (xy 95.6 92.15)
        (xy 95.6 90.89)
        (xy 95.55 90.75)
        (xy 95.55 88.7)
        (xy 96.95 88.7)
      )
    )
  )
  (zone (net 1) (net_name "GND") (layer "F.Cu") (hatch edge 0.508)
    (connect_pads yes (clearance 0.127))
    (min_thickness 0.254) (filled_areas_thickness no)
    (fill yes (thermal_gap 0.508) (thermal_bridge_width 0.508))
    (polygon
      (pts
        (xy 85 83.95)
        (xy 82.75 83.95)
        (xy 82.75 82.45)
        (xy 85 82.45)
      )
    )
  )
  (zone (net 1) (net_name "GND") (layer "F.Cu") (hatch edge 0.508)
    (priority 1)
    (connect_pads yes (clearance 0.127))
    (min_thickness 0.125) (filled_areas_thickness no)
    (fill yes (thermal_gap 0.15) (thermal_bridge_width 0.15) (smoothing fillet) (radius 0.125))
    (polygon
      (pts
        (xy 116.775 105.9)
        (xy 113.225 105.9)
        (xy 113.25 101.45)
        (xy 116.8 101.45)
      )
    )
  )
  (zone (net 353) (net_name "Net-(C108-Pad1)") (layer "F.Cu") (hatch edge 0.508)
    (priority 1)
    (connect_pads yes (clearance 0.127))
    (min_thickness 0.125) (filled_areas_thickness no)
    (fill yes (thermal_gap 0.15) (thermal_bridge_width 0.15) (smoothing fillet) (radius 0.125))
    (polygon
      (pts
        (xy 118.65 95.15)
        (xy 120.25 95.15)
        (xy 120.25 97.45)
        (xy 119.1 97.45)
        (xy 119.1 105.55)
        (xy 117.5 105.55)
        (xy 117.5 97.45)
        (xy 116.35 97.45)
        (xy 116.35 95.15)
        (xy 117.95 95.15)
        (xy 117.95 93.05)
        (xy 118.65 93.05)
      )
    )
  )
  (zone (net 131) (net_name "3V3_SYS") (layer "F.Cu") (hatch edge 0.508)
    (priority 1)
    (connect_pads yes (clearance 0.127))
    (min_thickness 0.125) (filled_areas_thickness no)
    (fill yes (thermal_gap 0.15) (thermal_bridge_width 0.15) (smoothing fillet) (radius 0.125))
    (polygon
      (pts
        (xy 83.92 112.4)
        (xy 80.7 112.4)
        (xy 80.7 113.6)
        (xy 79.5 113.6)
        (xy 79.5 109.7)
        (xy 83.92 109.7)
      )
    )
  )
  (zone (net 137) (net_name "3V8_SYS") (layer "F.Cu") (hatch edge 0.508)
    (connect_pads yes (clearance 0.127))
    (min_thickness 0.254) (filled_areas_thickness no)
    (fill yes (thermal_gap 0.508) (thermal_bridge_width 0.508))
    (polygon
      (pts
        (xy 82 92.6)
        (xy 82.2 92.8)
        (xy 86.2 92.8)
        (xy 88.31 94.8)
        (xy 88.31 97)
        (xy 86.4 97)
        (xy 86.4 95.3)
        (xy 84.9 94)
        (xy 81.2 94)
        (xy 81.2 89.52)
        (xy 82 89.52)
      )
    )
  )
  (zone (net 1) (net_name "GND") (layer "F.Cu") (hatch edge 0.508)
    (priority 1)
    (connect_pads yes (clearance 0.125))
    (min_thickness 0.125) (filled_areas_thickness no)
    (fill yes (thermal_gap 0.508) (thermal_bridge_width 0.508))
    (polygon
      (pts
        (xy 95.411159 91.775)
        (xy 95.411159 92.45)
        (xy 95.4 94.25)
        (xy 95.2 94.45)
        (xy 91.7 94.45)
        (xy 91.55 94.6)
        (xy 91.55 96.8)
        (xy 89.011159 96.8)
        (xy 89.011159 93)
        (xy 92.6 93)
        (xy 92.725 92.875)
        (xy 92.725 91.925)
        (xy 92.875 91.775)
      )
    )
  )
  (zone (net 1) (net_name "GND") (layer "F.Cu") (hatch edge 0.508)
    (priority 1)
    (connect_pads yes (clearance 0.127))
    (min_thickness 0.125) (filled_areas_thickness no)
    (fill yes (thermal_gap 0.15) (thermal_bridge_width 0.15) (smoothing fillet) (radius 0.125))
    (polygon
      (pts
        (xy 76.6 113.9)
        (xy 74.6 113.9)
        (xy 74.6 112.4)
        (xy 76.6 112.4)
      )
    )
  )
  (zone (net 1) (net_name "GND") (layer "F.Cu") (hatch edge 0.508)
    (priority 1)
    (connect_pads yes (clearance 0.127))
    (min_thickness 0.125) (filled_areas_thickness no)
    (fill yes (thermal_gap 0.15) (thermal_bridge_width 0.15) (smoothing fillet) (radius 0.125))
    (polygon
      (pts
        (xy 124.55 105.7)
        (xy 124.05 105.7)
        (xy 124.05 104.4)
        (xy 125.85 104.4)
        (xy 125.85 108.05)
        (xy 124.55 108.05)
      )
    )
  )
  (zone (net 133) (net_name "5V_SYS") (layer "F.Cu") (hatch edge 0.508)
    (priority 1)
    (connect_pads yes (clearance 0.127))
    (min_thickness 0.125) (filled_areas_thickness no)
    (fill yes (thermal_gap 0.15) (thermal_bridge_width 0.15) (smoothing fillet) (radius 0.125))
    (polygon
      (pts
        (xy 83.6 118.6)
        (xy 83.6 119.65)
        (xy 79.5 119.65)
        (xy 79.5 116.28)
        (xy 80.95 116.28)
      )
    )
  )
  (zone (net 133) (net_name "5V_SYS") (layer "In1.Cu") (hatch edge 0.508)
    (connect_pads yes (clearance 0.15))
    (min_thickness 0.125) (filled_areas_thickness no)
    (fill yes (thermal_gap 0.15) (thermal_bridge_width 0.15) (smoothing fillet) (radius 0.125))
    (polygon
      (pts
        (xy 155 152)
        (xy 73.5 152)
        (xy 73.5 137.1)
        (xy 59.4 137.1)
        (xy 57.6 135.3)
        (xy 57.6 132)
        (xy 63.8 132)
        (xy 66.2 129.6)
        (xy 70 129.55)
        (xy 70 81.95)
        (xy 155 82)
      )
    )
  )
  (zone (net 74) (net_name "VDD") (layer "In1.Cu") (hatch edge 0.508)
    (priority 2)
    (connect_pads yes (clearance 0.125))
    (min_thickness 0.125) (filled_areas_thickness no)
    (fill yes (thermal_gap 0.508) (thermal_bridge_width 0.508))
    (polygon
      (pts
        (xy 82.9 99.4)
        (xy 80 99.4)
        (xy 80 129.3)
        (xy 70 129.3)
        (xy 70 97.8)
        (xy 82.9 97.8)
      )
    )
  )
  (zone (net 131) (net_name "3V3_SYS") (layer "In3.Cu") (hatch edge 0.508)
    (connect_pads yes (clearance 0.15))
    (min_thickness 0.125) (filled_areas_thickness no)
    (fill yes (thermal_gap 0.15) (thermal_bridge_width 0.15) (smoothing fillet) (radius 0.125))
    (polygon
      (pts
        (xy 155 152)
        (xy 73.5 152)
        (xy 73.5 137.1)
        (xy 59.4 137.1)
        (xy 57.6 135.3)
        (xy 57.6 132)
        (xy 63.8 132)
        (xy 66.2 129.6)
        (xy 70 129.6)
        (xy 70 81.95)
        (xy 155 82)
      )
    )
  )
  (zone (net 106) (net_name "SD_LDO21A") (layer "In3.Cu") (hatch edge 0.508)
    (priority 1)
    (connect_pads yes (clearance 0.125))
    (min_thickness 0.125) (filled_areas_thickness no)
    (fill yes (thermal_gap 0.508) (thermal_bridge_width 0.508))
    (polygon
      (pts
        (xy 128.061606 104.65)
        (xy 126.411606 104.65)
        (xy 126.411606 103.25)
        (xy 128.061606 103.25)
      )
    )
  )
  (zone (net 210) (net_name "/USB-C Interface /USB2_5V") (layer "In3.Cu") (hatch edge 0.508)
    (priority 1)
    (connect_pads yes (clearance 0.125))
    (min_thickness 0.125) (filled_areas_thickness no)
    (fill yes (thermal_gap 0.508) (thermal_bridge_width 0.508))
    (polygon
      (pts
        (xy 118 149)
        (xy 106.75 149)
        (xy 106.75 144.77)
        (xy 107.62 144.77)
        (xy 107.85 145)
        (xy 112.5 145)
        (xy 112.5 141.25)
        (xy 118 141.25)
      )
    )
  )
  (zone (net 66) (net_name "USB_VBUS") (layer "In3.Cu") (hatch edge 0.508)
    (priority 1)
    (connect_pads yes (clearance 0.125))
    (min_thickness 0.125) (filled_areas_thickness no)
    (fill yes (thermal_gap 0.15) (thermal_bridge_width 0.15) (smoothing fillet) (radius 0.125))
    (polygon
      (pts
        (xy 95.9 134)
        (xy 104.1 134)
        (xy 104.1 149)
        (xy 97.1 149)
        (xy 97.1 137.6)
        (xy 92 137.6)
        (xy 92 113.4)
        (xy 95.9 113.4)
      )
    )
  )
  (zone (net 106) (net_name "SD_LDO21A") (layer "In3.Cu") (hatch edge 0.508)
    (priority 1)
    (connect_pads yes (clearance 0.125))
    (min_thickness 0.125) (filled_areas_thickness no)
    (fill yes (thermal_gap 0.508) (thermal_bridge_width 0.508))
    (polygon
      (pts
        (xy 99.7 92.05)
        (xy 98.05 92.05)
        (xy 98.05 90.65)
        (xy 99.7 90.65)
      )
    )
  )
  (zone (net 7) (net_name "GNDD") (layer "In4.Cu") (hatch edge 0.508)
    (connect_pads yes (clearance 0.5))
    (min_thickness 0.125) (filled_areas_thickness no)
    (fill yes (thermal_gap 0.15) (thermal_bridge_width 0.15) (smoothing fillet) (radius 0.125))
    (polygon
      (pts
        (xy 59.75 82)
        (xy 59.75 88.5)
        (xy 63 91.75)
        (xy 63 107.5)
        (xy 55 107.5)
        (xy 55 82)
      )
    )
  )
  (zone (net 1) (net_name "GND") (layer "In4.Cu") (hatch edge 0.508)
    (priority 1)
    (connect_pads yes (clearance 0.15))
    (min_thickness 0.125) (filled_areas_thickness no)
    (fill yes (thermal_gap 0.15) (thermal_bridge_width 0.15) (smoothing fillet) (radius 0.125))
    (polygon
      (pts
        (xy 155 152)
        (xy 73.9 152)
        (xy 73.9 137.1)
        (xy 71.1 137.1)
        (xy 71.1 135)
        (xy 70 135)
        (xy 70 129.55)
        (xy 70 105.75)
        (xy 70 81.95)
        (xy 155 82)
      )
    )
  )
  (zone (net 4) (net_name "Earth") (layer "In4.Cu") (hatch edge 0.508)
    (connect_pads yes (clearance 0.5))
    (min_thickness 0.125) (filled_areas_thickness no)
    (fill yes (thermal_gap 0.15) (thermal_bridge_width 0.15) (smoothing fillet) (radius 0.125))
    (polygon
      (pts
        (xy 69 129)
        (xy 65.75 129)
        (xy 63.75 131)
        (xy 57 131)
        (xy 57 135.2)
        (xy 59.8 138)
        (xy 73 138)
        (xy 73 152)
        (xy 55 152)
        (xy 55 108.25)
        (xy 69 108.25)
      )
    )
  )
  (zone (net 210) (net_name "/USB-C Interface /USB2_5V") (layer "B.Cu") (hatch edge 0.508)
    (connect_pads yes (clearance 0.125))
    (min_thickness 0.125) (filled_areas_thickness no)
    (fill yes (thermal_gap 0.508) (thermal_bridge_width 0.508))
    (polygon
      (pts
        (xy 118 148.9)
        (xy 116.1 148.9)
        (xy 116.1 147.1)
        (xy 118 147.1)
      )
    )
  )
  (zone (net 1) (net_name "GND") (layer "B.Cu") (hatch edge 0.508)
    (connect_pads yes (clearance 0.127))
    (min_thickness 0.125) (filled_areas_thickness no)
    (fill yes (thermal_gap 0.15) (thermal_bridge_width 0.15) (smoothing fillet) (radius 0.125))
    (polygon
      (pts
        (xy 126.8 121.4)
        (xy 124.8 121.4)
        (xy 124.8 119.8)
        (xy 126.8 119.8)
      )
    )
  )
  (zone (net 133) (net_name "5V_SYS") (layer "B.Cu") (hatch edge 0.508)
    (connect_pads yes (clearance 0.127))
    (min_thickness 0.125) (filled_areas_thickness no)
    (fill yes (thermal_gap 0.15) (thermal_bridge_width 0.15) (smoothing fillet) (radius 0.125))
    (polygon
      (pts
        (xy 126.8 125.3)
        (xy 123.95 125.3)
        (xy 123.95 123.6)
        (xy 125.2 123.6)
        (xy 125.5 123.3)
        (xy 125.5 122.5)
        (xy 126.8 122.5)
      )
    )
  )
  (zone (net 1) (net_name "GND") (layer "B.Cu") (hatch edge 0.508)
    (connect_pads yes (clearance 0.127))
    (min_thickness 0.125) (filled_areas_thickness no)
    (fill yes (thermal_gap 0.15) (thermal_bridge_width 0.15) (smoothing fillet) (radius 0.125))
    (polygon
      (pts
        (xy 129.2 126.8)
        (xy 127.2 126.8)
        (xy 127.2 124.4)
        (xy 129.2 124.4)
      )
    )
  )
  (zone (net 138) (net_name "1V2_SYS") (layer "B.Cu") (hatch edge 0.508)
    (connect_pads yes (clearance 0.127))
    (min_thickness 0.125) (filled_areas_thickness no)
    (fill yes (thermal_gap 0.15) (thermal_bridge_width 0.15) (smoothing fillet) (radius 0.125))
    (polygon
      (pts
        (xy 133.8 121.4)
        (xy 130.8 121.4)
        (xy 130.8 126.9)
        (xy 129.9 126.9)
        (xy 129.9 124)
        (xy 129.7 123.8)
        (xy 129.7 120.2)
        (xy 133.8 120.2)
      )
    )
  )
  (zone (net 360) (net_name "Net-(C134-Pad2)") (layer "B.Cu") (hatch edge 0.508)
    (priority 1)
    (connect_pads yes (clearance 0.127))
    (min_thickness 0.125) (filled_areas_thickness no)
    (fill yes (thermal_gap 0.15) (thermal_bridge_width 0.15) (smoothing fillet) (radius 0.125))
    (polygon
      (pts
        (xy 128.4 123.7)
        (xy 127.3 123.7)
        (xy 127.3 122.65)
        (xy 127 122.35)
        (xy 125.5 122.35)
        (xy 125.5 121.55)
        (xy 127 121.55)
        (xy 127.3 121.25)
        (xy 127.3 120.2)
        (xy 128.4 120.2)
      )
    )
  )
  (zone (net 131) (net_name "3V3_SYS") (layer "B.Cu") (hatch edge 0.508)
    (connect_pads yes (clearance 0.127))
    (min_thickness 0.125) (filled_areas_thickness no)
    (fill yes (thermal_gap 0.15) (thermal_bridge_width 0.15) (smoothing fillet) (radius 0.125))
    (polygon
      (pts
        (xy 150.1 137.45)
        (xy 148.9 137.45)
        (xy 148.9 135.8)
        (xy 150.1 135.8)
      )
    )
  )
  (zone (net 1) (net_name "GND") (layer "B.Cu") (hatch edge 0.508)
    (connect_pads yes (clearance 0.127))
    (min_thickness 0.125) (filled_areas_thickness no)
    (fill yes (thermal_gap 0.15) (thermal_bridge_width 0.15) (smoothing fillet) (radius 0.125))
    (polygon
      (pts
        (xy 74.25 101.55)
        (xy 74.25 102.05)
        (xy 72.35 102.05)
        (xy 72.375 99)
        (xy 80.025 99)
        (xy 80 101.5)
      )
    )
  )
  (zone (net 136) (net_name "5V_POE") (layer "B.Cu") (hatch edge 0.508)
    (connect_pads yes (clearance 0.127))
    (min_thickness 0.125) (filled_areas_thickness no)
    (fill yes (thermal_gap 0.15) (thermal_bridge_width 0.15) (smoothing fillet) (radius 0.125))
    (polygon
      (pts
        (xy 79.8 106.85)
        (xy 74.1 106.85)
        (xy 74.1 103.7)
        (xy 72.3 103.7)
        (xy 72.3 102.35)
        (xy 79.8 102.35)
      )
    )
  )
  (zone (net 73) (net_name "/PoE/VDD_POE") (layer "B.Cu") (hatch edge 0.508)
    (connect_pads yes (clearance 0.127))
    (min_thickness 0.125) (filled_areas_thickness no)
    (fill yes (thermal_gap 0.15) (thermal_bridge_width 0.15) (smoothing fillet) (radius 0.125))
    (polygon
      (pts
        (xy 68.4 119.1)
        (xy 61.5 119.1)
        (xy 61.5 115.1)
        (xy 62 114.6)
        (xy 62 111.4)
        (xy 62.6 111.4)
        (xy 64 110)
        (xy 68.4 110)
      )
    )
  )
  (zone (net 135) (net_name "/PoE/VSS_POE") (layer "B.Cu") (hatch edge 0.508)
    (connect_pads yes (clearance 0.127))
    (min_thickness 0.125) (filled_areas_thickness no)
    (fill yes (thermal_gap 0.15) (thermal_bridge_width 0.15) (smoothing fillet) (radius 0.125))
    (polygon
      (pts
        (xy 62.3 110.7)
        (xy 59.4 110.7)
        (xy 59.2 110.9)
        (xy 59.2 113.3)
        (xy 59.4 113.5)
        (xy 59.4 114)
        (xy 60.3 114.9)
        (xy 60.3 116.8)
        (xy 60.8 117.3)
        (xy 60.8 119.1)
        (xy 55 119.1)
        (xy 55 108.3)
        (xy 62.3 108.3)
      )
    )
  )
  (zone (net 7) (net_name "GNDD") (layer "B.Cu") (hatch edge 0.508)
    (connect_pads yes (clearance 0.127))
    (min_thickness 0.125) (filled_areas_thickness no)
    (fill yes (thermal_gap 0.15) (thermal_bridge_width 0.15) (smoothing fillet) (radius 0.125))
    (polygon
      (pts
        (xy 59.2 107.6)
        (xy 55 107.6)
        (xy 55 105)
        (xy 59.2 105)
      )
    )
  )
  (zone (net 131) (net_name "3V3_SYS") (layer "B.Cu") (hatch edge 0.508)
    (connect_pads yes (clearance 0.125))
    (min_thickness 0.125) (filled_areas_thickness no)
    (fill yes (thermal_gap 0.508) (thermal_bridge_width 0.508))
    (polygon
      (pts
        (xy 145.15 109.5)
        (xy 140.53 109.5)
        (xy 140.53 108.6)
        (xy 143.95 108.6)
        (xy 143.95 107.1)
        (xy 140.54 107.1)
        (xy 140.54 105.1)
        (xy 143.95 105.1)
        (xy 143.95 92.6)
        (xy 141.75 92.6)
        (xy 140.53 92.6)
        (xy 140.53 91.15)
        (xy 145.15 91.15)
      )
    )
  )
  (zone (net 152) (net_name "/PSU/AUX_VDD") (layer "B.Cu") (hatch edge 0.508)
    (priority 1)
    (connect_pads yes (clearance 0.125))
    (min_thickness 0.125) (filled_areas_thickness no)
    (fill yes (thermal_gap 0.508) (thermal_bridge_width 0.508))
    (polygon
      (pts
        (xy 77.5 138.6)
        (xy 79.2 140.3)
        (xy 79.2 144.2)
        (xy 78.5 144.9)
        (xy 77.7 145.7)
        (xy 77.7 147.3)
        (xy 76.9 147.3)
        (xy 76.9 144.6)
        (xy 77.3 144.2)
        (xy 77.3 141.7)
        (xy 75 139.4)
        (xy 75 136.825)
        (xy 77.45 136.825)
      )
    )
  )
  (zone (net 157) (net_name "/PSU/VS1") (layer "B.Cu") (hatch edge 0.508)
    (priority 1)
    (connect_pads yes (clearance 0.125))
    (min_thickness 0.125) (filled_areas_thickness no)
    (fill yes (thermal_gap 0.508) (thermal_bridge_width 0.508))
    (polygon
      (pts
        (xy 79.25 137.35)
        (xy 77.95 137.35)
        (xy 77.95 136.8)
        (xy 78.65 136.8)
        (xy 78.65 136.05)
        (xy 77.95 136.05)
        (xy 77.95 135.5)
        (xy 79.25 135.5)
      )
    )
  )
  (zone (net 158) (net_name "/PSU/VS2") (layer "B.Cu") (hatch edge 0.508)
    (priority 1)
    (connect_pads yes (clearance 0.125))
    (min_thickness 0.125) (filled_areas_thickness no)
    (fill yes (thermal_gap 0.508) (thermal_bridge_width 0.508))
    (polygon
      (pts
        (xy 84.35 137.356176)
        (xy 83.05 137.356176)
        (xy 83.05 136.806176)
        (xy 83.75 136.806176)
        (xy 83.75 136.056176)
        (xy 83.05 136.056176)
        (xy 83.05 135.506176)
        (xy 84.35 135.506176)
      )
    )
  )
  (zone (net 107) (net_name "/USB-PD/PD_VBUS") (layer "B.Cu") (hatch edge 0.508)
    (priority 1)
    (connect_pads yes (clearance 0.125))
    (min_thickness 0.125) (filled_areas_thickness no)
    (fill yes (thermal_gap 0.508) (thermal_bridge_width 0.508))
    (polygon
      (pts
        (xy 90.2 146.8)
        (xy 81.8 146.8)
        (xy 81.8 141.9)
        (xy 84.2 141.9)
        (xy 84.2 141)
        (xy 86.7 141)
        (xy 86.7 142.5)
        (xy 88.8 142.5)
        (xy 88.8 141)
        (xy 90.2 141)
      )
    )
  )
  (zone (net 210) (net_name "/USB-C Interface /USB2_5V") (layer "B.Cu") (hatch edge 0.508)
    (connect_pads yes (clearance 0.125))
    (min_thickness 0.125) (filled_areas_thickness no)
    (fill yes (thermal_gap 0.508) (thermal_bridge_width 0.508))
    (polygon
      (pts
        (xy 108.2 147.1)
        (xy 106.8 147.1)
        (xy 106.8 144.5)
        (xy 108.2 144.5)
      )
    )
  )
  (zone (net 1) (net_name "GND") (layer "B.Cu") (hatch edge 0.508)
    (connect_pads yes (clearance 0.125))
    (min_thickness 0.125) (filled_areas_thickness no)
    (fill yes (thermal_gap 0.508) (thermal_bridge_width 0.508))
    (polygon
      (pts
        (xy 109.2 139.25)
        (xy 106.8 139.25)
        (xy 106.8 137)
        (xy 109.2 137)
      )
    )
  )
  (zone (net 133) (net_name "5V_SYS") (layer "B.Cu") (hatch edge 0.508)
    (connect_pads yes (clearance 0.125))
    (min_thickness 0.125) (filled_areas_thickness no)
    (fill yes (thermal_gap 0.508) (thermal_bridge_width 0.508))
    (polygon
      (pts
        (xy 109.2 142.4)
        (xy 108.7 142.4)
        (xy 108.7 143.1)
        (xy 106.8 143.1)
        (xy 106.8 140.6)
        (xy 106.8 140)
        (xy 109.2 140)
      )
    )
  )
  (zone (net 210) (net_name "/USB-C Interface /USB2_5V") (layer "B.Cu") (hatch edge 0.508)
    (connect_pads yes (clearance 0.125))
    (min_thickness 0.125) (filled_areas_thickness no)
    (fill yes (thermal_gap 0.508) (thermal_bridge_width 0.508))
    (polygon
      (pts
        (xy 113.9 148.9)
        (xy 111.5 148.9)
        (xy 111.5 148.1)
        (xy 113.9 148.1)
      )
    )
  )
  (zone (net 1) (net_name "GND") (layer "B.Cu") (hatch edge 0.508)
    (connect_pads yes (clearance 0.125))
    (min_thickness 0.125) (filled_areas_thickness no)
    (fill yes (thermal_gap 0.508) (thermal_bridge_width 0.508))
    (polygon
      (pts
        (xy 118 150.3)
        (xy 113 150.3)
        (xy 113 149.6)
        (xy 118 149.6)
      )
    )
  )
  (zone (net 1) (net_name "GND") (layer "B.Cu") (hatch edge 0.508)
    (connect_pads yes (clearance 0.125))
    (min_thickness 0.125) (filled_areas_thickness no)
    (fill yes (thermal_gap 0.508) (thermal_bridge_width 0.508))
    (polygon
      (pts
        (xy 104 150.3)
        (xy 99 150.3)
        (xy 99 149.6)
        (xy 104 149.6)
      )
    )
  )
  (zone (net 66) (net_name "USB_VBUS") (layer "B.Cu") (hatch edge 0.508)
    (connect_pads yes (clearance 0.125))
    (min_thickness 0.125) (filled_areas_thickness no)
    (fill yes (thermal_gap 0.508) (thermal_bridge_width 0.508))
    (polygon
      (pts
        (xy 99.9 148.9)
        (xy 99 148.9)
        (xy 99 146.6)
        (xy 99.9 146.6)
      )
    )
  )
  (zone (net 66) (net_name "USB_VBUS") (layer "B.Cu") (hatch edge 0.508)
    (connect_pads yes (clearance 0.125))
    (min_thickness 0.125) (filled_areas_thickness no)
    (fill yes (thermal_gap 0.508) (thermal_bridge_width 0.508))
    (polygon
      (pts
        (xy 104 148.9)
        (xy 102.1 148.9)
        (xy 102.1 147.3)
        (xy 104 147.3)
      )
    )
  )
  (zone (net 228) (net_name "/USB-C Interface /5V0_DBG") (layer "B.Cu") (hatch edge 0.508)
    (priority 1)
    (connect_pads yes (clearance 0.125))
    (min_thickness 0.125) (filled_areas_thickness no)
    (fill yes (thermal_gap 0.15) (thermal_bridge_width 0.15) (smoothing fillet) (radius 0.125))
    (polygon
      (pts
        (xy 126.4 136.3)
        (xy 126.4 138.35)
        (xy 132 138.35)
        (xy 132 137.6)
        (xy 132.8 137.6)
        (xy 132.8 138.95)
        (xy 126.3 138.95)
        (xy 126.3 140.35)
        (xy 125 140.35)
        (xy 125 139.7)
        (xy 125.75 139.7)
        (xy 125.75 137.1)
        (xy 124.45 137.1)
        (xy 124.45 138.5)
        (xy 123.8 138.5)
        (xy 123.8 137)
        (xy 123.8 136.3)
        (xy 124.7 136.3)
      )
    )
  )
  (zone (net 127) (net_name "1V8_DBG") (layer "B.Cu") (hatch edge 0.508)
    (priority 1)
    (connect_pads yes (clearance 0.125))
    (min_thickness 0.125) (filled_areas_thickness no)
    (fill yes (thermal_gap 0.15) (thermal_bridge_width 0.15) (smoothing fillet) (radius 0.125))
    (polygon
      (pts
        (xy 126.4 133.5)
        (xy 126.7 133.8)
        (xy 127.2 134.3)
        (xy 128.2 134.3)
        (xy 128.2 135)
        (xy 126.4 135)
        (xy 126.4 135.8)
        (xy 125.7 135.8)
        (xy 125.7 134.3)
        (xy 125.2 134.3)
        (xy 125.2 133.5)
        (xy 126 133.5)
      )
    )
  )
  (zone (net 1) (net_name "GND") (layer "B.Cu") (hatch edge 0.508)
    (priority 1)
    (connect_pads yes (clearance 0.125))
    (min_thickness 0.125) (filled_areas_thickness no)
    (fill yes (thermal_gap 0.15) (thermal_bridge_width 0.15) (smoothing fillet) (radius 0.125))
    (polygon
      (pts
        (xy 128.9 137.55)
        (xy 127.3 137.55)
        (xy 127.3 135.75)
        (xy 128.9 135.75)
      )
    )
  )
  (zone (net 1) (net_name "GND") (layer "B.Cu") (hatch edge 0.508)
    (priority 1)
    (connect_pads yes (clearance 0.125))
    (min_thickness 0.125) (filled_areas_thickness no)
    (fill yes (thermal_gap 0.15) (thermal_bridge_width 0.15) (smoothing fillet) (radius 0.125))
    (polygon
      (pts
        (xy 125.4 139.55)
        (xy 123.85 139.55)
        (xy 123.85 138.85)
        (xy 124.8 138.85)
        (xy 124.8 137.5)
        (xy 125.4 137.5)
      )
    )
  )
  (zone (net 159) (net_name "/PSU/VS3") (layer "B.Cu") (hatch edge 0.508)
    (priority 1)
    (connect_pads yes (clearance 0.125))
    (min_thickness 0.125) (filled_areas_thickness no)
    (fill yes (thermal_gap 0.508) (thermal_bridge_width 0.508))
    (polygon
      (pts
        (xy 72.3 106.3014)
        (xy 73.6 106.3014)
        (xy 73.6 106.8514)
        (xy 72.9 106.8514)
        (xy 72.9 107.6014)
        (xy 73.6 107.6014)
        (xy 73.6 108.1514)
        (xy 72.3 108.1514)
      )
    )
  )
  (zone (net 1) (net_name "GND") (layer "B.Cu") (hatch edge 0.508)
    (priority 1)
    (connect_pads yes (clearance 0.127))
    (min_thickness 0.125) (filled_areas_thickness no)
    (fill yes (thermal_gap 0.15) (thermal_bridge_width 0.15) (smoothing fillet) (radius 0.125))
    (polygon
      (pts
        (xy 108.15 148.9)
        (xy 108.15 147.35)
        (xy 106.85 147.35)
        (xy 106.85 148.9)
      )
    )
  )
  (zone (net 133) (net_name "5V_SYS") (layer "B.Cu") (hatch edge 0.508)
    (priority 1)
    (connect_pads yes (clearance 0.127))
    (min_thickness 0.125) (filled_areas_thickness no)
    (fill yes (thermal_gap 0.15) (thermal_bridge_width 0.15) (smoothing fillet) (radius 0.125))
    (polygon
      (pts
        (xy 83.6 118.6)
        (xy 83.6 118.95)
        (xy 78.35 118.95)
        (xy 78.35 116.35)
        (xy 81.35 116.35)
      )
    )
  )
  (zone (net 142) (net_name "PD_VDD") (layer "B.Cu") (hatch edge 0.508)
    (priority 1)
    (connect_pads yes (clearance 0.125))
    (min_thickness 0.125) (filled_areas_thickness no)
    (fill yes (thermal_gap 0.508) (thermal_bridge_width 0.508))
    (polygon
      (pts
        (xy 82.55 138.925)
        (xy 83.675 138.925)
        (xy 83.675 141.425)
        (xy 81.1 141.425)
        (xy 81.1 139.5)
        (xy 79.8 139.5)
        (xy 79.8 136.825)
        (xy 80.125 136.825)
        (xy 82.55 136.825)
      )
    )
  )
  (zone (net 74) (net_name "VDD") (layer "B.Cu") (hatch edge 0.508)
    (priority 2)
    (connect_pads yes (clearance 0.125))
    (min_thickness 0.125) (filled_areas_thickness no)
    (fill yes (thermal_gap 0.508) (thermal_bridge_width 0.508))
    (polygon
      (pts
        (xy 84.6 128.7)
        (xy 82.6 130.7)
        (xy 82.6 135)
        (xy 82.6 136.7)
        (xy 80 136.7)
        (xy 80 134.7)
        (xy 77.5 134.7)
        (xy 77.5 136.7)
        (xy 75 136.7)
        (xy 75 127.9)
        (xy 84.6 127.9)
      )
    )
  )
  (zone (net 227) (net_name "/Other Interfaces/SD_VDD_R") (layer "B.Cu") (hatch edge 0.508)
    (connect_pads yes (clearance 0.125))
    (min_thickness 0.125) (filled_areas_thickness no)
    (fill yes (thermal_gap 0.508) (thermal_bridge_width 0.508))
    (polygon
      (pts
        (xy 131.1 104.9)
        (xy 129 104.9)
        (xy 129 103.1)
        (xy 130.3 103.1)
        (xy 130.3 98.1)
        (xy 131.1 98.1)
      )
    )
  )
  (zone (net 74) (net_name "VDD") (layer "B.Cu") (hatch edge 0.508)
    (priority 1)
    (connect_pads yes (clearance 0.127))
    (min_thickness 0.125) (filled_areas_thickness no)
    (fill yes (thermal_gap 0.15) (thermal_bridge_width 0.15) (smoothing fillet) (radius 0.125))
    (polygon
      (pts
        (xy 76.55 110.35)
        (xy 74.1 110.35)
        (xy 74.1 106.95)
        (xy 76.55 106.95)
      )
    )
  )
  (zone (net 1) (net_name "GND") (layer "B.Cu") (hatch edge 0.508)
    (connect_pads yes (clearance 0.127))
    (min_thickness 0.254) (filled_areas_thickness no)
    (fill yes (thermal_gap 0.508) (thermal_bridge_width 0.508))
    (polygon
      (pts
        (xy 85.1 98.8)
        (xy 83.9 98.8)
        (xy 83.1 98)
        (xy 82.4 98)
        (xy 82.4 97.2)
        (xy 85.1 97.2)
      )
    )
  )
  (zone (net 106) (net_name "SD_LDO21A") (layer "B.Cu") (hatch edge 0.508)
    (connect_pads yes (clearance 0.125))
    (min_thickness 0.125) (filled_areas_thickness no)
    (fill yes (thermal_gap 0.508) (thermal_bridge_width 0.508))
    (polygon
      (pts
        (xy 128.65 104.65)
        (xy 126.5 104.65)
        (xy 126.5 103.1)
        (xy 128.65 103.1)
      )
    )
  )
  (zone (net 1) (net_name "GND") (layer "B.Cu") (hatch edge 0.508)
    (connect_pads yes (clearance 0.127))
    (min_thickness 0.127) (filled_areas_thickness no)
    (fill yes (thermal_gap 0.508) (thermal_bridge_width 0.508))
    (polygon
      (pts
        (xy 152.5 92.3)
        (xy 149.6 92.3)
        (xy 149.6 90.9)
        (xy 152.5 90.9)
      )
    )
  )
  (zone (net 231) (net_name "/Camera Interface/3V3_CAM") (layer "B.Cu") (hatch edge 0.508)
    (priority 1)
    (connect_pads yes (clearance 0.127))
    (min_thickness 0.125) (filled_areas_thickness no)
    (fill yes (thermal_gap 0.15) (thermal_bridge_width 0.15) (smoothing fillet) (radius 0.125))
    (polygon
      (pts
        (xy 116.45 91.6)
        (xy 116.7 91.6)
        (xy 116.7 93.7)
        (xy 115.55 93.7)
        (xy 115.55 91.6)
        (xy 115.55 86.25)
        (xy 116.45 86.25)
      )
    )
  )
  (zone (net 1) (net_name "GND") (layer "B.Cu") (hatch edge 0.508)
    (priority 2)
    (connect_pads yes (clearance 0.125))
    (min_thickness 0.125) (filled_areas_thickness no)
    (fill yes (thermal_gap 0.508) (thermal_bridge_width 0.508))
    (polygon
      (pts
        (xy 85.3 127.2)
        (xy 82.2 127.2)
        (xy 82.2 125.2)
        (xy 85.3 125.2)
      )
    )
  )
  (zone (net 74) (net_name "VDD") (layer "B.Cu") (hatch edge 0.508)
    (priority 1)
    (connect_pads yes (clearance 0.127))
    (min_thickness 0.125) (filled_areas_thickness no)
    (fill yes (thermal_gap 0.15) (thermal_bridge_width 0.15) (smoothing fillet) (radius 0.125))
    (polygon
      (pts
        (xy 75.95 116.25)
        (xy 76.75 117.05)
        (xy 77.8 117.05)
        (xy 77.8 118.85)
        (xy 76.75 118.85)
        (xy 74.6 116.7)
        (xy 74.6 114.25)
        (xy 75.95 114.25)
      )
    )
  )
  (zone (net 74) (net_name "VDD") (layer "B.Cu") (hatch edge 0.508)
    (connect_pads yes (clearance 0.127))
    (min_thickness 0.254) (filled_areas_thickness no)
    (fill yes (thermal_gap 0.508) (thermal_bridge_width 0.508))
    (polygon
      (pts
        (xy 82.4 98.6)
        (xy 83.4 98.6)
        (xy 83.4 99.4)
        (xy 81 99.4)
        (xy 81 97.8)
        (xy 81.6 97.8)
      )
    )
  )
  (zone (net 1) (net_name "GND") (layer "B.Cu") (hatch edge 0.508)
    (connect_pads yes (clearance 0.127))
    (min_thickness 0.127) (filled_areas_thickness no)
    (fill yes (thermal_gap 0.508) (thermal_bridge_width 0.508))
    (polygon
      (pts
        (xy 76.7 142.3)
        (xy 76.7 143.8)
        (xy 76.2 144.3)
        (xy 76.2 147.2)
        (xy 74.8 147.2)
        (xy 74.8 141.75)
        (xy 76.7 141.75)
      )
    )
  )
)
